G04 ================== begin FILE IDENTIFICATION RECORD ==================*
G04 Layout Name:  13948-1b.brd*
G04 Film Name:    L1*
G04 File Format:  Gerber RS274X*
G04 File Origin:  Cadence Allegro 16.5-S045*
G04 Origin Date:  Thu Nov 13 15:46:06 2014*
G04 *
G04 Layer:  VIA CLASS/TOP*
G04 Layer:  PIN/TOP*
G04 Layer:  ETCH/TOP*
G04 Layer:  DRAWING FORMAT/LAYER_PCB_STORY*
G04 Layer:  DRAWING FORMAT/LAYER_L1*
G04 *
G04 Offset:    (0.00 0.00)*
G04 Mirror:    No*
G04 Mode:      Positive*
G04 Rotation:  0*
G04 FullContactRelief:  No*
G04 UndefLineWidth:     6.00*
G04 ================== end FILE IDENTIFICATION RECORD ====================*
%FSLAX35Y35*MOIN*%
%IR0*IPPOS*OFA0.00000B0.00000*MIA0B0*SFA1.00000B1.00000*%
%AMMACRO61*
4,1,40,.013,.017,
-.013,.017,
-.013695,.016939,
-.014368,.016759,
-.015,.016464,
-.015571,.016064,
-.016064,.015571,
-.016464,.015,
-.016759,.014368,
-.016939,.013695,
-.017,.013,
-.017,-.013,
-.016939,-.013695,
-.016759,-.014368,
-.016464,-.015,
-.016064,-.015571,
-.015571,-.016064,
-.015,-.016464,
-.014368,-.016759,
-.013695,-.016939,
-.013,-.017,
.013,-.017,
.013695,-.016939,
.014368,-.016759,
.015,-.016464,
.015571,-.016064,
.016064,-.015571,
.016464,-.015,
.016759,-.014368,
.016939,-.013695,
.017,-.013,
.017,.013,
.016939,.013695,
.016759,.014368,
.016464,.015,
.016064,.015571,
.015571,.016064,
.015,.016464,
.014368,.016759,
.013695,.016939,
.013,.017,
0.0*
%
%ADD61MACRO61*%
%AMMACRO45*
4,1,40,.017,-.013,
.017,.013,
.016939,.013695,
.016759,.014368,
.016464,.015,
.016064,.015571,
.015571,.016064,
.015,.016464,
.014368,.016759,
.013695,.016939,
.013,.017,
-.013,.017,
-.013695,.016939,
-.014368,.016759,
-.015,.016464,
-.015571,.016064,
-.016064,.015571,
-.016464,.015,
-.016759,.014368,
-.016939,.013695,
-.017,.013,
-.017,-.013,
-.016939,-.013695,
-.016759,-.014368,
-.016464,-.015,
-.016064,-.015571,
-.015571,-.016064,
-.015,-.016464,
-.014368,-.016759,
-.013695,-.016939,
-.013,-.017,
.013,-.017,
.013695,-.016939,
.014368,-.016759,
.015,-.016464,
.015571,-.016064,
.016064,-.015571,
.016464,-.015,
.016759,-.014368,
.016939,-.013695,
.017,-.013,
0.0*
%
%ADD45MACRO45*%
%ADD129R,.045X.11*%
%ADD96R,.055X.11*%
%ADD84R,.11X.055*%
%ADD137R,.007X.01*%
%ADD12C,.01*%
%ADD24C,.02*%
%ADD88R,.147X.014*%
%ADD14C,.04*%
%ADD13C,.022*%
%ADD158R,.104X.085*%
%ADD98C,.014*%
%AMMACRO91*
4,1,40,-.007,.004,
-.007,-.004,
-.00697,-.004347,
-.006879,-.004684,
-.006732,-.005,
-.006532,-.005286,
-.006286,-.005532,
-.006,-.005732,
-.005684,-.005879,
-.005347,-.00597,
-.005,-.006,
.005,-.006,
.005347,-.00597,
.005684,-.005879,
.006,-.005732,
.006286,-.005532,
.006532,-.005286,
.006732,-.005,
.006879,-.004684,
.00697,-.004347,
.007,-.004,
.007,.004,
.00697,.004347,
.006879,.004684,
.006732,.005,
.006532,.005286,
.006286,.005532,
.006,.005732,
.005684,.005879,
.005347,.00597,
.005,.006,
-.005,.006,
-.005347,.00597,
-.005684,.005879,
-.006,.005732,
-.006286,.005532,
-.006532,.005286,
-.006732,.005,
-.006879,.004684,
-.00697,.004347,
-.007,.004,
0.0*
%
%ADD91MACRO91*%
%ADD43C,.05*%
%ADD38C,.032*%
%ADD148R,.138X.07*%
%AMMACRO95*
4,1,40,.004,.007,
-.004,.007,
-.004347,.00697,
-.004684,.006879,
-.005,.006732,
-.005286,.006532,
-.005532,.006286,
-.005732,.006,
-.005879,.005684,
-.00597,.005347,
-.006,.005,
-.006,-.005,
-.00597,-.005347,
-.005879,-.005684,
-.005732,-.006,
-.005532,-.006286,
-.005286,-.006532,
-.005,-.006732,
-.004684,-.006879,
-.004347,-.00697,
-.004,-.007,
.004,-.007,
.004347,-.00697,
.004684,-.006879,
.005,-.006732,
.005286,-.006532,
.005532,-.006286,
.005732,-.006,
.005879,-.005684,
.00597,-.005347,
.006,-.005,
.006,.005,
.00597,.005347,
.005879,.005684,
.005732,.006,
.005532,.006286,
.005286,.006532,
.005,.006732,
.004684,.006879,
.004347,.00697,
.004,.007,
0.0*
%
%ADD95MACRO95*%
%ADD41R,.028X.126*%
%ADD33R,.008X.06*%
%ADD108C,.052*%
%ADD105C,.043*%
%ADD97C,.016*%
%ADD58C,.061*%
%ADD147R,.135X.085*%
%ADD146C,.054*%
%ADD101C,.018*%
%ADD100C,.045*%
%ADD42R,.028X.165*%
%ADD49C,.046*%
%ADD10C,.028*%
%ADD59C,.056*%
%ADD106C,.066*%
%ADD159C,.058*%
%ADD114R,.098X.135*%
%AMMACRO127*
4,1,46,.018,-.00177,
.017918,-.003163,
.017595,-.00452,
.017042,-.0058,
.016274,-.006965,
.015316,-.007979,
.014196,-.008812,
.012949,-.009437,
.011613,-.009836,
.010227,-.009997,
.01,-.01,
-.01,-.01,
-.01,-.00999,
-.011389,-.009868,
-.012737,-.009507,
-.014001,-.008918,
-.015143,-.008118,
-.016129,-.007132,
-.016929,-.005989,
-.017519,-.004725,
-.01788,-.003378,
-.018001,-.001989,
-.018,-.00185,
-.018,.00185,
-.017903,.003241,
-.017565,.004595,
-.016998,.005869,
-.016218,.007025,
-.015249,.008028,
-.01412,.008848,
-.012867,.009459,
-.011526,.009843,
-.010139,.009989,
-.01,.00999,
-.01,.01,
.01,.01,
.01139,.009878,
.012737,.009517,
.014002,.008928,
.015144,.008128,
.016131,.007141,
.016931,.005998,
.017521,.004734,
.017882,.003387,
.018003,.001997,
.018,.00177,
.018,-.00177,
0.0*
%
%ADD127MACRO127*%
%AMMACRO130*
4,1,40,.0225,-.007,
.022378,-.008389,
.022018,-.009736,
.021428,-.011,
.020628,-.012142,
.019642,-.013128,
.0185,-.013928,
.017236,-.014518,
.015889,-.014878,
.0145,-.015,
-.0145,-.015,
-.015889,-.014878,
-.017236,-.014518,
-.0185,-.013928,
-.019642,-.013128,
-.020628,-.012142,
-.021428,-.011,
-.022018,-.009736,
-.022378,-.008389,
-.0225,-.007,
-.0225,.007,
-.022378,.008389,
-.022018,.009736,
-.021428,.011,
-.020628,.012142,
-.019642,.013128,
-.0185,.013928,
-.017236,.014518,
-.015889,.014878,
-.0145,.015,
.0145,.015,
.015889,.014878,
.017236,.014518,
.0185,.013928,
.019642,.013128,
.020628,.012142,
.021428,.011,
.022018,.009736,
.022378,.008389,
.0225,.007,
.0225,-.007,
0.0*
%
%ADD130MACRO130*%
%ADD107C,.078*%
%ADD99R,.045X.045*%
%AMMACRO48*
4,1,40,-.007,-.0225,
-.008389,-.022378,
-.009736,-.022018,
-.011,-.021428,
-.012142,-.020628,
-.013128,-.019642,
-.013928,-.0185,
-.014518,-.017236,
-.014878,-.015889,
-.015,-.0145,
-.015,.0145,
-.014878,.015889,
-.014518,.017236,
-.013928,.0185,
-.013128,.019642,
-.012142,.020628,
-.011,.021428,
-.009736,.022018,
-.008389,.022378,
-.007,.0225,
.007,.0225,
.008389,.022378,
.009736,.022018,
.011,.021428,
.012142,.020628,
.013128,.019642,
.013928,.0185,
.014518,.017236,
.014878,.015889,
.015,.0145,
.015,-.0145,
.014878,-.015889,
.014518,-.017236,
.013928,-.0185,
.013128,-.019642,
.012142,-.020628,
.011,-.021428,
.009736,-.022018,
.008389,-.022378,
.007,-.0225,
-.007,-.0225,
0.0*
%
%ADD48MACRO48*%
%AMMACRO20*
4,1,40,.011,-.007,
.011,.007,
.010939,.007695,
.010759,.008368,
.010464,.009,
.010064,.009571,
.009571,.010064,
.009,.010464,
.008368,.010759,
.007695,.010939,
.007,.011,
-.007,.011,
-.007695,.010939,
-.008368,.010759,
-.009,.010464,
-.009571,.010064,
-.010064,.009571,
-.010464,.009,
-.010759,.008368,
-.010939,.007695,
-.011,.007,
-.011,-.007,
-.010939,-.007695,
-.010759,-.008368,
-.010464,-.009,
-.010064,-.009571,
-.009571,-.010064,
-.009,-.010464,
-.008368,-.010759,
-.007695,-.010939,
-.007,-.011,
.007,-.011,
.007695,-.010939,
.008368,-.010759,
.009,-.010464,
.009571,-.010064,
.010064,-.009571,
.010464,-.009,
.010759,-.008368,
.010939,-.007695,
.011,-.007,
0.0*
%
%ADD20MACRO20*%
%AMMACRO18*
4,1,40,.007,.011,
-.007,.011,
-.007695,.010939,
-.008368,.010759,
-.009,.010464,
-.009571,.010064,
-.010064,.009571,
-.010464,.009,
-.010759,.008368,
-.010939,.007695,
-.011,.007,
-.011,-.007,
-.010939,-.007695,
-.010759,-.008368,
-.010464,-.009,
-.010064,-.009571,
-.009571,-.010064,
-.009,-.010464,
-.008368,-.010759,
-.007695,-.010939,
-.007,-.011,
.007,-.011,
.007695,-.010939,
.008368,-.010759,
.009,-.010464,
.009571,-.010064,
.010064,-.009571,
.010464,-.009,
.010759,-.008368,
.010939,-.007695,
.011,-.007,
.011,.007,
.010939,.007695,
.010759,.008368,
.010464,.009,
.010064,.009571,
.009571,.010064,
.009,.010464,
.008368,.010759,
.007695,.010939,
.007,.011,
0.0*
%
%ADD18MACRO18*%
%AMMACRO165*
4,1,22,.007,.0145,
.007695,.014439,
.008368,.014259,
.009,.013964,
.009571,.013564,
.010064,.013071,
.010464,.0125,
.010759,.011868,
.010939,.011195,
.011,.0105,
.011,-.0145,
-.011,-.0145,
-.011,.0105,
-.010939,.011195,
-.010759,.011868,
-.010464,.0125,
-.010064,.013071,
-.009571,.013564,
-.009,.013964,
-.008368,.014259,
-.007695,.014439,
-.007,.0145,
.007,.0145,
0.0*
%
%ADD165MACRO165*%
%ADD132R,.066X.066*%
%AMMACRO80*
4,1,40,-.023,.005,
-.023,-.005,
-.022878,-.006389,
-.022518,-.007736,
-.021928,-.009,
-.021128,-.010142,
-.020142,-.011128,
-.019,-.011928,
-.017736,-.012518,
-.016389,-.012878,
-.015,-.013,
.015,-.013,
.016389,-.012878,
.017736,-.012518,
.019,-.011928,
.020142,-.011128,
.021128,-.010142,
.021928,-.009,
.022518,-.007736,
.022878,-.006389,
.023,-.005,
.023,.005,
.022878,.006389,
.022518,.007736,
.021928,.009,
.021128,.010142,
.020142,.011128,
.019,.011928,
.017736,.012518,
.016389,.012878,
.015,.013,
-.015,.013,
-.016389,.012878,
-.017736,.012518,
-.019,.011928,
-.020142,.011128,
-.021128,.010142,
-.021928,.009,
-.022518,.007736,
-.022878,.006389,
-.023,.005,
0.0*
%
%ADD80MACRO80*%
%AMMACRO149*
4,1,40,.005,.023,
-.005,.023,
-.006389,.022878,
-.007736,.022518,
-.009,.021928,
-.010142,.021128,
-.011128,.020142,
-.011928,.019,
-.012518,.017736,
-.012878,.016389,
-.013,.015,
-.013,-.015,
-.012878,-.016389,
-.012518,-.017736,
-.011928,-.019,
-.011128,-.020142,
-.010142,-.021128,
-.009,-.021928,
-.007736,-.022518,
-.006389,-.022878,
-.005,-.023,
.005,-.023,
.006389,-.022878,
.007736,-.022518,
.009,-.021928,
.010142,-.021128,
.011128,-.020142,
.011928,-.019,
.012518,-.017736,
.012878,-.016389,
.013,-.015,
.013,.015,
.012878,.016389,
.012518,.017736,
.011928,.019,
.011128,.020142,
.010142,.021128,
.009,.021928,
.007736,.022518,
.006389,.022878,
.005,.023,
0.0*
%
%ADD149MACRO149*%
%AMMACRO27*
4,1,40,-.012,.008,
-.012,-.008,
-.011939,-.008695,
-.011759,-.009368,
-.011464,-.01,
-.011064,-.010571,
-.010571,-.011064,
-.01,-.011464,
-.009368,-.011759,
-.008695,-.011939,
-.008,-.012,
.008,-.012,
.008695,-.011939,
.009368,-.011759,
.01,-.011464,
.010571,-.011064,
.011064,-.010571,
.011464,-.01,
.011759,-.009368,
.011939,-.008695,
.012,-.008,
.012,.008,
.011939,.008695,
.011759,.009368,
.011464,.01,
.011064,.010571,
.010571,.011064,
.01,.011464,
.009368,.011759,
.008695,.011939,
.008,.012,
-.008,.012,
-.008695,.011939,
-.009368,.011759,
-.01,.011464,
-.010571,.011064,
-.011064,.010571,
-.011464,.01,
-.011759,.009368,
-.011939,.008695,
-.012,.008,
0.0*
%
%ADD27MACRO27*%
%AMMACRO36*
4,1,40,.008,.012,
-.008,.012,
-.008695,.011939,
-.009368,.011759,
-.01,.011464,
-.010571,.011064,
-.011064,.010571,
-.011464,.01,
-.011759,.009368,
-.011939,.008695,
-.012,.008,
-.012,-.008,
-.011939,-.008695,
-.011759,-.009368,
-.011464,-.01,
-.011064,-.010571,
-.010571,-.011064,
-.01,-.011464,
-.009368,-.011759,
-.008695,-.011939,
-.008,-.012,
.008,-.012,
.008695,-.011939,
.009368,-.011759,
.01,-.011464,
.010571,-.011064,
.011064,-.010571,
.011464,-.01,
.011759,-.009368,
.011939,-.008695,
.012,-.008,
.012,.008,
.011939,.008695,
.011759,.009368,
.011464,.01,
.011064,.010571,
.010571,.011064,
.01,.011464,
.009368,.011759,
.008695,.011939,
.008,.012,
0.0*
%
%ADD36MACRO36*%
%AMMACRO83*
4,1,6,.0135,-.025,
-.0065,-.005,
-.0135,-.005,
-.0135,.005,
-.0065,.005,
.0135,.025,
.0135,-.025,
0.0*
%
%ADD83MACRO83*%
%AMMACRO57*
4,1,40,-.013,-.017,
.013,-.017,
.013695,-.016939,
.014368,-.016759,
.015,-.016464,
.015571,-.016064,
.016064,-.015571,
.016464,-.015,
.016759,-.014368,
.016939,-.013695,
.017,-.013,
.017,.013,
.016939,.013695,
.016759,.014368,
.016464,.015,
.016064,.015571,
.015571,.016064,
.015,.016464,
.014368,.016759,
.013695,.016939,
.013,.017,
-.013,.017,
-.013695,.016939,
-.014368,.016759,
-.015,.016464,
-.015571,.016064,
-.016064,.015571,
-.016464,.015,
-.016759,.014368,
-.016939,.013695,
-.017,.013,
-.017,-.013,
-.016939,-.013695,
-.016759,-.014368,
-.016464,-.015,
-.016064,-.015571,
-.015571,-.016064,
-.015,-.016464,
-.014368,-.016759,
-.013695,-.016939,
-.013,-.017,
0.0*
%
%ADD57MACRO57*%
%AMMACRO29*
4,1,40,-.017,.013,
-.017,-.013,
-.016939,-.013695,
-.016759,-.014368,
-.016464,-.015,
-.016064,-.015571,
-.015571,-.016064,
-.015,-.016464,
-.014368,-.016759,
-.013695,-.016939,
-.013,-.017,
.013,-.017,
.013695,-.016939,
.014368,-.016759,
.015,-.016464,
.015571,-.016064,
.016064,-.015571,
.016464,-.015,
.016759,-.014368,
.016939,-.013695,
.017,-.013,
.017,.013,
.016939,.013695,
.016759,.014368,
.016464,.015,
.016064,.015571,
.015571,.016064,
.015,.016464,
.014368,.016759,
.013695,.016939,
.013,.017,
-.013,.017,
-.013695,.016939,
-.014368,.016759,
-.015,.016464,
-.015571,.016064,
-.016064,.015571,
-.016464,.015,
-.016759,.014368,
-.016939,.013695,
-.017,.013,
0.0*
%
%ADD29MACRO29*%
%AMMACRO111*
4,1,6,-.0135,.005,
-.0065,.005,
.0135,.025,
.0135,-.025,
-.0065,-.005,
-.0135,-.005,
-.0135,.005,
0.0*
%
%ADD111MACRO111*%
%AMMACRO76*
4,1,40,.023,-.013,
.023,.013,
.022939,.013695,
.022759,.014368,
.022464,.015,
.022064,.015571,
.021571,.016064,
.021,.016464,
.020368,.016759,
.019695,.016939,
.019,.017,
-.019,.017,
-.019695,.016939,
-.020368,.016759,
-.021,.016464,
-.021571,.016064,
-.022064,.015571,
-.022464,.015,
-.022759,.014368,
-.022939,.013695,
-.023,.013,
-.023,-.013,
-.022939,-.013695,
-.022759,-.014368,
-.022464,-.015,
-.022064,-.015571,
-.021571,-.016064,
-.021,-.016464,
-.020368,-.016759,
-.019695,-.016939,
-.019,-.017,
.019,-.017,
.019695,-.016939,
.020368,-.016759,
.021,-.016464,
.021571,-.016064,
.022064,-.015571,
.022464,-.015,
.022759,-.014368,
.022939,-.013695,
.023,-.013,
0.0*
%
%ADD76MACRO76*%
%AMMACRO21*
4,1,40,.011,-.007,
.011,.007,
.010939,.007695,
.010759,.008368,
.010464,.009,
.010064,.009571,
.009571,.010064,
.009,.010464,
.008368,.010759,
.007695,.010939,
.007,.011,
-.007,.011,
-.007695,.010939,
-.008368,.010759,
-.009,.010464,
-.009571,.010064,
-.010064,.009571,
-.010464,.009,
-.010759,.008368,
-.010939,.007695,
-.011,.007,
-.011,-.007,
-.010939,-.007695,
-.010759,-.008368,
-.010464,-.009,
-.010064,-.009571,
-.009571,-.010064,
-.009,-.010464,
-.008368,-.010759,
-.007695,-.010939,
-.007,-.011,
.007,-.011,
.007695,-.010939,
.008368,-.010759,
.009,-.010464,
.009571,-.010064,
.010064,-.009571,
.010464,-.009,
.010759,-.008368,
.010939,-.007695,
.011,-.007,
0.0*
%
%ADD21MACRO21*%
%AMMACRO19*
4,1,40,.007,.011,
-.007,.011,
-.007695,.010939,
-.008368,.010759,
-.009,.010464,
-.009571,.010064,
-.010064,.009571,
-.010464,.009,
-.010759,.008368,
-.010939,.007695,
-.011,.007,
-.011,-.007,
-.010939,-.007695,
-.010759,-.008368,
-.010464,-.009,
-.010064,-.009571,
-.009571,-.010064,
-.009,-.010464,
-.008368,-.010759,
-.007695,-.010939,
-.007,-.011,
.007,-.011,
.007695,-.010939,
.008368,-.010759,
.009,-.010464,
.009571,-.010064,
.010064,-.009571,
.010464,-.009,
.010759,-.008368,
.010939,-.007695,
.011,-.007,
.011,.007,
.010939,.007695,
.010759,.008368,
.010464,.009,
.010064,.009571,
.009571,.010064,
.009,.010464,
.008368,.010759,
.007695,.010939,
.007,.011,
0.0*
%
%ADD19MACRO19*%
%AMMACRO166*
4,1,22,.011,.0145,
.011,-.0105,
.010939,-.011195,
.010759,-.011868,
.010464,-.0125,
.010064,-.013071,
.009571,-.013564,
.009,-.013964,
.008368,-.014259,
.007695,-.014439,
.007,-.0145,
-.007,-.0145,
-.007695,-.014439,
-.008368,-.014259,
-.009,-.013964,
-.009571,-.013564,
-.010064,-.013071,
-.010464,-.0125,
-.010759,-.011868,
-.010939,-.011195,
-.011,-.0105,
-.011,.0145,
.011,.0145,
0.0*
%
%ADD166MACRO166*%
%AMMACRO26*
4,1,40,-.012,.008,
-.012,-.008,
-.011939,-.008695,
-.011759,-.009368,
-.011464,-.01,
-.011064,-.010571,
-.010571,-.011064,
-.01,-.011464,
-.009368,-.011759,
-.008695,-.011939,
-.008,-.012,
.008,-.012,
.008695,-.011939,
.009368,-.011759,
.01,-.011464,
.010571,-.011064,
.011064,-.010571,
.011464,-.01,
.011759,-.009368,
.011939,-.008695,
.012,-.008,
.012,.008,
.011939,.008695,
.011759,.009368,
.011464,.01,
.011064,.010571,
.010571,.011064,
.01,.011464,
.009368,.011759,
.008695,.011939,
.008,.012,
-.008,.012,
-.008695,.011939,
-.009368,.011759,
-.01,.011464,
-.010571,.011064,
-.011064,.010571,
-.011464,.01,
-.011759,.009368,
-.011939,.008695,
-.012,.008,
0.0*
%
%ADD26MACRO26*%
%AMMACRO37*
4,1,40,.008,.012,
-.008,.012,
-.008695,.011939,
-.009368,.011759,
-.01,.011464,
-.010571,.011064,
-.011064,.010571,
-.011464,.01,
-.011759,.009368,
-.011939,.008695,
-.012,.008,
-.012,-.008,
-.011939,-.008695,
-.011759,-.009368,
-.011464,-.01,
-.011064,-.010571,
-.010571,-.011064,
-.01,-.011464,
-.009368,-.011759,
-.008695,-.011939,
-.008,-.012,
.008,-.012,
.008695,-.011939,
.009368,-.011759,
.01,-.011464,
.010571,-.011064,
.011064,-.010571,
.011464,-.01,
.011759,-.009368,
.011939,-.008695,
.012,-.008,
.012,.008,
.011939,.008695,
.011759,.009368,
.011464,.01,
.011064,.010571,
.010571,.011064,
.01,.011464,
.009368,.011759,
.008695,.011939,
.008,.012,
0.0*
%
%ADD37MACRO37*%
%AMMACRO53*
4,1,40,-.013,-.017,
.013,-.017,
.013695,-.016939,
.014368,-.016759,
.015,-.016464,
.015571,-.016064,
.016064,-.015571,
.016464,-.015,
.016759,-.014368,
.016939,-.013695,
.017,-.013,
.017,.013,
.016939,.013695,
.016759,.014368,
.016464,.015,
.016064,.015571,
.015571,.016064,
.015,.016464,
.014368,.016759,
.013695,.016939,
.013,.017,
-.013,.017,
-.013695,.016939,
-.014368,.016759,
-.015,.016464,
-.015571,.016064,
-.016064,.015571,
-.016464,.015,
-.016759,.014368,
-.016939,.013695,
-.017,.013,
-.017,-.013,
-.016939,-.013695,
-.016759,-.014368,
-.016464,-.015,
-.016064,-.015571,
-.015571,-.016064,
-.015,-.016464,
-.014368,-.016759,
-.013695,-.016939,
-.013,-.017,
0.0*
%
%ADD53MACRO53*%
%AMMACRO30*
4,1,40,-.017,.013,
-.017,-.013,
-.016939,-.013695,
-.016759,-.014368,
-.016464,-.015,
-.016064,-.015571,
-.015571,-.016064,
-.015,-.016464,
-.014368,-.016759,
-.013695,-.016939,
-.013,-.017,
.013,-.017,
.013695,-.016939,
.014368,-.016759,
.015,-.016464,
.015571,-.016064,
.016064,-.015571,
.016464,-.015,
.016759,-.014368,
.016939,-.013695,
.017,-.013,
.017,.013,
.016939,.013695,
.016759,.014368,
.016464,.015,
.016064,.015571,
.015571,.016064,
.015,.016464,
.014368,.016759,
.013695,.016939,
.013,.017,
-.013,.017,
-.013695,.016939,
-.014368,.016759,
-.015,.016464,
-.015571,.016064,
-.016064,.015571,
-.016464,.015,
-.016759,.014368,
-.016939,.013695,
-.017,.013,
0.0*
%
%ADD30MACRO30*%
%AMMACRO77*
4,1,40,-.019,-.017,
.019,-.017,
.019695,-.016939,
.020368,-.016759,
.021,-.016464,
.021571,-.016064,
.022064,-.015571,
.022464,-.015,
.022759,-.014368,
.022939,-.013695,
.023,-.013,
.023,.013,
.022939,.013695,
.022759,.014368,
.022464,.015,
.022064,.015571,
.021571,.016064,
.021,.016464,
.020368,.016759,
.019695,.016939,
.019,.017,
-.019,.017,
-.019695,.016939,
-.020368,.016759,
-.021,.016464,
-.021571,.016064,
-.022064,.015571,
-.022464,.015,
-.022759,.014368,
-.022939,.013695,
-.023,.013,
-.023,-.013,
-.022939,-.013695,
-.022759,-.014368,
-.022464,-.015,
-.022064,-.015571,
-.021571,-.016064,
-.021,-.016464,
-.020368,-.016759,
-.019695,-.016939,
-.019,-.017,
0.0*
%
%ADD77MACRO77*%
%ADD72R,.01X.014*%
%ADD172R,.012X.05*%
%ADD168R,.05X.012*%
%ADD125R,.04X.014*%
%ADD78R,.022X.04*%
%ADD68R,.012X.042*%
%ADD66R,.042X.012*%
%ADD40R,.06X.012*%
%ADD171R,.012X.043*%
%ADD167R,.043X.012*%
%ADD104R,.012X.06*%
%ADD55R,.016X.02*%
%ADD54R,.023X.04*%
%ADD153R,.081X.02*%
%ADD144R,.042X.014*%
%ADD143R,.014X.042*%
%ADD110R,.04X.016*%
%ADD90R,.014X.033*%
%ADD89R,.033X.014*%
%ADD73R,.016X.012*%
%ADD46R,.06X.014*%
%ADD22O,.014X.071*%
%ADD140R,.014X.042*%
%ADD138R,.042X.014*%
%ADD135R,.016X.04*%
%ADD116R,.012X.044*%
%ADD70R,.045X.03*%
%ADD65R,.036X.012*%
%ADD64R,.012X.036*%
%ADD28R,.014X.06*%
%ADD126R,.016X.032*%
%ADD123R,.012X.036*%
%ADD120R,.06X.016*%
%ADD118R,.036X.012*%
%ADD39R,.03X.045*%
%ADD174R,.028X.03*%
%ADD155R,.016X.06*%
%ADD134R,.012X.037*%
%ADD133R,.037X.012*%
%ADD122R,.012X.046*%
%ADD119R,.046X.012*%
%AMMACRO93*
4,1,40,-.004,-.007,
.004,-.007,
.004347,-.00697,
.004684,-.006879,
.005,-.006732,
.005286,-.006532,
.005532,-.006286,
.005732,-.006,
.005879,-.005684,
.00597,-.005347,
.006,-.005,
.006,.005,
.00597,.005347,
.005879,.005684,
.005732,.006,
.005532,.006286,
.005286,.006532,
.005,.006732,
.004684,.006879,
.004347,.00697,
.004,.007,
-.004,.007,
-.004347,.00697,
-.004684,.006879,
-.005,.006732,
-.005286,.006532,
-.005532,.006286,
-.005732,.006,
-.005879,.005684,
-.00597,.005347,
-.006,.005,
-.006,-.005,
-.00597,-.005347,
-.005879,-.005684,
-.005732,-.006,
-.005532,-.006286,
-.005286,-.006532,
-.005,-.006732,
-.004684,-.006879,
-.004347,-.00697,
-.004,-.007,
0.0*
%
%ADD93MACRO93*%
%AMMACRO85*
4,1,40,.007,-.004,
.007,.004,
.00697,.004347,
.006879,.004684,
.006732,.005,
.006532,.005286,
.006286,.005532,
.006,.005732,
.005684,.005879,
.005347,.00597,
.005,.006,
-.005,.006,
-.005347,.00597,
-.005684,.005879,
-.006,.005732,
-.006286,.005532,
-.006532,.005286,
-.006732,.005,
-.006879,.004684,
-.00697,.004347,
-.007,.004,
-.007,-.004,
-.00697,-.004347,
-.006879,-.004684,
-.006732,-.005,
-.006532,-.005286,
-.006286,-.005532,
-.006,-.005732,
-.005684,-.005879,
-.005347,-.00597,
-.005,-.006,
.005,-.006,
.005347,-.00597,
.005684,-.005879,
.006,-.005732,
.006286,-.005532,
.006532,-.005286,
.006732,-.005,
.006879,-.004684,
.00697,-.004347,
.007,-.004,
0.0*
%
%ADD85MACRO85*%
%ADD74R,.03X.064*%
%ADD169R,.02X.066*%
%ADD157R,.012X.038*%
%ADD156R,.038X.012*%
%ADD131R,.138X.115*%
%ADD170R,.042X.055*%
%ADD164R,.042X.037*%
%ADD92R,.128X.108*%
%ADD47R,.05X.065*%
%ADD163R,.138X.117*%
%ADD150R,.026X.036*%
%ADD145C,.107*%
%ADD94R,.053X.063*%
%ADD86R,.065X.05*%
%ADD128R,.065X.025*%
%ADD103R,.063X.053*%
%ADD71R,.045X.09*%
%ADD136R,.025X.065*%
%ADD63R,.045X.055*%
%ADD23R,.035X.083*%
%ADD15R,.048X.016*%
%ADD151R,.055X.036*%
%ADD121R,.016X.048*%
%ADD117R,.074X.054*%
%ADD87R,.096X.014*%
%ADD79R,.095X.06*%
%ADD75R,.197X.205*%
%ADD62R,.055X.045*%
%ADD81R,.054X.074*%
%ADD56R,.067X.043*%
%ADD142R,.075X.045*%
%ADD113R,.09X.095*%
%ADD11C,.158*%
%ADD173R,.152X.152*%
%ADD154R,.079X.071*%
%ADD152R,.065X.075*%
%ADD109R,.095X.09*%
%ADD67R,.045X.059*%
%AMMACRO52*
4,1,40,.007,.0225,
.008389,.022378,
.009736,.022018,
.011,.021428,
.012142,.020628,
.013128,.019642,
.013928,.0185,
.014518,.017236,
.014878,.015889,
.015,.0145,
.015,-.0145,
.014878,-.015889,
.014518,-.017236,
.013928,-.0185,
.013128,-.019642,
.012142,-.020628,
.011,-.021428,
.009736,-.022018,
.008389,-.022378,
.007,-.0225,
-.007,-.0225,
-.008389,-.022378,
-.009736,-.022018,
-.011,-.021428,
-.012142,-.020628,
-.013128,-.019642,
-.013928,-.0185,
-.014518,-.017236,
-.014878,-.015889,
-.015,-.0145,
-.015,.0145,
-.014878,.015889,
-.014518,.017236,
-.013928,.0185,
-.013128,.019642,
-.012142,.020628,
-.011,.021428,
-.009736,.022018,
-.008389,.022378,
-.007,.0225,
.007,.0225,
0.0*
%
%ADD52MACRO52*%
%AMMACRO25*
4,1,40,-.0225,.007,
-.022378,.008389,
-.022018,.009736,
-.021428,.011,
-.020628,.012142,
-.019642,.013128,
-.0185,.013928,
-.017236,.014518,
-.015889,.014878,
-.0145,.015,
.0145,.015,
.015889,.014878,
.017236,.014518,
.0185,.013928,
.019642,.013128,
.020628,.012142,
.021428,.011,
.022018,.009736,
.022378,.008389,
.0225,.007,
.0225,-.007,
.022378,-.008389,
.022018,-.009736,
.021428,-.011,
.020628,-.012142,
.019642,-.013128,
.0185,-.013928,
.017236,-.014518,
.015889,-.014878,
.0145,-.015,
-.0145,-.015,
-.015889,-.014878,
-.017236,-.014518,
-.0185,-.013928,
-.019642,-.013128,
-.020628,-.012142,
-.021428,-.011,
-.022018,-.009736,
-.022378,-.008389,
-.0225,-.007,
-.0225,.007,
0.0*
%
%ADD25MACRO25*%
%ADD175R,.057X.039*%
%ADD162R,.055X.069*%
%ADD141R,.035X.098*%
%ADD69R,.136X.136*%
%ADD139R,.128X.128*%
%ADD161R,.049X.069*%
%AMMACRO102*
4,1,40,.024,.012,
.024,-.012,
.023878,-.013389,
.023518,-.014736,
.022928,-.016,
.022128,-.017142,
.021142,-.018128,
.02,-.018928,
.018736,-.019518,
.017389,-.019878,
.016,-.02,
-.016,-.02,
-.017389,-.019878,
-.018736,-.019518,
-.02,-.018928,
-.021142,-.018128,
-.022128,-.017142,
-.022928,-.016,
-.023518,-.014736,
-.023878,-.013389,
-.024,-.012,
-.024,.012,
-.023878,.013389,
-.023518,.014736,
-.022928,.016,
-.022128,.017142,
-.021142,.018128,
-.02,.018928,
-.018736,.019518,
-.017389,.019878,
-.016,.02,
.016,.02,
.017389,.019878,
.018736,.019518,
.02,.018928,
.021142,.018128,
.022128,.017142,
.022928,.016,
.023518,.014736,
.023878,.013389,
.024,.012,
0.0*
%
%ADD102MACRO102*%
%ADD160R,.047X.098*%
%AMMACRO51*
4,1,40,.012,-.008,
.012,.008,
.011939,.008695,
.011759,.009368,
.011464,.01,
.011064,.010571,
.010571,.011064,
.01,.011464,
.009368,.011759,
.008695,.011939,
.008,.012,
-.008,.012,
-.008695,.011939,
-.009368,.011759,
-.01,.011464,
-.010571,.011064,
-.011064,.010571,
-.011464,.01,
-.011759,.009368,
-.011939,.008695,
-.012,.008,
-.012,-.008,
-.011939,-.008695,
-.011759,-.009368,
-.011464,-.01,
-.011064,-.010571,
-.010571,-.011064,
-.01,-.011464,
-.009368,-.011759,
-.008695,-.011939,
-.008,-.012,
.008,-.012,
.008695,-.011939,
.009368,-.011759,
.01,-.011464,
.010571,-.011064,
.011064,-.010571,
.011464,-.01,
.011759,-.009368,
.011939,-.008695,
.012,-.008,
0.0*
%
%ADD51MACRO51*%
%AMMACRO32*
4,1,40,-.008,-.012,
.008,-.012,
.008695,-.011939,
.009368,-.011759,
.01,-.011464,
.010571,-.011064,
.011064,-.010571,
.011464,-.01,
.011759,-.009368,
.011939,-.008695,
.012,-.008,
.012,.008,
.011939,.008695,
.011759,.009368,
.011464,.01,
.011064,.010571,
.010571,.011064,
.01,.011464,
.009368,.011759,
.008695,.011939,
.008,.012,
-.008,.012,
-.008695,.011939,
-.009368,.011759,
-.01,.011464,
-.010571,.011064,
-.011064,.010571,
-.011464,.01,
-.011759,.009368,
-.011939,.008695,
-.012,.008,
-.012,-.008,
-.011939,-.008695,
-.011759,-.009368,
-.011464,-.01,
-.011064,-.010571,
-.010571,-.011064,
-.01,-.011464,
-.009368,-.011759,
-.008695,-.011939,
-.008,-.012,
0.0*
%
%ADD32MACRO32*%
%AMMACRO16*
4,1,40,-.007,-.011,
.007,-.011,
.007695,-.010939,
.008368,-.010759,
.009,-.010464,
.009571,-.010064,
.010064,-.009571,
.010464,-.009,
.010759,-.008368,
.010939,-.007695,
.011,-.007,
.011,.007,
.010939,.007695,
.010759,.008368,
.010464,.009,
.010064,.009571,
.009571,.010064,
.009,.010464,
.008368,.010759,
.007695,.010939,
.007,.011,
-.007,.011,
-.007695,.010939,
-.008368,.010759,
-.009,.010464,
-.009571,.010064,
-.010064,.009571,
-.010464,.009,
-.010759,.008368,
-.010939,.007695,
-.011,.007,
-.011,-.007,
-.010939,-.007695,
-.010759,-.008368,
-.010464,-.009,
-.010064,-.009571,
-.009571,-.010064,
-.009,-.010464,
-.008368,-.010759,
-.007695,-.010939,
-.007,-.011,
0.0*
%
%ADD16MACRO16*%
%AMMACRO34*
4,1,40,-.011,.007,
-.011,-.007,
-.010939,-.007695,
-.010759,-.008368,
-.010464,-.009,
-.010064,-.009571,
-.009571,-.010064,
-.009,-.010464,
-.008368,-.010759,
-.007695,-.010939,
-.007,-.011,
.007,-.011,
.007695,-.010939,
.008368,-.010759,
.009,-.010464,
.009571,-.010064,
.010064,-.009571,
.010464,-.009,
.010759,-.008368,
.010939,-.007695,
.011,-.007,
.011,.007,
.010939,.007695,
.010759,.008368,
.010464,.009,
.010064,.009571,
.009571,.010064,
.009,.010464,
.008368,.010759,
.007695,.010939,
.007,.011,
-.007,.011,
-.007695,.010939,
-.008368,.010759,
-.009,.010464,
-.009571,.010064,
-.010064,.009571,
-.010464,.009,
-.010759,.008368,
-.010939,.007695,
-.011,.007,
0.0*
%
%ADD34MACRO34*%
%ADD124R,.189X.189*%
%AMMACRO112*
4,1,6,-.0135,.025,
.0065,.005,
.0135,.005,
.0135,-.005,
.0065,-.005,
-.0135,-.025,
-.0135,.025,
0.0*
%
%ADD112MACRO112*%
%AMMACRO60*
4,1,40,.013,.017,
-.013,.017,
-.013695,.016939,
-.014368,.016759,
-.015,.016464,
-.015571,.016064,
-.016064,.015571,
-.016464,.015,
-.016759,.014368,
-.016939,.013695,
-.017,.013,
-.017,-.013,
-.016939,-.013695,
-.016759,-.014368,
-.016464,-.015,
-.016064,-.015571,
-.015571,-.016064,
-.015,-.016464,
-.014368,-.016759,
-.013695,-.016939,
-.013,-.017,
.013,-.017,
.013695,-.016939,
.014368,-.016759,
.015,-.016464,
.015571,-.016064,
.016064,-.015571,
.016464,-.015,
.016759,-.014368,
.016939,-.013695,
.017,-.013,
.017,.013,
.016939,.013695,
.016759,.014368,
.016464,.015,
.016064,.015571,
.015571,.016064,
.015,.016464,
.014368,.016759,
.013695,.016939,
.013,.017,
0.0*
%
%ADD60MACRO60*%
%AMMACRO44*
4,1,40,.017,-.013,
.017,.013,
.016939,.013695,
.016759,.014368,
.016464,.015,
.016064,.015571,
.015571,.016064,
.015,.016464,
.014368,.016759,
.013695,.016939,
.013,.017,
-.013,.017,
-.013695,.016939,
-.014368,.016759,
-.015,.016464,
-.015571,.016064,
-.016064,.015571,
-.016464,.015,
-.016759,.014368,
-.016939,.013695,
-.017,.013,
-.017,-.013,
-.016939,-.013695,
-.016759,-.014368,
-.016464,-.015,
-.016064,-.015571,
-.015571,-.016064,
-.015,-.016464,
-.014368,-.016759,
-.013695,-.016939,
-.013,-.017,
.013,-.017,
.013695,-.016939,
.014368,-.016759,
.015,-.016464,
.015571,-.016064,
.016064,-.015571,
.016464,-.015,
.016759,-.014368,
.016939,-.013695,
.017,-.013,
0.0*
%
%ADD44MACRO44*%
%AMMACRO115*
4,1,20,.1095,.0655,
.1095,.051,
.12,.051,
.12,.0375,
.1095,.0375,
.1095,-.0375,
.12,-.0375,
.12,-.051,
.1095,-.051,
.1095,-.0655,
-.1095,-.0655,
-.1095,-.051,
-.12,-.051,
-.12,-.0375,
-.1095,-.0375,
-.1095,.0375,
-.12,.0375,
-.12,.051,
-.1095,.051,
-.1095,.0655,
.1095,.0655,
0.0*
%
%ADD115MACRO115*%
%AMMACRO82*
4,1,6,.0135,-.005,
.0065,-.005,
-.0135,-.025,
-.0135,.025,
.0065,.005,
.0135,.005,
.0135,-.005,
0.0*
%
%ADD82MACRO82*%
%AMMACRO50*
4,1,40,.012,-.008,
.012,.008,
.011939,.008695,
.011759,.009368,
.011464,.01,
.011064,.010571,
.010571,.011064,
.01,.011464,
.009368,.011759,
.008695,.011939,
.008,.012,
-.008,.012,
-.008695,.011939,
-.009368,.011759,
-.01,.011464,
-.010571,.011064,
-.011064,.010571,
-.011464,.01,
-.011759,.009368,
-.011939,.008695,
-.012,.008,
-.012,-.008,
-.011939,-.008695,
-.011759,-.009368,
-.011464,-.01,
-.011064,-.010571,
-.010571,-.011064,
-.01,-.011464,
-.009368,-.011759,
-.008695,-.011939,
-.008,-.012,
.008,-.012,
.008695,-.011939,
.009368,-.011759,
.01,-.011464,
.010571,-.011064,
.011064,-.010571,
.011464,-.01,
.011759,-.009368,
.011939,-.008695,
.012,-.008,
0.0*
%
%ADD50MACRO50*%
%AMMACRO31*
4,1,40,-.008,-.012,
.008,-.012,
.008695,-.011939,
.009368,-.011759,
.01,-.011464,
.010571,-.011064,
.011064,-.010571,
.011464,-.01,
.011759,-.009368,
.011939,-.008695,
.012,-.008,
.012,.008,
.011939,.008695,
.011759,.009368,
.011464,.01,
.011064,.010571,
.010571,.011064,
.01,.011464,
.009368,.011759,
.008695,.011939,
.008,.012,
-.008,.012,
-.008695,.011939,
-.009368,.011759,
-.01,.011464,
-.010571,.011064,
-.011064,.010571,
-.011464,.01,
-.011759,.009368,
-.011939,.008695,
-.012,.008,
-.012,-.008,
-.011939,-.008695,
-.011759,-.009368,
-.011464,-.01,
-.011064,-.010571,
-.010571,-.011064,
-.01,-.011464,
-.009368,-.011759,
-.008695,-.011939,
-.008,-.012,
0.0*
%
%ADD31MACRO31*%
%AMMACRO17*
4,1,40,-.007,-.011,
.007,-.011,
.007695,-.010939,
.008368,-.010759,
.009,-.010464,
.009571,-.010064,
.010064,-.009571,
.010464,-.009,
.010759,-.008368,
.010939,-.007695,
.011,-.007,
.011,.007,
.010939,.007695,
.010759,.008368,
.010464,.009,
.010064,.009571,
.009571,.010064,
.009,.010464,
.008368,.010759,
.007695,.010939,
.007,.011,
-.007,.011,
-.007695,.010939,
-.008368,.010759,
-.009,.010464,
-.009571,.010064,
-.010064,.009571,
-.010464,.009,
-.010759,.008368,
-.010939,.007695,
-.011,.007,
-.011,-.007,
-.010939,-.007695,
-.010759,-.008368,
-.010464,-.009,
-.010064,-.009571,
-.009571,-.010064,
-.009,-.010464,
-.008368,-.010759,
-.007695,-.010939,
-.007,-.011,
0.0*
%
%ADD17MACRO17*%
%AMMACRO35*
4,1,40,-.011,.007,
-.011,-.007,
-.010939,-.007695,
-.010759,-.008368,
-.010464,-.009,
-.010064,-.009571,
-.009571,-.010064,
-.009,-.010464,
-.008368,-.010759,
-.007695,-.010939,
-.007,-.011,
.007,-.011,
.007695,-.010939,
.008368,-.010759,
.009,-.010464,
.009571,-.010064,
.010064,-.009571,
.010464,-.009,
.010759,-.008368,
.010939,-.007695,
.011,-.007,
.011,.007,
.010939,.007695,
.010759,.008368,
.010464,.009,
.010064,.009571,
.009571,.010064,
.009,.010464,
.008368,.010759,
.007695,.010939,
.007,.011,
-.007,.011,
-.007695,.010939,
-.008368,.010759,
-.009,.010464,
-.009571,.010064,
-.010064,.009571,
-.010464,.009,
-.010759,.008368,
-.010939,.007695,
-.011,.007,
0.0*
%
%ADD35MACRO35*%
%ADD176C,.012*%
%ADD177C,.024*%
%ADD178C,.015*%
%ADD179C,.025*%
%ADD180C,.004*%
%ADD181C,.005*%
%ADD182C,.006*%
%ADD183C,.007*%
%ADD184C,.0035*%
%ADD185C,.008*%
%ADD186C,.0045*%
%ADD187C,.0055*%
%ADD196C,.02404*%
%ADD201C,.05204*%
%ADD202C,.04404*%
%ADD197C,.02604*%
%ADD199R,.08272X.1024*%
%ADD191C,.04604*%
%ADD188C,.09204*%
%ADD203C,.06704*%
%ADD190C,.08504*%
%ADD189R,.01X.01*%
%ADD198R,.01X.021*%
%ADD192R,.021X.01*%
%ADD195R,.01X.024*%
%ADD194R,.024X.01*%
%ADD193R,.035X.01*%
%ADD200C,.10204*%
%ADD204C,.13104*%
G75*
%LPD*%
G75*
G36*
G01X20065Y346862D02*
G03X16004Y329300I-792J-9067D01*
G02X16144Y328644I-143J-373D01*
G01X15000Y327500D01*
Y313000D01*
X14000Y312000D01*
X11501D01*
X3001Y320500D01*
Y850001D01*
X4000Y851000D01*
X9000D01*
X13000Y847000D01*
X24000D01*
X24365Y846635D01*
X24316Y846513D01*
G03X24202Y845920I1488J-593D01*
G01Y844520D01*
G03X24301Y843966I1602J0D01*
G01X24346Y843846D01*
X24000Y843500D01*
X21500D01*
X20500Y842500D01*
Y833000D01*
X23500Y830000D01*
X34695D01*
X34719Y829993D01*
G03X35889I585J2227D01*
G01X35913Y830000D01*
X36500D01*
X38000Y831500D01*
X43000D01*
X45500Y829000D01*
Y652500D01*
X108000Y590000D01*
Y472700D01*
X105600Y470300D01*
X30300D01*
X20500Y460500D01*
Y406316D01*
G02X20065Y405917I-400J0D01*
G03Y387783I-793J-9067D01*
G02X20500Y387384I35J-399D01*
G01Y377472D01*
X20341Y377439D01*
G03Y369017I879J-4211D01*
G01X20500Y368984D01*
Y347261D01*
G02X20065Y346862I-400J0D01*
G37*
G36*
G01X104211Y307086D02*
X13899D01*
Y427086D01*
X41143D01*
Y418778D01*
X24135D01*
Y377528D01*
X22153D01*
G03Y368928I-933J-4300D01*
G01X24135D01*
Y323622D01*
X93975D01*
Y368928D01*
X95956D01*
G03Y377528I934J4300D01*
G01X93975D01*
Y418778D01*
X75393D01*
Y427086D01*
X104211D01*
Y307086D01*
G37*
G36*
G01X17500Y862500D02*
X4500D01*
X3500Y863500D01*
Y971000D01*
X17000Y984500D01*
X103000D01*
X104000Y983500D01*
Y981000D01*
X84000Y961000D01*
X46000D01*
X21000Y936000D01*
Y866000D01*
X17500Y862500D01*
G37*
G36*
G01X68304Y782220D02*
X56304D01*
X55804Y782720D01*
Y794720D01*
X56304Y795220D01*
X68804D01*
X69304Y794720D01*
Y783220D01*
X68304Y782220D01*
G37*
G36*
G01X251544Y712761D02*
Y725403D01*
G03X248692I-1426J4006D01*
G01Y712887D01*
X248581Y712831D01*
G03X247698Y711400I718J-1431D01*
G01Y710466D01*
X245848Y708616D01*
Y706866D01*
X229183Y690200D01*
G02X228500Y690483I-283J283D01*
G01Y721500D01*
X224500Y725500D01*
Y732000D01*
X222500Y734000D01*
X187000D01*
X184500Y736500D01*
Y742500D01*
X181500Y745500D01*
X174500D01*
X171500Y742500D01*
Y719500D01*
X167500Y715500D01*
X133000D01*
X111000Y737500D01*
Y776000D01*
X116000Y781000D01*
X150000D01*
X150250Y781250D01*
X156500Y775000D01*
X276500D01*
X281500Y770000D01*
Y750000D01*
X333500Y698000D01*
Y606500D01*
X317000Y590000D01*
X310000D01*
X302500Y582500D01*
Y568500D01*
X296000Y562000D01*
X252000D01*
X250000Y564000D01*
X238000D01*
X237000Y565000D01*
Y566500D01*
X237500Y567000D01*
X237586D01*
G03X237655Y566998I81J1600D01*
G01X239255D01*
G03X239320Y567000I-17J1601D01*
G01X241500D01*
X243500Y569000D01*
Y670500D01*
X231426Y682574D01*
Y688409D01*
X248332Y705315D01*
X248466Y705233D01*
G03X249300Y704998I835J1367D01*
G01X250700D01*
G03X251075Y705043I-2J1602D01*
G01X251098Y705048D01*
X253500D01*
G03Y709452I0J2202D01*
G01X252696D01*
G02X252297Y709881I0J400D01*
G03X252302Y710000I-1597J127D01*
G01Y711400D01*
G03X251544Y712761I-1601J0D01*
G37*
G36*
G01X126318Y846182D02*
X126000Y846500D01*
Y859500D01*
X131000Y864500D01*
Y891624D01*
G03X131032Y894175I-1900J1300D01*
G01X131000Y894225D01*
Y894400D01*
X132400Y895800D01*
X133300D01*
X146000Y908500D01*
X169449D01*
G03X170700Y907898I1251J999D01*
G01X172300D01*
G03X173367Y908306I-1J1602D01*
G02X173633I133J-150D01*
G03X174700Y907898I1068J1194D01*
G01X176300D01*
G03X177551Y908500I0J1601D01*
G01X214500D01*
X216912Y906088D01*
Y896914D01*
X215999Y896000D01*
X206500D01*
X206250Y895750D01*
X204996D01*
G03X202004I-1496J-1750D01*
G01X191996D01*
G03X188754Y895500I-1496J-1750D01*
G01X179500D01*
X166000Y882000D01*
Y848010D01*
X164490Y846500D01*
X151979D01*
G02X151583Y846960I0J400D01*
G03X151602Y847200I-1583J246D01*
G01Y848800D01*
G03X151122Y849943I-1601J0D01*
G03X147331Y849993I-1872J1807D01*
G03X146803Y848926I1069J-1193D01*
G01X146789Y848742D01*
X138198D01*
Y846500D01*
X133500D01*
X133182Y846182D01*
X126318D01*
G37*
G36*
G01X146808Y532038D02*
X166773Y512074D01*
X170482D01*
X170528Y512028D01*
X197972D01*
X219500Y490500D01*
X241481D01*
X241518Y490347D01*
G03X244274Y488647I2237J543D01*
G01X244383Y488672D01*
X290555Y442500D01*
Y429500D01*
X289055Y428000D01*
X284055D01*
X281860Y430194D01*
Y431378D01*
G03X279859Y433380I-2002J0D01*
G01X278676D01*
X269277Y442778D01*
X258222D01*
X226500Y474500D01*
X213500D01*
X185000Y503000D01*
X161575D01*
X135000Y529575D01*
Y556500D01*
X148000Y569500D01*
Y578000D01*
X153000Y583000D01*
X168000D01*
X170500Y580500D01*
Y567000D01*
X163500Y560000D01*
X155000D01*
X147028Y552028D01*
Y549960D01*
X146808Y549741D01*
Y532038D01*
G37*
G36*
G01X224548Y908000D02*
X219000D01*
X217000Y910000D01*
X156500D01*
X153000Y913500D01*
Y943000D01*
X157750Y947750D01*
X217250D01*
X227000Y938000D01*
Y909000D01*
X226252Y908252D01*
X224548D01*
Y908000D01*
G37*
G36*
G01X195000Y561500D02*
X192500Y564000D01*
Y575500D01*
X187500Y580500D01*
X177000D01*
X175000Y582500D01*
Y588499D01*
G02X175746Y588699I400J0D01*
G03Y591301I2254J1301D01*
G02X175000Y591501I-346J200D01*
G01Y653500D01*
X177000Y655500D01*
X205000D01*
X219000Y641500D01*
Y574000D01*
X211000Y566000D01*
Y562500D01*
X210000Y561500D01*
X200968D01*
G02X200603Y562063I0J400D01*
G03X200766Y562593I-2103J937D01*
G02X201432Y562815I394J-71D01*
G03X200734Y564907I1568J1686D01*
G02X200068Y564685I-394J71D01*
G03X196397Y562063I-1568J-1685D01*
G02X196032Y561500I-365J-163D01*
G01X195000D01*
G37*
G36*
G01X276500Y975000D02*
X176500D01*
X175500Y976000D01*
Y983500D01*
X177000Y985000D01*
X264000D01*
X268500Y989500D01*
Y993000D01*
X270000Y994500D01*
X277000D01*
X278500Y993000D01*
Y977000D01*
X276500Y975000D01*
G37*
G36*
G01X205500Y707500D02*
X206437Y708437D01*
X206538Y708420D01*
G03X206800Y708398I265J1580D01*
G01X208200D01*
G03X208730Y708489I-2J1602D01*
G01X208762Y708500D01*
X210738D01*
X210770Y708489D01*
G03X211300Y708398I532J1511D01*
G01X212700D01*
G03X213230Y708489I-2J1602D01*
G01X213262Y708500D01*
X215238D01*
X215270Y708489D01*
G03X215800Y708398I532J1511D01*
G01X217200D01*
G03X217730Y708489I-2J1602D01*
G01X217762Y708500D01*
X219738D01*
X219770Y708489D01*
G03X220300Y708398I532J1511D01*
G01X221700D01*
G03X222230Y708489I-2J1602D01*
G01X222262Y708500D01*
X222500D01*
X223500Y707500D01*
Y680500D01*
X242000Y662000D01*
Y569500D01*
X240702Y568202D01*
X237002D01*
X236801Y568000D01*
X236236D01*
X236187Y568032D01*
G03X235323Y568284I-862J-1349D01*
G01X233923D01*
G03X233012Y568000I-1J-1601D01*
G01X228500D01*
X226500Y570000D01*
Y576287D01*
G03Y578513I-2352J1113D01*
G01Y644500D01*
X205500Y665500D01*
Y707500D01*
G37*
G36*
G01X260500Y898500D02*
X238000D01*
X234500Y902000D01*
Y906000D01*
X234154Y906346D01*
Y907950D01*
X232550D01*
X232500Y908000D01*
X230452D01*
Y908252D01*
X229248D01*
X228202Y909298D01*
Y920202D01*
X230500Y922500D01*
X260000D01*
X262000Y920500D01*
Y900000D01*
X260500Y898500D01*
G37*
G36*
G01X265700Y213602D02*
G03X265171Y213511I3J-1602D01*
G01X265139Y213500D01*
X259721D01*
X259695Y213507D01*
G03X258305I-695J-2507D01*
G01X258279Y213500D01*
X257000D01*
X255000Y211500D01*
Y199000D01*
X256500Y197500D01*
X256800D01*
X262500Y191800D01*
X269600D01*
X270000Y191400D01*
Y176500D01*
X269000Y175500D01*
X249000D01*
X247000Y177500D01*
Y264000D01*
X248500Y265500D01*
X265500D01*
X274500Y256500D01*
Y216000D01*
X272000Y213500D01*
X271861D01*
X271829Y213511D01*
G03X271300Y213602I-532J-1511D01*
G01X269700D01*
G03X269171Y213511I3J-1602D01*
G01X269139Y213500D01*
X267861D01*
X267829Y213511D01*
G03X267300Y213602I-532J-1511D01*
G01X265700D01*
G37*
G36*
G01X268899Y888587D02*
G03X270431Y886128I2601J-86D01*
G01X270548Y886075D01*
Y885878D01*
X270532Y885840D01*
G03X270398Y885200I1468J-641D01*
G01Y883800D01*
G03X271000Y882549I1601J0D01*
G01Y880000D01*
X269000Y878000D01*
X243000D01*
X241500Y879500D01*
Y896500D01*
X242114Y897114D01*
X255386D01*
X256000Y896500D01*
Y890000D01*
X256298Y889702D01*
Y889598D01*
X256402D01*
X257000Y889000D01*
X268500D01*
G02X268899Y888587I-1J-400D01*
G37*
G36*
G01X271900Y200100D02*
X271452Y200549D01*
Y200652D01*
X271349D01*
X270600Y201400D01*
X266600D01*
X266500Y201300D01*
X259200D01*
X256500Y204000D01*
Y211000D01*
X257500Y212000D01*
X257700D01*
X257998Y212298D01*
X272498D01*
X272499Y212300D01*
X273200D01*
X275000Y210500D01*
Y200500D01*
X274600Y200100D01*
X274265D01*
G03X274200Y200102I-82J-1599D01*
G01X272800D01*
G03X272735Y200100I17J-1601D01*
G01X271900D01*
G37*
G36*
G01X274000Y175700D02*
X271800Y177900D01*
Y191500D01*
X270300Y193000D01*
X270099D01*
X270098Y193002D01*
X265799D01*
X264800Y194000D01*
Y198200D01*
X265600Y199000D01*
X271301D01*
X271402Y198898D01*
X275098D01*
X275100Y198900D01*
X288000Y186000D01*
Y176400D01*
X287300Y175700D01*
X274000D01*
G37*
G36*
G01X374300Y15898D02*
G03X374830Y15989I-2J1602D01*
G01X374862Y16000D01*
X375638D01*
X375670Y15989D01*
G03X376200Y15898I532J1511D01*
G01X377800D01*
G03X378330Y15989I-2J1602D01*
G01X378362Y16000D01*
X379138D01*
X379170Y15989D01*
G03X379700Y15898I532J1511D01*
G01X381300D01*
G03X381830Y15989I-2J1602D01*
G01X381862Y16000D01*
X382500D01*
X383000Y15500D01*
Y14641D01*
X382976Y14596D01*
G03X382698Y13477I2024J-1097D01*
G01X382699Y13393D01*
X380857Y11552D01*
X375259D01*
X375151Y11444D01*
X370442D01*
Y4540D01*
X373575D01*
G02X373858Y3858I0J-400D01*
G01X373500Y3500D01*
X297500D01*
X296500Y4500D01*
Y11000D01*
X297500Y12000D01*
X311500D01*
X313682Y9818D01*
X313696Y9791D01*
G03X314791Y8696I2304J1209D01*
G01X314818Y8682D01*
X315500Y8000D01*
X321500D01*
X323500Y10000D01*
Y11500D01*
X324000Y12000D01*
X326500D01*
X330500Y16000D01*
X372138D01*
X372170Y15989D01*
G03X372700Y15898I532J1511D01*
G01X374300D01*
G37*
G36*
G01X312798Y55400D02*
G03X312800Y55335I1601J17D01*
G01Y53065D01*
G03X312798Y53000I1599J-82D01*
G01Y50400D01*
G03X312800Y50335I1601J17D01*
G01Y49252D01*
X312398D01*
Y48698D01*
X311000Y47300D01*
Y14500D01*
X310000Y13500D01*
X297000D01*
X296200Y14300D01*
Y69800D01*
X298200Y71800D01*
X306500D01*
X306999Y72298D01*
X307700D01*
G03X309302Y73900I0J1602D01*
G01Y74601D01*
X309650Y74950D01*
X311050D01*
X311200Y75100D01*
X313852D01*
X314496Y74456D01*
X322004D01*
X323246Y75698D01*
X331000D01*
Y74222D01*
X325178D01*
Y72678D01*
X325000Y72500D01*
X315000D01*
X314754Y72254D01*
X314662D01*
Y72162D01*
X314500Y72000D01*
Y70600D01*
X314550Y70550D01*
Y66150D01*
X312800Y64400D01*
Y63065D01*
G03X312798Y63000I1599J-82D01*
G01Y60400D01*
G03X312800Y60335I1601J17D01*
G01Y58065D01*
G03X312798Y58000I1599J-82D01*
G01Y55400D01*
G37*
G36*
G01X295000Y73500D02*
X294500Y74000D01*
Y85000D01*
X295000Y85500D01*
X295235D01*
G03X295300Y85498I82J1599D01*
G01X296700D01*
G03X296765Y85500I-17J1601D01*
G01X299735D01*
G03X299800Y85498I82J1599D01*
G01X301200D01*
G03X301265Y85500I-17J1601D01*
G01X303000D01*
X303500Y85000D01*
Y83202D01*
X303198D01*
Y79798D01*
X303500D01*
Y78500D01*
X304000Y78000D01*
X306401D01*
X308000Y76401D01*
Y74999D01*
X306501Y73500D01*
X295000D01*
G37*
G36*
G01X294706Y100794D02*
X293500Y102000D01*
Y126000D01*
X294000Y126500D01*
X297000D01*
X297500Y126000D01*
Y121500D01*
X298000Y121000D01*
X301500D01*
X308000Y114500D01*
Y102000D01*
X306500Y100500D01*
X295640D01*
G03X294775Y100786I-1141J-2000D01*
G01X294706Y100794D01*
G37*
G36*
G01X324220Y129243D02*
G03X327472Y125991I1709J-1543D01*
G02X328023Y125977I268J-297D01*
G01X329500Y124500D01*
X335500D01*
X337500Y122500D01*
Y104500D01*
X336500Y103500D01*
X325855D01*
G03X322545I-1655J-1600D01*
G01X316073D01*
G03X312508Y104253I-2073J-1000D01*
G01X312367Y104133D01*
X310500Y106000D01*
Y115000D01*
X303000Y122500D01*
X299500D01*
X299000Y123000D01*
Y127500D01*
X298500Y128000D01*
X294000D01*
X293500Y128500D01*
Y132500D01*
X294000Y133000D01*
X321000D01*
X324206Y129794D01*
G02X324220Y129243I-283J-283D01*
G37*
G36*
G01X288500Y307500D02*
X282500Y313500D01*
Y362500D01*
X284000Y364000D01*
X315929D01*
X316429Y363500D01*
Y355951D01*
G03X315828Y354701I1000J-1250D01*
G01Y353297D01*
G03X315860Y352980I1601J2D01*
G02X315468Y352500I-392J-80D01*
G01X295000D01*
X292000Y349500D01*
Y343256D01*
G03Y340744I1929J-1256D01*
G01Y329500D01*
X298500Y323000D01*
X315929D01*
X316929Y322000D01*
Y314137D01*
X316926Y314121D01*
G03X316904Y313852I1579J-265D01*
G01Y312452D01*
G03X316926Y312183I1601J-4D01*
G01X316929Y312167D01*
Y309500D01*
X314929Y307500D01*
X288500D01*
G37*
G36*
G01X362454Y393300D02*
G03X362495Y392938I1601J-2D01*
G01X362500Y392916D01*
Y390584D01*
X362495Y390562D01*
G03X362454Y390200I1560J-360D01*
G01Y388800D01*
G03X362495Y388438I1601J-2D01*
G01X362500Y388416D01*
Y386084D01*
X362495Y386062D01*
G03X362454Y385700I1560J-360D01*
G01Y384300D01*
G03X362495Y383938I1601J-2D01*
G01X362500Y383916D01*
Y381584D01*
X362495Y381562D01*
G03X362454Y381200I1560J-360D01*
G01Y379800D01*
G03X362495Y379438I1601J-2D01*
G01X362500Y379416D01*
Y377084D01*
X362495Y377062D01*
G03X362454Y376700I1560J-360D01*
G01Y375300D01*
G03X362495Y374938I1601J-2D01*
G01X362500Y374916D01*
Y372084D01*
X362495Y372062D01*
G03X362454Y371700I1560J-360D01*
G01Y370300D01*
G03X362495Y369938I1601J-2D01*
G01X362500Y369916D01*
Y362500D01*
X360500Y360500D01*
X347197D01*
G03X346329Y360802I-869J-1100D01*
G01X345529D01*
G03X344661Y360500I1J-1402D01*
G01X343697D01*
G03X342829Y360802I-869J-1100D01*
G01X342029D01*
G03X341161Y360500I1J-1402D01*
G01X327429D01*
X325929Y362000D01*
Y365500D01*
X324429Y367000D01*
X289929D01*
Y401500D01*
X292929Y404500D01*
X325256D01*
G03X338916I6830J4358D01*
G01X348971D01*
X358316Y395154D01*
X362346D01*
X362482Y395018D01*
X362469Y394919D01*
G03X362454Y394701I1586J-219D01*
G01Y393300D01*
G37*
G36*
G01X362704Y418299D02*
G03X363055Y417299I1601J0D01*
G01Y416201D01*
G03X362704Y415201I1250J-1000D01*
G01Y413799D01*
G03X363055Y412799I1601J0D01*
G01Y411701D01*
G03X362704Y410701I1250J-1000D01*
G01Y409299D01*
G03X363055Y408299I1601J0D01*
G01Y406971D01*
G03X362704Y405971I1250J-1000D01*
G01Y404569D01*
G03X363055Y403569I1601J0D01*
G01Y402189D01*
G03X362714Y401202I1260J-988D01*
G01Y399799D01*
G03X362719Y399673I1601J0D01*
G01Y399458D01*
X360099D01*
X339497Y420060D01*
X307555D01*
Y426400D01*
X305815Y428140D01*
X300475D01*
X297855Y430760D01*
X295875D01*
X295845Y430730D01*
X294265D01*
X292535Y432460D01*
Y437980D01*
X292885Y438330D01*
X292945D01*
X295065Y440450D01*
X308505D01*
X308555Y440500D01*
X311293D01*
X311325Y440489D01*
G03X311855Y440398I532J1511D01*
G01X313255D01*
G03X313785Y440489I-2J1602D01*
G01X313817Y440500D01*
X314604D01*
Y440348D01*
X330523D01*
X330563Y440330D01*
G03X331155Y440198I594J1270D01*
G01X331955D01*
G03X332823Y440500I-1J1402D01*
G01X334287D01*
G03X335155Y440198I869J1100D01*
G01X335955D01*
G03X336823Y440500I-1J1402D01*
G01X338287D01*
G03X339155Y440198I869J1100D01*
G01X339955D01*
G03X340823Y440500I-1J1402D01*
G01X342287D01*
G03X343155Y440198I869J1100D01*
G01X343955D01*
G03X344823Y440500I-1J1402D01*
G01X346287D01*
G03X347155Y440198I869J1100D01*
G01X347955D01*
G03X348823Y440500I-1J1402D01*
G01X350287D01*
G03X351155Y440198I869J1100D01*
G01X351955D01*
G03X352823Y440500I-1J1402D01*
G01X354287D01*
G03X355155Y440198I869J1100D01*
G01X355955D01*
G03X356823Y440500I-1J1402D01*
G01X358287D01*
G03X359155Y440198I869J1100D01*
G01X359955D01*
G03X360823Y440500I-1J1402D01*
G01X362287D01*
G03X363155Y440198I869J1100D01*
G01X363955D01*
G03X364823Y440500I-1J1402D01*
G01X365732D01*
G03X366600Y440198I869J1100D01*
G01X367400D01*
G03X367987Y440328I-2J1401D01*
G01X368114Y440386D01*
X370904Y437596D01*
Y433779D01*
X371027Y433656D01*
Y433528D01*
X372555Y432000D01*
X372683D01*
X372684Y431998D01*
X373597D01*
X374024Y431570D01*
X375483D01*
X375520Y431534D01*
X375522D01*
X376055Y431000D01*
Y421000D01*
X375055Y420000D01*
X369072D01*
X369071Y420002D01*
X367285D01*
X367243Y420146D01*
G03X365705Y421302I-1538J-445D01*
G01X364305D01*
G03X362704Y419702I0J-1601D01*
G01Y418299D01*
G37*
G36*
G01X325000Y71000D02*
X325178Y70821D01*
Y66482D01*
X325268Y66268D01*
X322500Y63500D01*
Y28000D01*
X318000Y23500D01*
X313000D01*
X312202Y24298D01*
Y46702D01*
X314000Y48500D01*
Y48601D01*
X314002Y48602D01*
Y63902D01*
X315752Y65652D01*
Y70751D01*
X316000Y71000D01*
X325000D01*
G37*
G36*
G01X326500Y132500D02*
X324500Y134500D01*
X299000D01*
X297500Y136000D01*
Y142438D01*
G02X298186Y142718I400J0D01*
G03X301567Y142816I1645J1610D01*
G01X303145D01*
X303176Y142806D01*
G03Y145850I501J1522D01*
G01X303145Y145840D01*
X301567D01*
G03X298186Y145938I-1736J-1512D01*
G02X297500Y146218I-286J280D01*
G01Y149500D01*
X299000Y151000D01*
X324910D01*
Y149476D01*
X324900Y149445D01*
G03X327759Y148062I1522J-501D01*
G02X328376Y148124I334J-221D01*
G01X330191Y146309D01*
G02X329908Y145626I-283J-283D01*
G01X324351D01*
X323946Y146030D01*
G03X323169Y146352I-778J-780D01*
G01X321797D01*
G02X321398Y146781I0J400D01*
G03X318278Y146397I-1598J116D01*
G01X318288Y146366D01*
Y143584D01*
X318278Y143553D01*
G03X321398Y143169I1522J-500D01*
G02X321797Y143598I399J29D01*
G01X322485D01*
X322642Y143442D01*
G03X324013Y142874I1371J1371D01*
G01X332100D01*
Y139126D01*
X329074D01*
G02X328680Y139593I1J400D01*
G03X325578Y139356I-1580J264D01*
G01X325588Y139325D01*
Y136826D01*
X325578Y136795D01*
G03X328701Y136353I1522J-501D01*
G02X328985Y136374I287J-1945D01*
G01X332100D01*
Y133400D01*
X331200Y132500D01*
X326500D01*
G37*
G36*
G01X309184Y217469D02*
G03X309398Y216726I1401J1D01*
G01X309429Y216678D01*
Y216000D01*
X308929Y215500D01*
X304429D01*
X303500Y216429D01*
Y238000D01*
X304500Y239000D01*
X308929D01*
X309429Y238500D01*
Y222564D01*
G03X309184Y221773I1156J-792D01*
G01Y220971D01*
G03X309429Y220180I1401J1D01*
G01Y219064D01*
G03X309184Y218273I1156J-792D01*
G01Y217469D01*
G37*
G36*
G01X310786Y218274D02*
G03X310650Y218875I-1401J-1D01*
G01X310630Y218916D01*
Y220328D01*
X310650Y220369D01*
G03X310786Y220970I-1265J602D01*
G01Y221774D01*
G03X310650Y222375I-1401J-1D01*
G01X310630Y222416D01*
Y223920D01*
X310636D01*
Y239824D01*
X310106D01*
X309464Y240465D01*
X305035D01*
X304500Y241000D01*
Y245500D01*
X305500Y246500D01*
X311959D01*
G03X312785Y246270I827J1372D01*
G01X314230D01*
X315000Y245500D01*
Y243500D01*
X318429Y240071D01*
Y211000D01*
X317429Y210000D01*
X312429D01*
X310429Y212000D01*
Y215301D01*
X310630Y215502D01*
Y216828D01*
X310650Y216869D01*
G03X310786Y217470I-1265J602D01*
G01Y218274D01*
G37*
G36*
G01X311791Y265500D02*
X314067D01*
X314099Y265489D01*
G03X314629Y265398I532J1511D01*
G01X316229D01*
G03X316759Y265489I-2J1602D01*
G01X316791Y265500D01*
X319067D01*
X319099Y265489D01*
G03X319629Y265398I532J1511D01*
G01X321229D01*
G03X321759Y265489I-2J1602D01*
G01X321791Y265500D01*
X323000D01*
X324500Y264000D01*
Y261000D01*
X328500Y257000D01*
Y249000D01*
X327500Y248000D01*
X305000D01*
X304500Y248500D01*
Y261500D01*
X308500Y265500D01*
X309067D01*
X309099Y265489D01*
G03X309629Y265398I532J1511D01*
G01X311229D01*
G03X311759Y265489I-2J1602D01*
G01X311791Y265500D01*
G37*
G36*
G01X321929Y267000D02*
X309429D01*
X308429Y268000D01*
Y273500D01*
X308929Y274000D01*
X321929D01*
X322429Y273500D01*
Y267500D01*
X321929Y267000D01*
G37*
G36*
G01X303230Y336400D02*
G03X302929Y337268I-1402J0D01*
G01Y345000D01*
X307929Y350000D01*
X314929D01*
X315828Y349102D01*
Y347798D01*
G03X315918Y347270I1601J1D01*
G01X315929Y347238D01*
Y339000D01*
X316929Y338000D01*
Y335762D01*
X316918Y335730D01*
G03X316828Y335202I1511J-529D01*
G01Y333798D01*
G03X316918Y333270I1601J1D01*
G01X316929Y333238D01*
Y327000D01*
X315429Y325500D01*
X304929D01*
X302929Y327500D01*
Y330732D01*
G03X303230Y331600I-1101J868D01*
G01Y332400D01*
G03X302929Y333268I-1402J0D01*
G01Y334732D01*
G03X303230Y335600I-1101J868D01*
G01Y336400D01*
G37*
G36*
G01X303848Y441652D02*
X301500Y444000D01*
Y448000D01*
X305500Y452000D01*
X318000D01*
X318436Y451564D01*
X318418Y451460D01*
G03X318392Y451173I1575J-287D01*
G01Y449573D01*
G03X319993Y447972I1601J0D01*
G01X321593D01*
G03X322782Y448500I1J1601D01*
G01X324485D01*
X324932Y448946D01*
X327644D01*
X327757Y449060D01*
X333455D01*
X335015Y447500D01*
X338215D01*
X338240Y447493D01*
G03X338655Y447438I416J1547D01*
G01X340255D01*
G03X341856Y449040I0J1601D01*
G01Y450682D01*
X342355Y451180D01*
X348315D01*
X353055Y446440D01*
X367098D01*
X368500Y445038D01*
Y442000D01*
X368202Y441702D01*
X367921D01*
X367887Y441714D01*
G03X367400Y441802I-489J-1314D01*
G01X366600D01*
G03X366113Y441714I2J-1402D01*
G01X366079Y441702D01*
X364476D01*
X364442Y441714D01*
G03X363955Y441802I-489J-1314D01*
G01X363155D01*
G03X362668Y441714I2J-1402D01*
G01X362634Y441702D01*
X360476D01*
X360442Y441714D01*
G03X359955Y441802I-489J-1314D01*
G01X359155D01*
G03X358668Y441714I2J-1402D01*
G01X358634Y441702D01*
X356476D01*
X356442Y441714D01*
G03X355955Y441802I-489J-1314D01*
G01X355155D01*
G03X354668Y441714I2J-1402D01*
G01X354634Y441702D01*
X352476D01*
X352442Y441714D01*
G03X351955Y441802I-489J-1314D01*
G01X351155D01*
G03X350668Y441714I2J-1402D01*
G01X350634Y441702D01*
X348476D01*
X348442Y441714D01*
G03X347955Y441802I-489J-1314D01*
G01X347155D01*
G03X346668Y441714I2J-1402D01*
G01X346634Y441702D01*
X344476D01*
X344442Y441714D01*
G03X343955Y441802I-489J-1314D01*
G01X343155D01*
G03X342668Y441714I2J-1402D01*
G01X342634Y441702D01*
X340476D01*
X340442Y441714D01*
G03X339955Y441802I-489J-1314D01*
G01X339155D01*
G03X338668Y441714I2J-1402D01*
G01X338634Y441702D01*
X336476D01*
X336442Y441714D01*
G03X335955Y441802I-489J-1314D01*
G01X335155D01*
G03X334668Y441714I2J-1402D01*
G01X334634Y441702D01*
X332476D01*
X332442Y441714D01*
G03X331955Y441802I-489J-1314D01*
G01X331155D01*
G03X330668Y441714I2J-1402D01*
G01X330634Y441702D01*
X308057D01*
X308007Y441652D01*
X303848D01*
G37*
G36*
G01X322199Y10398D02*
X321002Y9202D01*
X315998D01*
X314000Y11199D01*
Y21000D01*
X315000Y22000D01*
X318500D01*
X319548Y23048D01*
X319802D01*
Y23302D01*
X322500Y26000D01*
X324500D01*
X325500Y25000D01*
Y14000D01*
X325000Y13500D01*
X324000D01*
X323701Y13202D01*
X323502D01*
X322298Y11998D01*
Y11173D01*
X322290Y11146D01*
G03X322198Y10482I2210J-645D01*
G01X322199Y10398D01*
G37*
G36*
G01X402000Y20301D02*
Y18000D01*
X401000Y17000D01*
X383199D01*
X382998Y17202D01*
X372299D01*
X372000Y17500D01*
X327500D01*
X327000Y18000D01*
Y41500D01*
X328500Y43000D01*
X349500D01*
X352000Y40500D01*
X381500D01*
X382500Y41500D01*
X400500D01*
X402000Y40000D01*
Y26943D01*
X401863Y26897D01*
G03Y20347I1090J-3275D01*
G01X402000Y20301D01*
G37*
G36*
G01X335780Y72488D02*
X335828Y72356D01*
G03X336343Y71543I2072J743D01*
G01X337588Y70298D01*
X338702D01*
X339500Y69500D01*
X345090D01*
X345101Y69311D01*
G03X346700Y67798I1599J88D01*
G01X347795D01*
X349500Y66094D01*
Y52500D01*
X348000Y51000D01*
X330500D01*
X329000Y52500D01*
Y63500D01*
X326600Y65900D01*
X326702Y66002D01*
Y70998D01*
X326666Y71034D01*
Y72298D01*
X330998D01*
X331699Y73000D01*
X333073D01*
G03X334330Y72488I1258J1290D01*
G01X335780D01*
G37*
G36*
G01X328286Y222273D02*
G03X327929Y223207I-1401J0D01*
G01Y238000D01*
X328429Y238500D01*
X333429D01*
X333929Y238000D01*
Y236000D01*
X340929Y229000D01*
Y207500D01*
X340429Y207000D01*
X329929D01*
X327929Y209000D01*
Y217037D01*
G03X328286Y217971I-1044J934D01*
G01Y218773D01*
G03X327929Y219707I-1401J0D01*
G01Y220537D01*
G03X328286Y221471I-1044J934D01*
G01Y222273D01*
G37*
G36*
G01X317000Y246000D02*
X317270Y246270D01*
X318685D01*
G03X319511Y246500I-1J1602D01*
G01X327000D01*
X327500Y246000D01*
Y240571D01*
X326429Y239500D01*
Y212000D01*
X325929Y211500D01*
X320429D01*
X319929Y212000D01*
Y240000D01*
X319630Y240298D01*
Y240569D01*
X317000Y243199D01*
Y246000D01*
G37*
G36*
G01X347188Y314741D02*
X347429Y314500D01*
Y312000D01*
X341429Y306000D01*
Y299500D01*
X340929Y299000D01*
X325929D01*
X325429Y299500D01*
Y314500D01*
X325929Y315000D01*
X341161D01*
G03X342029Y314698I869J1100D01*
G01X342829D01*
G03X343697Y315000I-1J1402D01*
G01X345161D01*
G03X346029Y314698I869J1100D01*
G01X346829D01*
G03X347084Y314722I-3J1402D01*
G01X347188Y314741D01*
G37*
G36*
G01X323429Y311500D02*
X322929Y311000D01*
X318929D01*
X318429Y311500D01*
Y322500D01*
X318929Y323000D01*
X348929D01*
X349929Y322000D01*
Y317000D01*
X349429Y316500D01*
X323929D01*
X323429Y316000D01*
Y311500D01*
G37*
G36*
G01X343697Y332500D02*
G03X342829Y332802I-869J-1100D01*
G01X342029D01*
G03X341161Y332500I1J-1402D01*
G01X325429D01*
X324929Y333000D01*
Y337500D01*
X325429Y338000D01*
X341360D01*
G03X343640I1140J2000D01*
G01X347429D01*
X347929Y337500D01*
Y333000D01*
X347543Y332614D01*
X347416Y332672D01*
G03X346829Y332802I-589J-1271D01*
G01X346029D01*
G03X345161Y332500I1J-1402D01*
G01X343697D01*
G37*
G36*
G01X319429Y324500D02*
X318429Y325500D01*
Y336000D01*
X318929Y336500D01*
X322429D01*
X323429Y335500D01*
Y332500D01*
X324478Y331452D01*
Y331348D01*
X324580D01*
X324929Y331000D01*
X347429D01*
X347929Y330500D01*
Y325000D01*
X347429Y324500D01*
X319429D01*
G37*
G36*
G01X343697Y347000D02*
G03X342829Y347302I-869J-1100D01*
G01X342029D01*
G03X341161Y347000I1J-1402D01*
G01X321429D01*
X320929Y347500D01*
Y350500D01*
X321429Y351000D01*
X322929D01*
X323929Y352000D01*
X345929D01*
X346929Y351000D01*
Y347500D01*
X346688Y347259D01*
X346584Y347278D01*
G03X346329Y347302I-258J-1378D01*
G01X345529D01*
G03X344661Y347000I1J-1402D01*
G01X343697D01*
G37*
G36*
G01X324730Y339000D02*
X317929D01*
X317429Y339500D01*
Y349000D01*
X317929Y349500D01*
X319429D01*
X319728Y349202D01*
Y347002D01*
X320931Y345798D01*
X321630D01*
X321929Y345500D01*
X347429D01*
X347929Y345000D01*
Y339500D01*
X347630Y339202D01*
X324931D01*
X324730Y339000D01*
G37*
G36*
G01X350429Y331500D02*
X349429Y332500D01*
Y350500D01*
X346429Y353500D01*
X323929D01*
X323630Y353202D01*
X323431D01*
X322431Y352202D01*
X320931D01*
X320730Y352000D01*
X318429D01*
X317929Y352500D01*
Y363500D01*
X318429Y364000D01*
X323429D01*
X323929Y363500D01*
Y361500D01*
X324478Y360952D01*
Y360348D01*
X325080D01*
X326429Y359000D01*
X350429D01*
X356929Y352500D01*
Y332000D01*
X356429Y331500D01*
X350429D01*
G37*
G36*
G01X386798Y867588D02*
X388967Y865419D01*
X388981Y865394D01*
G03X393281Y866807I2019J1106D01*
G01X393268Y866905D01*
X394370Y868006D01*
X394435Y868016D01*
G03X395802Y869600I-234J1584D01*
G01Y871000D01*
G03X395451Y872000I-1602J-1D01*
G03X395578Y872184I-1251J1000D01*
G02X395922I172J-102D01*
G03X397300Y871398I1378J815D01*
G01X398700D01*
G03X400087Y872200I-1J1602D01*
G02X400717Y872283I347J-200D01*
G01X403500Y869500D01*
Y801500D01*
X439500Y765500D01*
Y714500D01*
X435000Y710000D01*
X403500D01*
X398132Y715368D01*
G03X396903Y716618I-2132J-867D01*
G01X396867Y716633D01*
X394794Y718706D01*
X394786Y718775D01*
G03X392775Y720786I-2286J-275D01*
G01X392706Y720794D01*
X331500Y782000D01*
Y866500D01*
X332602Y867602D01*
G02X333272Y867420I283J-283D01*
G03X337795Y868179I2228J580D01*
G01X337788Y868271D01*
X340514Y870997D01*
X340593Y871000D01*
X366138D01*
X366170Y870989D01*
G03X366700Y870898I532J1511D01*
G01X368300D01*
G03X368830Y870989I-2J1602D01*
G01X368862Y871000D01*
X369224D01*
Y870783D01*
X369221Y870767D01*
G03X369198Y870500I1579J-270D01*
G01Y869100D01*
G03X369465Y868215I1602J0D01*
G03X373056Y867535I1535J-1715D01*
G02X373120Y867789I179J90D01*
G03X373440Y868087I-921J1310D01*
G02X374060I310J-253D01*
G03X374173Y867962I1243J1010D01*
G02X374210Y867436I-282J-284D01*
G03X377841Y867476I1831J-1395D01*
G02X377864Y868000I313J249D01*
G03X378302Y869100I-1164J1101D01*
G01Y870500D01*
G03X377951Y871500I-1602J-1D01*
G03X378302Y872500I-1251J1001D01*
G01Y872802D01*
X379000Y873500D01*
X382198D01*
Y873000D01*
G03X383800Y871398I1602J0D01*
G01X385200D01*
G03X386578Y872184I0J1601D01*
G02X386922I172J-102D01*
G03X387049Y872000I1378J816D01*
G03X386698Y871000I1251J-1001D01*
G01Y869600D01*
G03X386787Y869074I1602J1D01*
G01X386798Y869042D01*
Y867588D01*
G37*
G36*
G01X336379Y947500D02*
G03X337127Y947305I921J2000D01*
G01X337201Y947299D01*
X339000Y945500D01*
X340981D01*
X341848Y944632D01*
Y939348D01*
X341000Y938500D01*
X340641D01*
X340596Y938524D01*
G03X338854Y938710I-1097J-2024D01*
G01X338827Y938702D01*
X334088D01*
X334068Y938682D01*
X333973Y938692D01*
G03X333800Y938702I-179J-1592D01*
G01X331298D01*
X330700Y939300D01*
Y943800D01*
X331200Y944300D01*
Y946800D01*
X331900Y947500D01*
X332635D01*
G03X332700Y947498I82J1599D01*
G01X334300D01*
G03X334365Y947500I-17J1601D01*
G01X336379D01*
G37*
G36*
G01X337300Y955102D02*
G03X337038Y955080I3J-1602D01*
G01X336937Y955063D01*
X336500Y955500D01*
Y960000D01*
X338000Y961500D01*
X362500D01*
X363500Y960500D01*
Y956000D01*
X362500Y955000D01*
X361762D01*
X361730Y955011D01*
G03X361200Y955102I-532J-1511D01*
G01X359800D01*
G03X359270Y955011I2J-1602D01*
G01X359238Y955000D01*
X357262D01*
X357230Y955011D01*
G03X356700Y955102I-532J-1511D01*
G01X355300D01*
G03X354770Y955011I2J-1602D01*
G01X354738Y955000D01*
X352762D01*
X352730Y955011D01*
G03X352200Y955102I-532J-1511D01*
G01X350800D01*
G03X350270Y955011I2J-1602D01*
G01X350238Y955000D01*
X348262D01*
X348230Y955011D01*
G03X347700Y955102I-532J-1511D01*
G01X346300D01*
G03X345770Y955011I2J-1602D01*
G01X345738Y955000D01*
X343762D01*
X343730Y955011D01*
G03X343200Y955102I-532J-1511D01*
G01X341800D01*
G03X341270Y955011I2J-1602D01*
G01X341238Y955000D01*
X339262D01*
X339230Y955011D01*
G03X338700Y955102I-532J-1511D01*
G01X337300D01*
G37*
G36*
G01X370963Y69537D02*
X371748Y68752D01*
Y62048D01*
X372000D01*
Y50000D01*
X372348Y49652D01*
Y48798D01*
X373202D01*
X374000Y48000D01*
X380000D01*
X380500Y47500D01*
Y43000D01*
X380000Y42500D01*
X355500D01*
X354500Y43500D01*
Y57500D01*
X363500Y66500D01*
Y69000D01*
X364500Y70000D01*
X368964D01*
G03X370864Y69524I1536J2100D01*
G01X370963Y69537D01*
G37*
G36*
G01X365588Y169659D02*
X364929Y169000D01*
Y166500D01*
X363929Y165500D01*
X362429D01*
X361929Y166000D01*
Y169000D01*
X361637Y169292D01*
X361633Y169367D01*
G03X360509Y170491I-1200J-76D01*
G01X360434Y170495D01*
X359429Y171500D01*
Y172500D01*
X359707Y172778D01*
G03X360080Y173151I-859J1232D01*
G01X360102Y173174D01*
X365344D01*
X365670Y173500D01*
X366929D01*
X367429Y173000D01*
Y172047D01*
G03X366812Y170950I880J-1217D01*
G01X366806Y170877D01*
X366365Y170436D01*
X366323Y170421D01*
G03X365603Y169701I410J-1130D01*
G01X365588Y169659D01*
G37*
G36*
G01X377782Y214500D02*
G02X378064Y213817I-1J-400D01*
G01X377545Y213298D01*
X377484Y213287D01*
G03X376279Y212082I272J-1477D01*
G01X376268Y212021D01*
X375359Y211112D01*
G03X376181Y209034I822J-876D01*
G01X376182D01*
G03X377032Y209386I0J1202D01*
G01X377967Y210322D01*
X378028Y210333D01*
G03X379233Y211538I-272J1477D01*
G01X379244Y211599D01*
X380287Y212642D01*
X381597Y211332D01*
G02X381602Y211055I-142J-141D01*
G03X383331Y209386I879J-819D01*
G01X384266Y210322D01*
X384327Y210333D01*
G03X385320Y211000I-272J1477D01*
G01X385929D01*
X387429Y212500D01*
Y224500D01*
X388429Y225500D01*
X390929D01*
X391429Y225000D01*
Y224000D01*
X391265Y223836D01*
X391250Y223826D01*
G03X390929Y222167I679J-992D01*
G01Y220352D01*
G03Y219018I1000J-667D01*
G01Y217202D01*
G03X391489Y215416I1000J-667D01*
G01X391528Y215401D01*
X391929Y215000D01*
X395929D01*
X396929Y216000D01*
Y220500D01*
X398069Y221640D01*
X398158Y221635D01*
G03X399079Y221984I72J1199D01*
G01X400132Y223038D01*
Y223703D01*
X400429Y224000D01*
X401929D01*
X402429Y223500D01*
Y216000D01*
X403654Y214775D01*
G02X403660Y214216I-283J-283D01*
G03X403326Y213385I867J-831D01*
G01Y213384D01*
G03X403678Y212534I1202J0D01*
G01X404614Y211599D01*
X404625Y211538D01*
G03X405830Y210333I1477J272D01*
G01X405891Y210322D01*
X406826Y209386D01*
G03X407676Y209034I850J850D01*
G01X407677D01*
G03X408499Y211112I0J1202D01*
G01X407590Y212021D01*
X407579Y212082D01*
G03X406949Y213051I-1477J-271D01*
G02X406948Y213711I225J330D01*
G03X407262Y214000I-850J1238D01*
G01X408098D01*
G03X409256Y213463I1151J965D01*
G02X409650Y213143I2J-400D01*
G03X412021Y213243I1177J242D01*
G01X412029Y213312D01*
X412717Y214000D01*
X415236D01*
X415639Y213597D01*
X415340Y213298D01*
X415279Y213287D01*
G03X414074Y212082I272J-1477D01*
G01X414063Y212021D01*
X413127Y211086D01*
G03X414827Y209386I850J-850D01*
G01X415762Y210322D01*
X415823Y210333D01*
G03X417028Y211538I-272J1477D01*
G01X417039Y211599D01*
X417976Y212535D01*
G03X418317Y213546I-850J850D01*
G02X418713Y214000I396J54D01*
G01X421858D01*
G02X421999Y213659I0J-200D01*
G01X421639Y213298D01*
X421578Y213287D01*
G03X420373Y212082I272J-1477D01*
G01X420362Y212021D01*
X419426Y211086D01*
G03X421126Y209386I850J-850D01*
G01X422061Y210322D01*
X422122Y210333D01*
G03X423327Y211538I-272J1477D01*
G01X423338Y211599D01*
X424275Y212535D01*
G03X424616Y213546I-850J850D01*
G02X425012Y214000I396J54D01*
G01X428158D01*
G02X428299Y213659I0J-200D01*
G01X427939Y213298D01*
X427878Y213287D01*
G03X426673Y212082I272J-1477D01*
G01X426662Y212021D01*
X425753Y211112D01*
G03X426575Y209034I822J-876D01*
G01X426576D01*
G03X427426Y209386I0J1202D01*
G01X428361Y210322D01*
X428422Y210333D01*
G03X429502Y211157I-272J1477D01*
G02X430145Y211265I360J-175D01*
G01X432024Y209386D01*
G03X433724Y211086I850J850D01*
G01X431492Y213317D01*
G02X431774Y214000I283J283D01*
G01X432500D01*
X433500Y215000D01*
X441500D01*
X441592Y214908D01*
G02X441562Y214316I-283J-282D01*
G03X441875Y212270I761J-931D01*
G01X442000Y212219D01*
Y211402D01*
X441875Y211351D01*
G03Y209121I448J-1115D01*
G01X442000Y209070D01*
Y208252D01*
X441875Y208201D01*
G03X441465Y206245I448J-1115D01*
G01X441603Y206103D01*
X441429Y205929D01*
Y204740D01*
G03Y203134I894J-803D01*
G01Y201590D01*
G03Y199984I894J-803D01*
G01Y198440D01*
G03Y196834I894J-803D01*
G01Y195291D01*
G03X441385Y193736I894J-803D01*
G01X441429Y193681D01*
Y193500D01*
X442462Y192467D01*
X442478Y192423D01*
G03X443406Y191495I1419J491D01*
G01X443450Y191479D01*
X445612Y189317D01*
X445628Y189273D01*
G03X448340Y189000I1419J491D01*
G01X448903D01*
G03X449492Y188437I1293J764D01*
G01X449929Y188000D01*
Y187000D01*
X449429Y186500D01*
X442429D01*
X442161Y186232D01*
X442100Y186220D01*
G03X441127Y185155I223J-1181D01*
G02X440909Y184975I-199J19D01*
G03X440744Y184982I-146J-1495D01*
G02X440347Y185296I-7J400D01*
G03X440023Y185889I-1174J-256D01*
G01X439086Y186825D01*
X439075Y186886D01*
G03X437326Y185137I-1477J-272D01*
G01X437387Y185126D01*
X438323Y184189D01*
G03X438943Y183860I849J851D01*
G02X439267Y183470I-76J-393D01*
G03X440755Y181978I1502J10D01*
G02X441144Y181656I-3J-400D01*
G03X441429Y181086I1179J233D01*
G01Y179543D01*
G03Y177937I894J-803D01*
G01Y176393D01*
G03Y174787I894J-803D01*
G01Y173244D01*
G03Y171638I894J-803D01*
G01Y170094D01*
G03Y168488I894J-803D01*
G01Y166944D01*
G03Y165338I894J-803D01*
G01Y163795D01*
G03Y162189I894J-803D01*
G01Y160645D01*
G03Y159039I894J-803D01*
G01Y157496D01*
G03Y155890I894J-803D01*
G01Y154346D01*
G03Y152740I894J-803D01*
G01Y151196D01*
G03Y149590I894J-803D01*
G01Y149000D01*
X440555Y148126D01*
G02X439998Y148118I-283J283D01*
G03X439995Y148120I-659J-985D01*
G01X439086Y149029D01*
X439075Y149090D01*
G03X437870Y150295I-1477J-272D01*
G01X437809Y150306D01*
X436900Y151215D01*
G03X434822Y150393I-876J-822D01*
G01Y150392D01*
G03X435174Y149542I1202J0D01*
G01X436110Y148607D01*
X436121Y148546D01*
G03X437326Y147341I1477J272D01*
G01X437387Y147330D01*
X438322Y146394D01*
G03X438940Y146065I849J850D01*
G02X439263Y145672I-77J-392D01*
G03X439929Y144422I1502J-2D01*
G01Y142500D01*
X439528Y142099D01*
X439422Y142121D01*
G03X437979Y141087I-249J-1176D01*
G01X437971Y141018D01*
X437255Y140302D01*
X434792D01*
X434291Y140803D01*
X434505Y141017D01*
X434578Y141023D01*
G03X435947Y142392I-128J1497D01*
G01X435953Y142465D01*
X436462Y142974D01*
X436497Y142989D01*
G03X434919Y144567I-473J1105D01*
G01X434904Y144532D01*
X434395Y144023D01*
X434322Y144017D01*
G03X432953Y142648I128J-1497D01*
G01X432947Y142575D01*
X432438Y142066D01*
X432402Y142051D01*
G03X432732Y139751I471J-1106D01*
G01X432801Y139743D01*
X432887Y139657D01*
G02X432672Y138980I-283J-283D01*
G03X431900Y138500I202J-1185D01*
G01X430699D01*
G03X428751I-974J-705D01*
G01X427549D01*
G03X425601I-974J-705D01*
G01X424399D01*
G03X422451I-974J-705D01*
G01X421250D01*
G03X419302I-974J-705D01*
G01X418100D01*
G03X416152I-974J-705D01*
G01X415429D01*
X414593Y139336D01*
G02X414651Y139950I283J283D01*
G03X415082Y140472I-674J995D01*
G01X415097Y140507D01*
X415607Y141017D01*
X415680Y141023D01*
G03X417049Y142392I-128J1497D01*
G01X417055Y142465D01*
X417564Y142974D01*
X417599Y142989D01*
G03X416021Y144567I-473J1105D01*
G01X416006Y144532D01*
X415497Y144023D01*
X415424Y144017D01*
G03X414055Y142648I128J-1497D01*
G01X414049Y142575D01*
X413539Y142065D01*
X413504Y142050D01*
G03X412982Y141619I473J-1105D01*
G02X412368Y141561I-331J225D01*
G01X410212Y143718D01*
Y145323D01*
X408916Y146618D01*
X407266D01*
G03X406101Y147162I-1157J-958D01*
G02X405706Y147483I-3J400D01*
G03X403423Y147717I-1178J-239D01*
G01X403408Y147682D01*
X402899Y147173D01*
X402826Y147167D01*
G03X401924Y144577I128J-1497D01*
G02X401932Y144003I-275J-291D01*
G01X401929Y144000D01*
Y143618D01*
G03Y141422I1025J-1098D01*
G01Y140500D01*
X398812Y137383D01*
X398806Y137378D01*
G03X398642Y137214I977J-1141D01*
G01X398637Y137208D01*
X398429Y137000D01*
X394929D01*
X394429Y137500D01*
Y138152D01*
G03X394769Y138520I-918J1189D01*
G02X395436Y138525I335J-218D01*
G03X398176Y139528I1247J837D01*
G01X398175Y139550D01*
X398354Y139749D01*
G03X398484Y142120I-124J1196D01*
G01X398427Y142132D01*
X398244Y142315D01*
X398429Y142500D01*
Y142899D01*
X398572Y142942D01*
G03X398331Y145292I-343J1152D01*
G01X398148Y145491D01*
X398149Y145512D01*
G03X398152Y145542I-1493J164D01*
G01X398158Y145615D01*
X398667Y146124D01*
X398702Y146139D01*
G03X397124Y147717I-473J1105D01*
G01X397109Y147682D01*
X396600Y147173D01*
X396527Y147167D01*
G03X395153Y145664I128J-1497D01*
G02X394834Y145271I-400J-1D01*
G03X393902Y144340I245J-1177D01*
G02X393510Y144022I-391J82D01*
G03X392003Y142515I-5J-1502D01*
G02X391684Y142122I-400J-1D01*
G03X390824Y141418I245J-1177D01*
G01X390809Y141383D01*
X390426Y141000D01*
X389992D01*
X389962Y141164D01*
G03X389026Y142122I-1182J-219D01*
G02X388708Y142515I82J391D01*
G03Y142525I-1502J5D01*
G02X389026Y142917I400J1D01*
G03X389957Y143849I-246J1177D01*
G02X390350Y144168I392J-81D01*
G03X391852Y145542I5J1502D01*
G01X391858Y145615D01*
X392367Y146124D01*
X392402Y146139D01*
G03X390824Y147717I-473J1105D01*
G01X390809Y147682D01*
X390300Y147173D01*
X390227Y147167D01*
G03X388853Y145664I128J-1497D01*
G02X388535Y145271I-400J-2D01*
G03X387990Y145000I245J-1177D01*
G01X386420D01*
G03X385732Y145292I-790J-906D01*
G01X385549Y145491D01*
X385550Y145512D01*
G03X385553Y145542I-1493J164D01*
G01X385559Y145615D01*
X386068Y146124D01*
X386103Y146139D01*
G03X384525Y147717I-473J1105D01*
G01X384510Y147682D01*
X384001Y147173D01*
X383928Y147167D01*
G03X383214Y144426I128J-1497D01*
G02Y143764I-224J-331D01*
G03X382554Y142515I842J-1244D01*
G02X382236Y142122I-400J-2D01*
G03X381367Y141397I245J-1177D01*
G01X381352Y141360D01*
X380992Y141000D01*
X380543D01*
X380513Y141164D01*
G03X379929Y141988I-1182J-219D01*
G01Y143051D01*
G03X379647Y145254I-598J1043D01*
G01X379500Y145294D01*
Y145855D01*
X379769Y146124D01*
X379804Y146139D01*
G03X380527Y147125I-473J1105D01*
G02X380745Y147304I199J-20D01*
G03X382365Y148527I143J1495D01*
G01X382376Y148588D01*
X383331Y149542D01*
G03X383682Y150392I-851J849D01*
G01Y150393D01*
G03X381605Y151215I-1201J0D01*
G01X380677Y150287D01*
X380616Y150276D01*
G03X379393Y148658I272J-1477D01*
G02X379213Y148440I-199J-19D01*
G03X378226Y147717I118J-1196D01*
G01X378211Y147682D01*
X377702Y147173D01*
X377629Y147167D01*
G03X377099Y147020I130J-1497D01*
G01X377058Y147000D01*
X377000D01*
X376912Y146912D01*
X376897Y146902D01*
G03X376516Y146516I861J-1231D01*
G01X376500Y146500D01*
X372743D01*
G03X371366Y147164I-1250J-833D01*
G01X371273Y147156D01*
X371081Y147348D01*
X371072Y147414D01*
G03X370429Y148314I-1190J-170D01*
G01Y149225D01*
G03X370501Y149363I-1047J634D01*
G03X370003Y151589I-619J1030D01*
G01X369823Y151788D01*
X369824Y151808D01*
G03X369429Y152979I-1495J148D01*
G01Y154080D01*
G03X369559Y154239I-1095J1028D01*
G02X370216Y154234I327J-231D01*
G03X371185Y153603I1241J846D01*
G01X371246Y153592D01*
X372496Y152342D01*
X373032D01*
G03X373700Y154542I0J1201D01*
G01X373683Y154553D01*
X372945Y155291D01*
X372934Y155352D01*
G03X371458Y156582I-1477J-272D01*
G01X371457D01*
G02X371064Y156910I1J400D01*
G03X369952Y157893I-1182J-217D01*
G01X369764Y158093D01*
X369765Y158113D01*
G03X369773Y158262I-1494J155D01*
G01Y158344D01*
X370085Y158656D01*
X370142Y158668D01*
G03X370429Y160912I-260J1174D01*
G01Y161000D01*
X369814Y161615D01*
X369802Y161676D01*
G03X368929Y162776I-1477J-275D01*
G01Y163210D01*
G03X369804Y164324I-604J1375D01*
G01X369815Y164386D01*
X370429Y165000D01*
Y165071D01*
G03Y167211I-547J1070D01*
G01Y168221D01*
G03Y170361I-547J1070D01*
G01Y170500D01*
X369777Y171152D01*
X369763Y171205D01*
G03X368929Y172198I-1454J-375D01*
G01Y175834D01*
G03X369555Y176365I-622J1367D01*
G02X370224Y176360I333J-222D01*
G03X371617Y175679I1261J815D01*
G02X371834Y175495I17J-199D01*
G03X374215Y175379I1198J96D01*
G02X374599Y175708I394J-71D01*
G03X374440Y178707I-39J1502D01*
G02X374225Y178883I-16J200D01*
G03X371835Y178852I-1193J-143D01*
G01X371636Y178670D01*
X371618Y178671D01*
G03X371456Y178677I-137J-1496D01*
G02X371057Y178993I-8J400D01*
G03X370429Y179810I-1175J-253D01*
G01Y180819D01*
G03Y182959I-547J1070D01*
G01Y183969D01*
G03X369442Y186157I-547J1070D01*
G01X369320Y186109D01*
X367855Y187574D01*
X367934Y187653D01*
Y188189D01*
G03X366292Y189307I-1202J0D01*
G01X366170Y189259D01*
X364653Y190776D01*
X364701Y190898D01*
G03X363143Y192456I-1118J440D01*
G01X363021Y192408D01*
X361503Y193926D01*
X361551Y194048D01*
G03X361030Y195531I-1118J440D01*
G01X360929Y195589D01*
Y196536D01*
X361030Y196594D01*
G03Y198680I-597J1043D01*
G01X360929Y198738D01*
Y199686D01*
X361030Y199744D01*
G03X360122Y201948I-597J1043D01*
G01X360011Y201918D01*
X358415Y203514D01*
X358445Y203626D01*
G03X356973Y205098I-1161J311D01*
G01X356861Y205068D01*
X350000Y211929D01*
Y226000D01*
X351000Y227000D01*
X363929D01*
X367806Y223124D01*
Y221139D01*
G02X367238Y220776I-400J0D01*
G03X367568Y218820I-505J-1091D01*
G01X367709Y218957D01*
X369057Y217608D01*
X369320D01*
X369429Y217500D01*
X370429D01*
X370980Y216948D01*
Y215685D01*
X372307Y214359D01*
X371246Y213298D01*
X371185Y213287D01*
G03X369980Y212082I272J-1477D01*
G01X369969Y212021D01*
X369060Y211112D01*
G03X369882Y209034I822J-876D01*
G01X369883D01*
G03X370733Y209386I0J1202D01*
G01X371668Y210322D01*
X371729Y210333D01*
G03X372934Y211538I-272J1477D01*
G01X372945Y211599D01*
X373882Y212535D01*
G03X374107Y213921I-850J849D01*
G02X374465Y214500I358J179D01*
G01X377782D01*
G37*
G36*
G01X351929Y249000D02*
X350429Y250500D01*
Y271000D01*
X351429Y272000D01*
X381429D01*
X382824Y270606D01*
Y270604D01*
X382928Y270500D01*
Y264583D01*
X382929Y264582D01*
Y250000D01*
X381929Y249000D01*
X381191D01*
X381159Y249011D01*
G03X380629Y249102I-532J-1511D01*
G01X379229D01*
G03X378699Y249011I2J-1602D01*
G01X378667Y249000D01*
X376691D01*
X376659Y249011D01*
G03X376129Y249102I-532J-1511D01*
G01X374729D01*
G03X374199Y249011I2J-1602D01*
G01X374167Y249000D01*
X372191D01*
X372159Y249011D01*
G03X371629Y249102I-532J-1511D01*
G01X370229D01*
G03X369699Y249011I2J-1602D01*
G01X369667Y249000D01*
X367691D01*
X367659Y249011D01*
G03X367129Y249102I-532J-1511D01*
G01X365729D01*
G03X365199Y249011I2J-1602D01*
G01X365167Y249000D01*
X351929D01*
G37*
G36*
G01X379428Y280000D02*
X381429Y277999D01*
Y274500D01*
X380429Y273500D01*
X380291D01*
X380259Y273511D01*
G03X379729Y273602I-532J-1511D01*
G01X378129D01*
G03X377599Y273511I2J-1602D01*
G01X377567Y273500D01*
X376362D01*
X376330Y273511D01*
G03X375800Y273602I-532J-1511D01*
G01X374200D01*
G03X373670Y273511I2J-1602D01*
G01X373638Y273500D01*
X372291D01*
X372259Y273511D01*
G03X371729Y273602I-532J-1511D01*
G01X370129D01*
G03X369599Y273511I2J-1602D01*
G01X369567Y273500D01*
X363291D01*
X363259Y273511D01*
G03X362729Y273602I-532J-1511D01*
G01X361129D01*
G03X360599Y273511I2J-1602D01*
G01X360567Y273500D01*
X354291D01*
X354259Y273511D01*
G03X353729Y273602I-532J-1511D01*
G01X352129D01*
G03X351945Y273591I3J-1602D01*
G01X351849Y273580D01*
X350429Y275000D01*
Y279000D01*
X351429Y280000D01*
X379428D01*
G37*
G36*
G01X374199Y49500D02*
X373500Y50199D01*
Y62500D01*
X373202Y62798D01*
Y68701D01*
X373500Y69000D01*
X378500D01*
X394000Y53500D01*
Y45000D01*
X392000Y43000D01*
X383000D01*
X382500Y43500D01*
Y48500D01*
X381500Y49500D01*
X374199D01*
G37*
G36*
G01X386000Y940000D02*
X385702Y940298D01*
Y940412D01*
X385000Y941113D01*
Y945638D01*
X385011Y945670D01*
G03X385102Y946200I-1511J532D01*
G01Y947800D01*
G03X385011Y948330I-1602J-2D01*
G01X385000Y948362D01*
Y948500D01*
X385500Y949000D01*
X391500D01*
X393848Y946652D01*
Y940348D01*
X393500Y940000D01*
X386000D01*
G37*
G36*
G01X405429Y240400D02*
X403929Y238900D01*
X400929D01*
X400552Y239277D01*
X400681Y239418D01*
G03X400429Y241805I-1181J1082D01*
G01Y247400D01*
X400929Y247900D01*
Y265086D01*
X400931Y265099D01*
G03X400952Y265400I-2181J303D01*
G01Y266810D01*
X400930Y266879D01*
Y268683D01*
X400929Y268684D01*
Y273429D01*
X402000Y274500D01*
X407500D01*
X408000Y274000D01*
Y273112D01*
G03X408418Y269582I1500J-1612D01*
G01X409429Y268571D01*
Y263352D01*
X409278D01*
Y250248D01*
X406190Y247161D01*
X406140Y247147D01*
G03X405128Y245800I390J-1346D01*
G01Y245000D01*
G03X405429Y244132I1402J0D01*
G01Y243448D01*
X405228Y243246D01*
Y241900D01*
G03X405409Y241112I1801J-1D01*
G01X405429Y241071D01*
Y240400D01*
G37*
G36*
G01X418500Y3500D02*
X418142Y3858D01*
G02X418425Y4540I283J282D01*
G01X424590D01*
Y11444D01*
X417686D01*
Y9544D01*
X417000D01*
Y14000D01*
X418500Y15500D01*
X443000D01*
X447500Y11000D01*
X541000D01*
X566500Y36500D01*
Y61000D01*
X573500Y68000D01*
X577500D01*
X578000Y67500D01*
Y67362D01*
X577989Y67330D01*
G03X577898Y66800I1511J-532D01*
G01Y65200D01*
G03X577989Y64670I1602J2D01*
G01X578000Y64638D01*
Y63362D01*
X577989Y63330D01*
G03X577898Y62800I1511J-532D01*
G01Y61200D01*
G03X577989Y60670I1602J2D01*
G01X578000Y60638D01*
Y60000D01*
X579500Y58500D01*
X583738D01*
Y50392D01*
X592010D01*
Y58500D01*
X634500D01*
X650000Y74000D01*
X660500D01*
X663000Y71500D01*
Y62194D01*
X662748Y61943D01*
Y42543D01*
X658706Y38500D01*
X644969D01*
G02X644667Y39162I0J400D01*
G03X633167I-5750J4972D01*
G02X632865Y38500I-302J-262D01*
G01X606977D01*
G02X606675Y39162I0J400D01*
G03X595175I-5750J4972D01*
G02X594873Y38500I-302J-262D01*
G01X594000D01*
X583000Y27500D01*
Y10000D01*
X576500Y3500D01*
X418500D01*
G37*
G36*
G01X548057Y145943D02*
X551202Y149088D01*
Y150042D01*
X551213Y150074D01*
G03X551302Y150600I-1513J527D01*
G01Y152000D01*
G03X551299Y152080I-1601J-20D01*
G02X551699Y152500I400J20D01*
G01X552738D01*
X552770Y152489D01*
G03X553300Y152398I532J1511D01*
G01X554700D01*
G03X555230Y152489I-2J1602D01*
G01X555262Y152500D01*
X557738D01*
X557770Y152489D01*
G03X558300Y152398I532J1511D01*
G01X559700D01*
G03X560230Y152489I-2J1602D01*
G01X560262Y152500D01*
X562738D01*
X562770Y152489D01*
G03X563300Y152398I532J1511D01*
G01X564700D01*
G03X564962Y152420I-3J1602D01*
G01X565063Y152437D01*
X565500Y152000D01*
Y142000D01*
X555500Y132000D01*
X476500D01*
X474500Y134000D01*
Y148000D01*
X476000Y149500D01*
X479000D01*
X479253Y149247D01*
X479268Y149205D01*
G03X480634Y147839I2161J795D01*
G01X480676Y147824D01*
X486500Y142000D01*
X531500D01*
X542000Y152500D01*
X542738D01*
X542770Y152489D01*
G03X543300Y152398I532J1511D01*
G01X544700D01*
G03X545230Y152489I-2J1602D01*
G01X545262Y152500D01*
X546301D01*
G02X546701Y152080I0J-400D01*
G03X546698Y152000I1598J-100D01*
G01Y150812D01*
X544943Y149057D01*
G03X548057Y145943I1557J-1557D01*
G37*
G36*
G01X501500Y685500D02*
X469500D01*
X463500Y691500D01*
Y762000D01*
X479000Y777500D01*
Y800000D01*
X481500Y802500D01*
X509500D01*
X513500Y798500D01*
Y697500D01*
X501500Y685500D01*
G37*
G36*
G01X517565Y552980D02*
X584520D01*
X630000Y507500D01*
Y448000D01*
X623000Y441000D01*
Y409500D01*
X624490Y408010D01*
X624500D01*
X634010Y398500D01*
X681500D01*
X684500Y395500D01*
Y378500D01*
X681000Y375000D01*
Y345000D01*
X678500Y342500D01*
X634000D01*
X624000Y352500D01*
Y367000D01*
X607000D01*
X600000Y374000D01*
Y453500D01*
X597250Y456250D01*
X586750D01*
X567500Y475500D01*
X555500D01*
X515000Y516000D01*
Y551000D01*
X516813Y552813D01*
X516882Y552821D01*
G03X517533Y552970I-385J3178D01*
G01X517565Y552980D01*
G37*
G36*
G01X595758Y294915D02*
X597673Y293000D01*
Y292560D01*
X597626Y292504D01*
G03X597673Y288152I2573J-2148D01*
G01Y252673D01*
X596500Y251500D01*
X588000D01*
X587302Y252198D01*
Y253500D01*
G03X587033Y254387I-1602J-1D01*
G01X587000Y254437D01*
Y254563D01*
X587033Y254613D01*
G03X587302Y255500I-1333J888D01*
G01Y256900D01*
G03X587033Y257787I-1602J-1D01*
G01X587000Y257837D01*
Y258000D01*
X584500Y260500D01*
Y273000D01*
X583000Y274500D01*
X541000D01*
X539173Y276327D01*
Y295500D01*
X541673Y298000D01*
Y298599D01*
X541745Y298659D01*
G03X543734Y302013I-3751J4491D01*
G01X543746Y302073D01*
X545673Y304000D01*
X593173D01*
X594173Y303000D01*
Y300854D01*
G03X595695Y294926I2086J-2624D01*
G01X595758Y294915D01*
G37*
G36*
G01X547436Y371000D02*
X544500D01*
X543000Y372500D01*
Y468500D01*
X545000Y470500D01*
X568000D01*
X569500Y469000D01*
Y444000D01*
X567500Y442000D01*
Y375000D01*
X567000Y374500D01*
X556000D01*
X555402Y373902D01*
X554255D01*
G03X552854Y373076I0J-1601D01*
G01X549559D01*
X547768Y371285D01*
X547677Y371148D01*
X547619Y371091D01*
X547532Y371032D01*
X547506Y371024D01*
G03X547469Y371011I512J-1518D01*
G01X547436Y371000D01*
G37*
G36*
G01X577890Y332183D02*
G03X566434Y343639I-5647J5809D01*
G02X565865Y343635I-286J279D01*
G01X559500Y350000D01*
Y351966D01*
X560396D01*
Y360038D01*
G03X561957Y361500I-841J2462D01*
G01X610500D01*
X632000Y340000D01*
X681000D01*
X684500Y343500D01*
Y373000D01*
X687000Y375500D01*
Y386500D01*
X689500Y389000D01*
X712000D01*
X713500Y387500D01*
Y330000D01*
X711000Y327500D01*
X582000D01*
X577886Y331614D01*
G02X577890Y332183I283J283D01*
G37*
G36*
G01X572000Y365500D02*
X571000Y366500D01*
Y453000D01*
X572500Y454500D01*
X597000D01*
X598798Y452702D01*
Y373502D01*
X599000Y373301D01*
Y366500D01*
X598000Y365500D01*
X572000D01*
G37*
G36*
G01X602000Y62000D02*
X601000Y61000D01*
X579500D01*
X579202Y61298D01*
Y67998D01*
X579000Y68199D01*
Y72500D01*
X593500Y87000D01*
X601000D01*
X602000Y86000D01*
Y83413D01*
G03X600281Y81294I1897J-3295D01*
G02X599521I-380J123D01*
G03Y78942I-3616J-1176D01*
G02X600281I380J-123D01*
G03X602000Y76823I3616J1176D01*
G01Y73978D01*
G02X601442Y73611I-400J1D01*
G03Y66625I-1501J-3493D01*
G02X602000Y66258I158J-368D01*
G01Y62000D01*
G37*
G36*
G01X605420Y207000D02*
G03X604500Y207202I-921J-2000D01*
G01X604298D01*
X603500Y208000D01*
Y211798D01*
G03X604605Y215904I0J2202D01*
G02Y216596I201J346D01*
G03X603500Y220702I-1105J1904D01*
G01Y240000D01*
X601000Y242500D01*
X595862D01*
X595830Y242511D01*
G03X595300Y242602I-532J-1511D01*
G01X593700D01*
G03X593170Y242511I2J-1602D01*
G01X593138Y242500D01*
X592000D01*
X591500Y243000D01*
Y246500D01*
X592000Y247000D01*
X605500D01*
X609500Y243000D01*
Y208000D01*
X608500Y207000D01*
X605420D01*
G37*
G36*
G01X603293Y540766D02*
G03X603264Y545264I-2293J2234D01*
G01X589144Y559384D01*
X585500D01*
Y657344D01*
X590656Y662500D01*
X607000D01*
X609500Y660000D01*
Y569500D01*
X626500Y552500D01*
X710500D01*
X736500Y526500D01*
X844000D01*
X856000Y514500D01*
Y487246D01*
G03Y483754I1500J-1746D01*
G01Y452517D01*
X845983Y442500D01*
X838000D01*
X835500Y445000D01*
Y479000D01*
X817000Y497500D01*
X724000D01*
X695500Y526000D01*
X617500D01*
X603296Y540204D01*
G02X603293Y540766I283J283D01*
G37*
G36*
G01X604500Y89000D02*
X603000Y90500D01*
Y98000D01*
X678000Y173000D01*
X728000D01*
X729000Y172000D01*
Y152000D01*
X728000Y151000D01*
X696500D01*
X692000Y146500D01*
Y137500D01*
X691500Y137000D01*
X688701D01*
X687829Y137872D01*
X683567D01*
X682695Y137000D01*
X680000D01*
X675500Y132500D01*
Y129500D01*
X675032Y129032D01*
X674947Y129033D01*
G03X674922Y129034I-76J-1599D01*
G01X673322D01*
G03X673015Y129004I2J-1602D01*
G01X672996Y129000D01*
X668500D01*
X662500Y123000D01*
Y104000D01*
X663546Y102954D01*
Y97546D01*
X662000Y96000D01*
X631500D01*
X624500Y89000D01*
X604500D01*
G37*
G36*
G01X1390500Y357000D02*
X1385520Y361980D01*
Y567520D01*
X1393000Y575000D01*
Y663000D01*
X1352500Y703500D01*
Y923500D01*
X1329500Y946500D01*
X1183200D01*
G02X1182948Y947211I0J400D01*
G03X1180052I-1448J1789D01*
G02X1179800Y946500I-252J-311D01*
G01X1043000D01*
X1002500Y906000D01*
Y905248D01*
X1002030Y904779D01*
Y780530D01*
X999698Y778198D01*
G03X999402Y777902I1402J-1698D01*
G01X998000Y776500D01*
Y773347D01*
X996574Y771920D01*
Y771074D01*
X996500Y771000D01*
Y766011D01*
X991366Y760876D01*
X987916D01*
X987539Y760500D01*
X987000D01*
X985000Y758500D01*
Y754000D01*
X1010000Y729000D01*
Y669112D01*
G03Y665888I1500J-1612D01*
G01Y650126D01*
G03Y645874I1500J-2126D01*
G01Y644126D01*
G03Y639874I1500J-2126D01*
G01Y607000D01*
X992500Y589500D01*
X942500D01*
X940000Y592000D01*
Y646000D01*
X944500Y650500D01*
X982000D01*
X987000Y655500D01*
Y657323D01*
G02X987637Y657645I400J0D01*
G03Y661355I1363J1855D01*
G02X987000Y661677I-237J322D01*
G01Y693500D01*
X903000Y777500D01*
Y954000D01*
X883000Y974000D01*
X755000D01*
X751500Y970500D01*
Y934000D01*
X754500Y931000D01*
X845000D01*
X857500Y918500D01*
Y867000D01*
X855500Y865000D01*
X849500D01*
X847952Y866548D01*
Y867022D01*
X847968Y867060D01*
G03X848102Y867700I-1468J641D01*
G01Y869300D01*
G03X847331Y870669I-1601J0D01*
G01X844500Y873500D01*
X831549D01*
X831535Y873686D01*
G03X826821Y875010I-2595J-186D01*
G01X826761Y874926D01*
X826432D01*
X826378Y874968D01*
G03X825400Y875302I-979J-1268D01*
G01X824000D01*
G03X823000Y874951I1J-1602D01*
G03X822000Y875302I-1001J-1251D01*
G01X820600D01*
G03X818999Y873700I0J-1601D01*
G02X818799Y873500I-200J0D01*
G01X801500D01*
X797000Y878000D01*
Y891500D01*
X793000Y895500D01*
X788000D01*
X787500Y896000D01*
Y899000D01*
X786000Y900500D01*
X738990D01*
G02X738738Y901211I0J400D01*
G03X735503Y904452I-1448J1789D01*
G01X727649D01*
X724499Y901302D01*
X723600D01*
G03X722213Y900500I1J-1602D01*
G01X695000D01*
X661500Y867000D01*
Y699500D01*
X670000Y691000D01*
X723000D01*
X732500Y681500D01*
Y678000D01*
X740500Y670000D01*
X759000D01*
X762182Y666818D01*
G03X762500Y666336I2317J1183D01*
G01Y659000D01*
X760000Y656500D01*
Y644000D01*
X763500Y640500D01*
X822500D01*
X827000Y636000D01*
Y580500D01*
X823000Y576500D01*
X803000D01*
X797500Y582000D01*
X795000D01*
X794664Y582336D01*
X794679Y582435D01*
G03X794696Y582668I-1585J233D01*
G01Y584268D01*
G03X794522Y584994I-1602J0D01*
G01X794500Y585036D01*
Y585500D01*
X793500Y586500D01*
X778500D01*
X770500Y594500D01*
X716000D01*
X686000Y624500D01*
X619500D01*
X612500Y631500D01*
Y661500D01*
X597500Y676500D01*
Y801642D01*
G02X598069Y802004I400J0D01*
G03X598909Y806200I931J1996D01*
G01X598821Y806196D01*
X598604Y806413D01*
Y919913D01*
X597500Y921017D01*
Y923500D01*
X595000Y926000D01*
Y984000D01*
X596000Y985000D01*
X716500D01*
X720500Y989000D01*
Y997500D01*
X721500Y998500D01*
X740500D01*
X742000Y997000D01*
Y991500D01*
X746500Y987000D01*
X752000D01*
X756500Y991500D01*
Y999000D01*
X757000Y999500D01*
X793000D01*
X794000Y998500D01*
Y989000D01*
X798000Y985000D01*
X903000D01*
X918500Y969500D01*
Y772500D01*
X923000Y768000D01*
X987500D01*
X992000Y772500D01*
Y971000D01*
X1005500Y984500D01*
X1383000D01*
X1396500Y971000D01*
Y899500D01*
X1397000Y899000D01*
Y358500D01*
X1395500Y357000D01*
X1390500D01*
G37*
G36*
G01X634188Y442500D02*
X636835Y440165D01*
X639201Y437798D01*
X639202D01*
X640500Y436500D01*
Y433679D01*
G03Y433495I2300J-92D01*
G01Y427000D01*
X661500Y406000D01*
Y401500D01*
X660500Y400500D01*
X634500D01*
X625000Y410000D01*
Y441000D01*
X626500Y442500D01*
X634188D01*
G37*
G36*
G01X692360Y454664D02*
G03X692371Y454479I1602J2D01*
G01X692382Y454382D01*
X692000Y454000D01*
X689000D01*
X685000Y450000D01*
X684607D01*
Y450223D01*
X669191D01*
Y450000D01*
X664920D01*
Y450222D01*
X661318D01*
Y450000D01*
X660606D01*
X660605Y450002D01*
X659998D01*
X659500Y450500D01*
Y458500D01*
X658500Y459500D01*
X656500D01*
X656000Y460000D01*
Y465000D01*
X656500Y465500D01*
X660000D01*
X662018Y463482D01*
Y463406D01*
X662094D01*
X662500Y463000D01*
X671160D01*
Y462705D01*
X684607D01*
Y463000D01*
X685500D01*
X686000Y463500D01*
Y522000D01*
X687000Y523000D01*
X694500D01*
X695500Y522000D01*
Y464000D01*
X694318Y462818D01*
X694291Y462804D01*
G03X693196Y461709I1209J-2304D01*
G01X693182Y461682D01*
X692500Y461000D01*
Y456919D01*
X692485Y456882D01*
G03X692360Y456264I1477J-620D01*
G01Y454664D01*
G37*
G36*
G01X929602Y52300D02*
G03X929591Y52484I-1602J-3D01*
G01X929580Y52580D01*
X930500Y53500D01*
X937198D01*
X937247Y53371D01*
G03X939209Y51741I2430J930D01*
G01X939271Y51729D01*
X942000Y49000D01*
X953500D01*
X955000Y50500D01*
Y172000D01*
X971620Y188620D01*
G02X972302Y188362I283J-283D01*
G03X974638Y190698I2198J138D01*
G02X974380Y191380I25J399D01*
G01X975099Y192099D01*
X975173Y192104D01*
G03X977203Y194134I-166J2196D01*
G01X977208Y194208D01*
X979500Y196500D01*
X982917D01*
X982948Y196490D01*
G03X983460Y196406I512J1518D01*
G01X985060D01*
G03X985572Y196490I0J1602D01*
G01X985603Y196500D01*
X987317D01*
X987348Y196490D01*
G03X987860Y196406I512J1518D01*
G01X989460D01*
G03X989972Y196490I0J1602D01*
G01X990003Y196500D01*
X1019500D01*
X1021000Y195000D01*
Y188846D01*
X1008074Y175920D01*
Y99091D01*
X991074Y82091D01*
Y80574D01*
X990500Y80000D01*
Y59500D01*
X1029000Y21000D01*
X1103000D01*
X1105000Y23000D01*
Y50000D01*
X1096000Y59000D01*
Y70000D01*
X1095862Y70138D01*
X1095951Y70274D01*
G03X1097076Y74061I-5814J3788D01*
G01Y75489D01*
G03X1097976Y77707I-2283J2218D01*
G01Y83700D01*
G03X1096415Y85712I-2077J0D01*
G01X1096362Y85725D01*
X1095794Y86294D01*
G02X1095726Y86457I161J163D01*
G01Y87098D01*
X1096602D01*
Y93502D01*
X1095338D01*
Y95240D01*
X1096362D01*
Y101244D01*
X1096101D01*
G03X1095912Y101542I-1439J-704D01*
G03X1096100Y101840I-1252J998D01*
G01X1096363D01*
Y107844D01*
X1095077D01*
G03X1094452Y108753I-2762J-1230D01*
G01X1094259Y108946D01*
G02X1094112Y109300I354J355D01*
G01Y124000D01*
G02X1094127Y124210I1522J-3D01*
G03X1093047Y128641I-233J2290D01*
G02X1092500Y129012I-147J372D01*
G01Y213500D01*
X1094000Y215000D01*
X1106500D01*
X1109000Y212500D01*
Y5000D01*
X1107001Y3001D01*
X667499D01*
X665500Y5000D01*
Y20000D01*
X682500Y37000D01*
Y47000D01*
X686500Y51000D01*
X721500D01*
X722500Y52000D01*
Y54500D01*
X723228Y55228D01*
X723344Y55191D01*
G03X723832Y55114I491J1525D01*
G01X725232D01*
G03X726274Y55500I-1J1602D01*
G01X729700D01*
X731000Y54200D01*
X740400D01*
X743000Y56800D01*
X750700D01*
X756498Y51002D01*
Y50800D01*
G03X758100Y49198I1602J0D01*
G01X758302D01*
X759500Y48000D01*
X767500D01*
X785000Y65500D01*
Y96483D01*
X815017Y126500D01*
X829500D01*
X854500Y101500D01*
Y81222D01*
X854493Y81196D01*
G03Y79804I2507J-696D01*
G01X854500Y79778D01*
Y68500D01*
X875000Y48000D01*
X929000D01*
X929500Y48500D01*
Y50138D01*
X929511Y50170D01*
G03X929602Y50700I-1511J532D01*
G01Y52300D01*
G37*
G36*
G01X664500Y222500D02*
X663500Y223500D01*
Y262500D01*
X665000Y264000D01*
X673693D01*
X673725Y263989D01*
G03X674255Y263898I532J1511D01*
G01X675855D01*
G03X676385Y263989I-2J1602D01*
G01X676417Y264000D01*
X677693D01*
X677725Y263989D01*
G03X678255Y263898I532J1511D01*
G01X679855D01*
G03X680385Y263989I-2J1602D01*
G01X680417Y264000D01*
X681693D01*
X681725Y263989D01*
G03X682255Y263898I532J1511D01*
G01X683855D01*
G03X684385Y263989I-2J1602D01*
G01X684417Y264000D01*
X685693D01*
X685725Y263989D01*
G03X686255Y263898I532J1511D01*
G01X687855D01*
G03X688385Y263989I-2J1602D01*
G01X688417Y264000D01*
X690910D01*
G02X691196Y263320I0J-400D01*
G03X695626Y261902I1859J-1820D01*
G01X695610Y262002D01*
X697608Y264000D01*
X704693D01*
X704725Y263989D01*
G03X705255Y263898I532J1511D01*
G01X706855D01*
G03X707385Y263989I-2J1602D01*
G01X707417Y264000D01*
X708693D01*
X708725Y263989D01*
G03X709255Y263898I532J1511D01*
G01X710855D01*
G03X711385Y263989I-2J1602D01*
G01X711417Y264000D01*
X712693D01*
X712725Y263989D01*
G03X713255Y263898I532J1511D01*
G01X714855D01*
G03X715385Y263989I-2J1602D01*
G01X715417Y264000D01*
X716693D01*
X716725Y263989D01*
G03X717255Y263898I532J1511D01*
G01X718855D01*
G03X719385Y263989I-2J1602D01*
G01X719417Y264000D01*
X720000D01*
X721000Y263000D01*
Y256500D01*
X687000Y222500D01*
X664500D01*
G37*
G36*
G01Y412000D02*
X664000Y412500D01*
Y434000D01*
X672500Y442500D01*
Y443420D01*
X672794D01*
Y448294D01*
X673000Y448500D01*
X686000D01*
X688500Y446000D01*
X695000D01*
X696000Y445000D01*
Y438000D01*
X684000Y426000D01*
Y414000D01*
X682000Y412000D01*
X664500D01*
G37*
G36*
G01X672794Y468247D02*
X674802Y470254D01*
Y472990D01*
G03X674500Y476191I-1792J1446D01*
G01Y483000D01*
X671000Y486500D01*
Y507000D01*
X665500Y512500D01*
Y522000D01*
X666500Y523000D01*
X684000D01*
X684798Y522202D01*
Y464298D01*
X684716Y464216D01*
X672094D01*
Y464679D01*
X672164Y464738D01*
G03X672794Y466107I-1171J1368D01*
G01Y468247D01*
G37*
G36*
G01X716000Y183000D02*
X715176Y183824D01*
Y193676D01*
X716500Y195000D01*
X720000D01*
X720437Y194563D01*
X720420Y194462D01*
G03X720398Y194200I1580J-265D01*
G01Y192800D01*
G03X722000Y191198I1602J0D01*
G01X723400D01*
G03X724287Y191467I-1J1602D01*
G01X724337Y191500D01*
X724500D01*
X725874Y192874D01*
X730374D01*
X730754Y192494D01*
X730767Y192441D01*
G03X732441Y190767I2233J559D01*
G01X732494Y190754D01*
X732685Y190563D01*
X732668Y190462D01*
G03X732646Y190200I1580J-265D01*
G01Y188800D01*
G03X732737Y188270I1602J2D01*
G01X732748Y188238D01*
Y184000D01*
X731748Y183000D01*
X731110D01*
X731078Y183011D01*
G03X730548Y183102I-532J-1511D01*
G01X728948D01*
G03X728418Y183011I2J-1602D01*
G01X728386Y183000D01*
X727010D01*
X726978Y183011D01*
G03X726448Y183102I-532J-1511D01*
G01X725048D01*
G03X724518Y183011I2J-1602D01*
G01X724486Y183000D01*
X716000D01*
G37*
G36*
G01X762500Y843000D02*
X757500Y848000D01*
X720000D01*
X718500Y849500D01*
Y859763D01*
X718504Y859783D01*
G03Y860717I-2254J467D01*
G01X718500Y860737D01*
Y862638D01*
X718511Y862670D01*
G03X718602Y863200I-1511J532D01*
G01Y864800D01*
G03X718511Y865330I-1602J-2D01*
G01X718500Y865362D01*
Y866000D01*
X719000Y866500D01*
X725000D01*
X725500Y866000D01*
Y865262D01*
X725489Y865230D01*
G03X725398Y864700I1511J-532D01*
G01Y863300D01*
G03X725489Y862770I1602J2D01*
G01X725500Y862738D01*
Y862000D01*
X728000Y859500D01*
X767500D01*
X767937Y859063D01*
X767920Y858962D01*
G03X767898Y858700I1580J-265D01*
G01Y857300D01*
G03X768500Y856049I1601J0D01*
G01Y855451D01*
G03X767898Y854200I999J-1251D01*
G01Y852800D01*
G03X768500Y851549I1601J0D01*
G01Y844500D01*
X767000Y843000D01*
X762500D01*
G37*
G36*
G01X743000Y672000D02*
X738000Y677000D01*
Y757500D01*
X735000Y760500D01*
Y762816D01*
X735008Y762843D01*
G03X735070Y763284I-1540J441D01*
G01Y764684D01*
G03X735062Y764836I-1602J-8D01*
G01X735053Y764930D01*
X735623Y765500D01*
X779500D01*
X782500Y768500D01*
Y775500D01*
X783000Y776000D01*
X786138D01*
X786170Y775989D01*
G03X786700Y775898I532J1511D01*
G01X788300D01*
G03X788830Y775989I-2J1602D01*
G01X788862Y776000D01*
X790138D01*
X790170Y775989D01*
G03X790700Y775898I532J1511D01*
G01X792300D01*
G03X792830Y775989I-2J1602D01*
G01X792862Y776000D01*
X793000D01*
X793500Y775500D01*
Y771500D01*
X791500Y769500D01*
Y760500D01*
X790500Y759500D01*
X788000D01*
X757500Y729000D01*
Y728285D01*
X757168D01*
X757116Y728406D01*
G03X756789Y726052I-2116J-906D01*
G02X757500Y725800I311J-252D01*
G01Y693500D01*
X759500Y691500D01*
X767947D01*
X768145Y691302D01*
X772698D01*
X772936Y691064D01*
Y689552D01*
X773000D01*
Y688556D01*
X772936D01*
Y687156D01*
X772081D01*
X772027Y687196D01*
G03Y683512I-1381J-1842D01*
G01X772081Y683552D01*
X772936D01*
Y682152D01*
X773000D01*
Y675231D01*
G02X772553Y674834I-400J0D01*
G03X769651Y672380I-303J-2584D01*
G02X769252Y672000I-399J20D01*
G01X743000D01*
G37*
G36*
G01X945000Y652500D02*
X942000Y655500D01*
Y680000D01*
X877952Y744048D01*
Y744952D01*
X877048D01*
X859500Y762500D01*
Y920000D01*
X846500Y933000D01*
X756000D01*
X753500Y935500D01*
Y970500D01*
X755000Y972000D01*
X783579D01*
G02X783863Y971319I0J-400D01*
G03X787137I1637J-1619D01*
G02X787421Y972000I284J281D01*
G01X881000D01*
X901000Y952000D01*
Y776500D01*
X971569Y705931D01*
G02X971207Y705256I-283J-283D01*
G03X972076Y701118I-457J-2256D01*
G02X972705Y700822I230J-327D01*
G03X976976Y699820I2295J178D01*
G02X977603Y699897I343J-205D01*
G01X985000Y692500D01*
Y656000D01*
X981500Y652500D01*
X945000D01*
G37*
G36*
G01X812000Y339000D02*
Y330500D01*
X811000Y329500D01*
X772000D01*
X770500Y331000D01*
Y339000D01*
X771500Y340000D01*
X811000D01*
X812000Y339000D01*
G37*
G36*
G01X782898Y354700D02*
G03X782989Y354170I1602J2D01*
G01X783000Y354138D01*
Y353500D01*
X784000Y352500D01*
X797500D01*
X798500Y351500D01*
Y343500D01*
X797500Y342500D01*
X772500D01*
X770500Y344500D01*
Y387500D01*
X772000Y389000D01*
X780000D01*
X781500Y387500D01*
Y358500D01*
X783000Y357000D01*
Y356862D01*
X782989Y356830D01*
G03X782898Y356300I1511J-532D01*
G01Y354700D01*
G37*
G36*
G01X771000Y429500D02*
X768318Y432182D01*
X768304Y432209D01*
G03X767209Y433304I-2304J-1209D01*
G01X767182Y433318D01*
X767000Y433500D01*
Y442500D01*
X768000Y443500D01*
X780000D01*
X782824Y446324D01*
X783670D01*
Y446500D01*
X787500D01*
X787926Y446074D01*
Y441970D01*
X788530D01*
X790000Y440500D01*
Y430500D01*
X795000Y425500D01*
Y409000D01*
X794000Y408000D01*
X772500D01*
X771000Y409500D01*
Y429500D01*
G37*
G36*
G01X782020Y447219D02*
X779801Y445000D01*
X768500D01*
X768000Y445500D01*
Y451000D01*
X768500Y451500D01*
X775500D01*
X776000Y451000D01*
X776594D01*
X777233Y450360D01*
X777666D01*
Y450260D01*
X783770D01*
Y453864D01*
X783670D01*
Y454500D01*
X789878D01*
Y453864D01*
X789778D01*
Y450260D01*
X789878D01*
Y447974D01*
X789360D01*
Y448074D01*
X783988D01*
Y447974D01*
X782020D01*
Y447219D01*
G37*
G36*
G01X804500Y358500D02*
X812000Y351000D01*
Y342500D01*
X811000Y341500D01*
X800000D01*
X799500Y342000D01*
Y342801D01*
X799702Y343002D01*
Y351998D01*
X799500Y352199D01*
Y352500D01*
X798000Y354000D01*
X785000D01*
X784202Y354798D01*
Y357498D01*
X783000Y358699D01*
Y388000D01*
X782152Y388848D01*
Y389452D01*
X781548D01*
X779000Y392000D01*
Y403000D01*
X781000Y405000D01*
X802500D01*
X804500Y403000D01*
Y365202D01*
X804198D01*
Y361798D01*
X804500D01*
Y358500D01*
G37*
G36*
G01X801000Y441000D02*
X797500Y444500D01*
Y451500D01*
X802500Y456500D01*
X831500D01*
X832500Y455500D01*
Y441500D01*
X832000Y441000D01*
X807812D01*
X807771Y441020D01*
G03X807074Y441180I-698J-1442D01*
G01X805474D01*
G03X804777Y441020I1J-1602D01*
G01X804736Y441000D01*
X801000D01*
G37*
G36*
G01X820500Y367138D02*
Y367000D01*
X820631Y366869D01*
G03X822000Y366098I1369J830D01*
G01X823600D01*
G03X824661Y366500I0J1601D01*
G01X834000D01*
X836500Y369000D01*
Y379500D01*
X838500Y381500D01*
X849000D01*
X850000Y380500D01*
Y362500D01*
X846500Y359000D01*
X818517D01*
X810926Y366591D01*
Y401426D01*
X811500Y402000D01*
X818000D01*
X819000Y401000D01*
Y371500D01*
X820500Y370000D01*
Y369862D01*
X820489Y369830D01*
G03X820398Y369300I1511J-532D01*
G01Y367700D01*
G03X820489Y367170I1602J2D01*
G01X820500Y367138D01*
G37*
G36*
G01X827580Y405420D02*
X832000Y401000D01*
Y368500D01*
X831202Y367702D01*
X822298D01*
X821702Y368298D01*
Y370498D01*
X821000Y371199D01*
Y405000D01*
X821437Y405437D01*
X821538Y405420D01*
G03X821800Y405398I265J1580D01*
G01X823200D01*
G03X823730Y405489I-2J1602D01*
G01X823762Y405500D01*
X825138D01*
X825170Y405489D01*
G03X825700Y405398I532J1511D01*
G01X827300D01*
G03X827484Y405409I-3J1602D01*
G01X827580Y405420D01*
G37*
G36*
G01X940000Y154173D02*
X896827Y111000D01*
X850500D01*
X847500Y114000D01*
Y155500D01*
X907000Y215000D01*
X939000D01*
X940000Y214000D01*
Y154173D01*
G37*
G36*
G01X861514Y364000D02*
X853000D01*
X851500Y365500D01*
Y383638D01*
X851511Y383670D01*
G03X851602Y384200I-1511J532D01*
G01Y385800D01*
G03X851591Y385984I-1602J-3D01*
G01X851580Y386080D01*
X852500Y387000D01*
X858500D01*
X860500Y389000D01*
Y401500D01*
X861000Y402000D01*
X868324D01*
Y401884D01*
X870159Y400048D01*
X873000D01*
Y365500D01*
X871500Y364000D01*
X871126D01*
X871103Y364174D01*
G03X866537I-2283J-294D01*
G01X866514Y364000D01*
X866126D01*
X866103Y364174D01*
G03X861537I-2283J-294D01*
G01X861514Y364000D01*
G37*
G36*
G01X850000Y384000D02*
X849500Y383500D01*
X843500D01*
X843000Y384000D01*
Y388534D01*
X843558D01*
Y395136D01*
X840364D01*
X840333Y395167D01*
Y403480D01*
X840000D01*
Y407000D01*
X841000Y408000D01*
X842500D01*
X842520Y408020D01*
X843558D01*
Y413500D01*
X849500D01*
X849990Y413010D01*
Y408020D01*
X850980D01*
X851000Y408000D01*
X853000D01*
X853216Y407784D01*
Y404794D01*
X853500D01*
Y400920D01*
X853216D01*
Y395216D01*
X853136Y395136D01*
X849990D01*
Y388534D01*
X850000D01*
Y384000D01*
G37*
G36*
G01X859300Y433898D02*
G03X859830Y433989I-2J1602D01*
G01X859862Y434000D01*
X861238D01*
X861270Y433989D01*
G03X861800Y433898I532J1511D01*
G01X863200D01*
G03X863730Y433989I-2J1602D01*
G01X863762Y434000D01*
X865738D01*
X865770Y433989D01*
G03X866300Y433898I532J1511D01*
G01X867700D01*
G03X868230Y433989I-2J1602D01*
G01X868262Y434000D01*
X869500D01*
X870000Y433500D01*
Y426000D01*
X858500Y414500D01*
Y410500D01*
X857000Y409000D01*
X854376D01*
Y409180D01*
X853520D01*
X853498Y409202D01*
X851498D01*
X851234Y409465D01*
Y414622D01*
X851000D01*
Y416000D01*
X849000Y418000D01*
Y423500D01*
X855500Y430000D01*
Y432500D01*
X857000Y434000D01*
X857138D01*
X857170Y433989D01*
G03X857700Y433898I532J1511D01*
G01X859300D01*
G37*
G36*
G01X860000Y413000D02*
X863000Y416000D01*
X870000D01*
X870937Y415063D01*
X870920Y414962D01*
G03X870898Y414700I1580J-265D01*
G01Y413300D01*
G03X870989Y412770I1602J2D01*
G01X871000Y412738D01*
Y410862D01*
X870989Y410830D01*
G03X870898Y410300I1511J-532D01*
G01Y408700D01*
G03X870909Y408516I1602J3D01*
G01X870920Y408420D01*
X870500Y408000D01*
X868000D01*
X866000Y406000D01*
X855000D01*
X854500Y406500D01*
Y407500D01*
X854798Y407798D01*
X857498D01*
X857699Y408000D01*
X859000D01*
X860000Y409000D01*
Y413000D01*
G37*
G36*
G01X862500Y652000D02*
X856000D01*
X854000Y654000D01*
Y660000D01*
X855000Y661000D01*
X860500D01*
X861500Y660000D01*
Y657500D01*
X863500Y655500D01*
Y653000D01*
X862500Y652000D01*
G37*
G36*
G01X876500Y368500D02*
X874500Y370500D01*
Y400000D01*
X874548Y400048D01*
X882844D01*
X883295Y400500D01*
X884500D01*
X885500Y399500D01*
Y370500D01*
X883500Y368500D01*
X876500D01*
G37*
G36*
G01X901000Y65500D02*
X900000Y64500D01*
X894500D01*
X893500Y65500D01*
Y96500D01*
X894500Y97500D01*
X900000D01*
X901000Y96500D01*
Y65500D01*
G37*
G36*
G01X891500Y58500D02*
X890500Y59500D01*
Y62000D01*
X891500Y63000D01*
X901000D01*
X902500Y64500D01*
Y68500D01*
X903037Y69037D01*
X903156Y68994D01*
G03X903700Y68898I546J1506D01*
G01X905300D01*
G03X906658Y69650I0J1602D01*
G01X906670Y69670D01*
X907000Y70000D01*
Y72000D01*
X907500Y72500D01*
X909500D01*
X910000Y72000D01*
Y71762D01*
X909989Y71730D01*
G03X909898Y71200I1511J-532D01*
G01Y69800D01*
G03X909989Y69270I1602J2D01*
G01X910000Y69238D01*
Y67557D01*
G03Y64943I2250J-1307D01*
G01Y59000D01*
X909500Y58500D01*
X891500D01*
G37*
G36*
G01X917798Y49202D02*
X917500Y49500D01*
Y52500D01*
X917937Y52937D01*
X918038Y52920D01*
G03X918300Y52898I265J1580D01*
G01X919700D01*
G03X920230Y52989I-2J1602D01*
G01X920262Y53000D01*
X921000D01*
X922000Y54000D01*
Y58000D01*
X922500Y58500D01*
X928000D01*
X928500Y58000D01*
Y53199D01*
X928298Y52998D01*
Y49298D01*
X928202Y49202D01*
X917798D01*
G37*
G36*
G01X1010680Y283679D02*
X972501Y245500D01*
Y213501D01*
X966500Y207500D01*
X960000D01*
X958000Y209500D01*
Y245500D01*
X961714Y249214D01*
X961807Y249206D01*
G03X964295Y251679I193J2294D01*
G01X964288Y251771D01*
X964574Y252056D01*
X964590D01*
X1050676Y338143D01*
Y338176D01*
X1051000Y338500D01*
Y356983D01*
X1075726Y381709D01*
Y382226D01*
X1083000Y389500D01*
Y415129D01*
G03X1083684Y416149I-1240J1571D01*
G01X1083698Y416198D01*
X1083998Y416498D01*
X1084405D01*
X1088406Y420500D01*
X1096902D01*
G03X1097098I98J2600D01*
G01X1099000D01*
X1100000Y419500D01*
Y385000D01*
X1068000Y353000D01*
Y340999D01*
X1011821Y284820D01*
X1011793Y284805D01*
G03X1010695Y283707I1207J-2305D01*
G01X1010680Y283679D01*
G37*
G36*
G01X1003000Y67000D02*
X1002000Y66000D01*
X996000D01*
X994000Y68000D01*
Y80500D01*
X999500Y86000D01*
X1014500D01*
X1015500Y85000D01*
Y82500D01*
X1009000Y76000D01*
X1005000D01*
X1003000Y74000D01*
Y67000D01*
G37*
G36*
G01X1058796Y39759D02*
G03X1055376I-1710J3508D01*
G02X1055201Y39000I-175J-359D01*
G01X1053500D01*
X1048000Y44500D01*
X1013746D01*
G03X1012903Y45118I-1747J-1499D01*
G01X1012867Y45133D01*
X1011500Y46500D01*
Y63500D01*
X1013000Y65000D01*
X1067750D01*
X1068500Y65750D01*
X1068750D01*
X1071867Y68867D01*
X1071903Y68882D01*
G03X1073117Y70095I-903J2118D01*
G01X1073132Y70130D01*
X1073800Y70798D01*
X1073833D01*
X1074389Y71355D01*
X1074469Y71357D01*
G03X1076030Y72958I-41J1601D01*
G01Y74561D01*
G03X1075892Y75210I-1601J-1D01*
G01X1075836Y75336D01*
X1077000Y76500D01*
X1084398D01*
Y76498D01*
X1089102D01*
Y82101D01*
X1089500Y82500D01*
X1091298D01*
Y73798D01*
X1089826Y72326D01*
X1088795D01*
G03X1086884Y72011I2J-5965D01*
G01X1086853Y72000D01*
X1084500D01*
X1062000Y49500D01*
Y40500D01*
X1060500Y39000D01*
X1058971D01*
G02X1058796Y39759I0J400D01*
G37*
G36*
G01X1004202Y73202D02*
X1005000Y74000D01*
X1010000D01*
X1017000Y81000D01*
X1021500D01*
X1022500Y80000D01*
Y67000D01*
X1021702Y66202D01*
X1012502D01*
X1012301Y66000D01*
X1005500D01*
X1004202Y67298D01*
Y73202D01*
G37*
G36*
G01X1019000Y282862D02*
Y288000D01*
X1034000Y303000D01*
X1052500D01*
X1054000Y301500D01*
Y301461D01*
G03X1053598Y300400I1199J-1061D01*
G01Y298800D01*
G03X1053903Y297861I1602J1D01*
G03X1053622Y296956I1321J-906D01*
G01Y295356D01*
G03X1054000Y294323I1602J0D01*
G01Y293589D01*
G03X1053622Y292556I1224J-1033D01*
G01Y290956D01*
G03X1054000Y289923I1602J0D01*
G01Y288862D01*
X1053989Y288830D01*
G03X1053898Y288300I1511J-532D01*
G01Y286700D01*
G03X1053989Y286170I1602J2D01*
G01X1054000Y286138D01*
Y285551D01*
G03X1053398Y284300I999J-1251D01*
G01Y281700D01*
G03X1053923Y280515I1602J1D01*
G02X1053947Y280245I-135J-148D01*
G03X1053614Y279268I1269J-978D01*
G01Y276668D01*
G03X1054846Y275110I1601J0D01*
G01X1055000Y275073D01*
Y271000D01*
X1062000Y264000D01*
Y257500D01*
X1061386Y256886D01*
X1047702D01*
Y264402D01*
X1046426D01*
Y264920D01*
X1046491Y264980D01*
G03X1043509I-1491J1620D01*
G01X1043574Y264920D01*
Y264402D01*
X1042298D01*
Y259000D01*
X1027500D01*
X1019000Y267500D01*
Y276138D01*
X1019011Y276170D01*
G03X1019102Y276700I-1511J532D01*
G01Y278300D01*
G03X1019011Y278830I-1602J-2D01*
G01X1019000Y278862D01*
Y280138D01*
X1019011Y280170D01*
G03X1019102Y280700I-1511J532D01*
G01Y282300D01*
G03X1019011Y282830I-1602J-2D01*
G01X1019000Y282862D01*
G37*
G36*
G01X1011500Y274500D02*
X1010500Y275500D01*
Y281500D01*
X1012500Y283500D01*
X1017500D01*
X1017798Y283202D01*
Y275298D01*
X1017000Y274500D01*
X1011500D01*
G37*
G36*
G01X1014716Y882370D02*
G03X1013114Y880768I0J-1602D01*
G01Y879168D01*
G03X1013580Y878039I1601J0D01*
G02X1013586Y877762I-141J-142D01*
G03X1017886Y877039I1915J-1762D01*
G02X1018252Y877598I367J159D01*
G01X1022172D01*
Y877448D01*
X1027500D01*
Y869263D01*
X1027346Y869226D01*
G03X1026114Y867668I369J-1558D01*
G01Y866268D01*
G03X1026177Y865824I1602J1D01*
G01X1026210Y865710D01*
X1025170Y864670D01*
X1023916D01*
G03X1022772Y864189I0J-1601D01*
G02X1022222Y864169I-286J280D01*
G03X1021728Y859924I-1722J-1951D01*
G02X1022317Y859551I189J-352D01*
G03X1022314Y859468I1598J-99D01*
G01Y857868D01*
G03X1022479Y857160I1601J0D01*
G01X1022500Y857118D01*
Y826500D01*
X1029500Y819500D01*
X1056000D01*
X1057500Y821000D01*
Y838000D01*
X1056500Y839000D01*
Y843140D01*
X1056511Y843172D01*
G03X1056602Y843700I-1510J532D01*
G01Y845300D01*
G03X1056511Y845828I-1601J-4D01*
G01X1056500Y845860D01*
Y879500D01*
X1055000Y881000D01*
X1048260D01*
Y881252D01*
X1043348D01*
X1042900Y881700D01*
Y887500D01*
X1043084Y887684D01*
X1048260D01*
Y888000D01*
X1049000D01*
X1051000Y890000D01*
Y899000D01*
X1050618Y899382D01*
X1050675Y899508D01*
G03X1050818Y900168I-1459J662D01*
G01Y901768D01*
G03X1050500Y902725I-1602J-1D01*
G01Y917500D01*
X1051000Y918000D01*
X1059500D01*
X1060000Y917500D01*
Y889500D01*
X1085000Y864500D01*
X1093500D01*
X1093867Y864133D01*
G03X1093866Y864084I1601J-57D01*
G01Y862484D01*
G03X1093985Y861879I1602J1D01*
G01X1094000Y861842D01*
Y860861D01*
X1093973Y860814D01*
G03X1094000Y858140I2245J-1314D01*
G01Y845500D01*
X1092500Y844000D01*
X1081500D01*
X1076500Y839000D01*
Y825000D01*
X1070500Y819000D01*
Y770000D01*
X1067000Y766500D01*
Y760544D01*
G02X1066588Y760145I-400J1D01*
G03X1066538Y760146I-57J-1601D01*
G01X1065138D01*
G03X1063698Y759246I0J-1602D01*
G01X1059693D01*
X1054898Y754451D01*
Y749787D01*
G03X1057802I1452J-1787D01*
G01Y753249D01*
X1060895Y756342D01*
X1063751D01*
G03X1065138Y755542I1387J802D01*
G01X1066538D01*
G03X1066588Y755543I-7J1602D01*
G02X1067000Y755144I12J-400D01*
G01Y752500D01*
X1066681Y752181D01*
X1066583Y752193D01*
G03X1066388Y752206I-204J-1588D01*
G01X1064988D01*
G03X1063386Y750604I0J-1602D01*
G01Y749204D01*
G03X1063399Y749010I1601J10D01*
G01Y749009D01*
X1063411Y748911D01*
X1054500Y740000D01*
X1025859D01*
G03X1023095Y740135I-1472J-1770D01*
G01X1022958Y740042D01*
X1006534Y756466D01*
Y899034D01*
X1007000Y899500D01*
X1012500D01*
X1013000Y899000D01*
Y895220D01*
X1012993Y895194D01*
G03Y893806I2507J-694D01*
G01X1013000Y893780D01*
Y891000D01*
X1016000Y888000D01*
X1022172D01*
Y887684D01*
X1027316D01*
X1027500Y887500D01*
Y881252D01*
X1022172D01*
Y881036D01*
X1021995Y881002D01*
X1017908D01*
X1017870Y881154D01*
G03X1016316Y882370I-1554J-385D01*
G01X1014716D01*
G37*
G36*
G01X1068000Y67500D02*
X1067500Y67000D01*
X1030000D01*
X1028000Y69000D01*
Y113500D01*
X1029000Y114500D01*
X1039500D01*
X1040500Y113500D01*
Y103000D01*
X1041500Y102000D01*
Y75500D01*
X1043500Y73500D01*
X1067500D01*
X1068000Y73000D01*
Y67500D01*
G37*
G36*
G01X1039000Y246500D02*
X1027000D01*
X1025500Y248000D01*
Y255500D01*
X1026500Y256500D01*
X1039500D01*
X1040000Y256000D01*
Y247500D01*
X1039000Y246500D01*
G37*
G36*
G01X1056000Y821500D02*
X1055500Y821000D01*
X1032000D01*
X1031000Y822000D01*
Y833500D01*
X1032000Y834500D01*
X1055500D01*
X1056000Y834000D01*
Y821500D01*
G37*
G36*
G01X1023702Y839298D02*
Y859667D01*
G02X1023903Y859867I200J0D01*
G03X1023916Y859866I129J1592D01*
G01X1025516D01*
G03X1026627Y860315I-1J1602D01*
G02X1026905I139J-144D01*
G03X1028016Y859866I1112J1153D01*
G01X1029416D01*
G03X1030692Y860500I0J1601D01*
G01X1031500D01*
X1034500Y863500D01*
Y876500D01*
X1034866Y876866D01*
X1042818D01*
Y879734D01*
X1043064Y879837D01*
X1043102Y879798D01*
X1054202D01*
X1055000Y879000D01*
Y838500D01*
X1054500Y838000D01*
X1025000D01*
X1023702Y839298D01*
G37*
G36*
G01X1048682Y889682D02*
X1048202Y889202D01*
X1043298D01*
X1042818Y889682D01*
Y892070D01*
X1034500D01*
Y900121D01*
G03Y902879I-1843J1379D01*
G01Y906831D01*
X1034502Y906845D01*
G03X1034518Y907068I-1586J226D01*
G01Y908468D01*
G03X1034502Y908691I-1602J-3D01*
G01X1034500Y908705D01*
Y910231D01*
X1034502Y910245D01*
G03X1034518Y910468I-1586J226D01*
G01Y911868D01*
G03X1034502Y912091I-1602J-3D01*
G01X1034500Y912105D01*
Y921408D01*
G03Y921592I-2300J92D01*
G01Y926000D01*
X1035500Y927000D01*
X1047500D01*
X1048500Y926000D01*
Y903500D01*
X1049298Y902702D01*
Y899002D01*
X1049798Y898502D01*
Y890808D01*
G03X1048696Y889709I1202J-2308D01*
G01X1048682Y889682D01*
G37*
G36*
G01X1093339Y68161D02*
X1093500Y68000D01*
Y58500D01*
X1103798Y48202D01*
Y23799D01*
X1102500Y22500D01*
X1040000D01*
X1036500Y26000D01*
Y37500D01*
X1040000Y41000D01*
X1049500D01*
X1053500Y37000D01*
X1081500D01*
X1082500Y38000D01*
Y39335D01*
G02X1083062Y39701I400J0D01*
G03Y46833I1584J3566D01*
G02X1082500Y47199I-162J366D01*
G01Y62000D01*
X1088495Y67995D01*
G02X1088800Y68024I309J-1633D01*
G01X1092310D01*
G03X1093229Y68134I3J3866D01*
G01X1093339Y68161D01*
G37*
G36*
G01X1045000Y76500D02*
Y101000D01*
X1042000Y104000D01*
Y115500D01*
X1047000Y120500D01*
X1072000D01*
X1074000Y118500D01*
Y78500D01*
X1070000Y74500D01*
X1068199D01*
X1067998Y74702D01*
X1046798D01*
X1045000Y76500D01*
G37*
G36*
G01X1051500Y123000D02*
X1049000Y125500D01*
Y130094D01*
X1049202Y130295D01*
Y141214D01*
X1049000Y141415D01*
Y142500D01*
X1048700Y142800D01*
Y145641D01*
G03X1048164Y146881I-1702J0D01*
G01X1048100Y146941D01*
Y147532D01*
X1061120D01*
Y148000D01*
X1061500D01*
X1065000Y144500D01*
X1068500D01*
X1069500Y143500D01*
Y140000D01*
X1070631Y138869D01*
G03X1071150Y138342I1370J830D01*
G01X1071170Y138330D01*
X1073500Y136000D01*
Y125000D01*
X1071500Y123000D01*
X1051500D01*
G37*
G36*
G01X1089500Y146000D02*
X1065500D01*
X1062500Y149000D01*
X1062199D01*
X1061998Y149202D01*
X1048002D01*
X1047843Y149042D01*
X1047166D01*
Y149000D01*
X1038000D01*
X1037000Y150000D01*
Y160500D01*
X1038500Y162000D01*
X1047166D01*
Y161525D01*
X1060475D01*
X1061000Y161000D01*
X1089500D01*
X1090500Y160000D01*
Y147000D01*
X1089500Y146000D01*
G37*
G36*
G01X1048800Y164926D02*
Y167698D01*
X1053946D01*
X1056248Y170000D01*
X1061500D01*
X1063000Y171500D01*
Y172590D01*
X1063016Y172628D01*
G03Y174440I-2116J906D01*
G01X1063000Y174478D01*
Y175500D01*
X1064000Y176500D01*
X1089500D01*
X1090500Y175500D01*
Y163500D01*
X1089500Y162500D01*
X1061199D01*
X1061120Y162580D01*
Y163036D01*
X1060664D01*
X1060498Y163202D01*
X1048100D01*
Y163499D01*
X1048170Y163558D01*
G03X1048800Y164926I-1171J1368D01*
G37*
G36*
G01X1084500Y234500D02*
X1084000Y234000D01*
X1046500D01*
X1046000Y234500D01*
Y254000D01*
X1047000Y255000D01*
X1064500D01*
X1071500Y248000D01*
X1083500D01*
X1084500Y247000D01*
Y234500D01*
G37*
G36*
G01X1345500Y691500D02*
X1357500Y679500D01*
Y666500D01*
X1356000Y665000D01*
X1353000D01*
X1344566Y673434D01*
X1344555Y673494D01*
G03X1342494Y675555I-2555J-494D01*
G01X1342434Y675566D01*
X1338894Y679106D01*
Y680123D01*
X1331000Y688017D01*
Y914000D01*
X1317500Y927500D01*
X1086000D01*
X1081000Y922500D01*
Y891500D01*
X1079000Y889500D01*
X1064000D01*
X1062500Y891000D01*
Y918500D01*
X1061000Y920000D01*
X1050500D01*
X1050000Y920500D01*
Y936500D01*
X1050500Y937000D01*
X1072500D01*
X1075372Y939872D01*
X1075462D01*
X1075611Y939724D01*
X1078389D01*
X1080120Y941454D01*
X1327478D01*
X1345500Y923433D01*
Y792358D01*
G02X1344836Y792058I-400J0D01*
G03Y785142I-3036J-3458D01*
G02X1345500Y784842I264J-300D01*
G01Y691500D01*
G37*
G36*
G01X1166000Y413248D02*
Y399177D01*
G02X1165363Y398855I-400J0D01*
G03Y395145I-1363J-1855D01*
G02X1166000Y394823I237J-322D01*
G01Y391390D01*
G03Y389110I2000J-1140D01*
G01Y386040D01*
X1142044Y362084D01*
X1141995Y362070D01*
G03X1140430Y360505I645J-2210D01*
G01X1140416Y360456D01*
X1139225Y359265D01*
Y358462D01*
X1139224Y358461D01*
Y313724D01*
X1085500Y260000D01*
Y259000D01*
X1082500Y256000D01*
X1066000D01*
X1064000Y258000D01*
Y330500D01*
X1070500Y337000D01*
Y352000D01*
X1110000Y391500D01*
Y511000D01*
X1112500Y513500D01*
X1158500D01*
X1166000Y506000D01*
Y417752D01*
X1165856Y417710D01*
G03Y413290I644J-2210D01*
G01X1166000Y413248D01*
G37*
G36*
G01X1057500Y272500D02*
X1056500Y273500D01*
Y284500D01*
X1056202Y284798D01*
Y284998D01*
X1055202Y285998D01*
Y301998D01*
X1054500Y302699D01*
Y304000D01*
X1056500Y306000D01*
X1061500D01*
X1062000Y305500D01*
Y273500D01*
X1061000Y272500D01*
X1057500D01*
G37*
G36*
G01X1079000Y178500D02*
X1078452Y179048D01*
Y184252D01*
X1078000D01*
Y194000D01*
X1079500Y195500D01*
X1088500D01*
X1090000Y194000D01*
Y180000D01*
X1088500Y178500D01*
X1079000D01*
G37*
G36*
G01X1077500Y424000D02*
X1076500Y425000D01*
Y435000D01*
X1077500Y436000D01*
X1090000D01*
X1091000Y435000D01*
Y425000D01*
X1090002Y424002D01*
X1087095D01*
X1087094Y424000D01*
X1077500D01*
G37*
G36*
G01X1101298Y870702D02*
G03X1101202Y870798I-1675J-1579D01*
G01X1097500Y874500D01*
X1076699D01*
X1072500Y878699D01*
Y884500D01*
X1074000Y886000D01*
X1097711D01*
G03X1098668Y885682I958J1284D01*
G01X1100268D01*
G03X1101225Y886000I-1J1602D01*
G01X1102908D01*
G03X1103092I92J2300D01*
G01X1110000D01*
X1112000Y884000D01*
Y878500D01*
X1111500Y878000D01*
X1109500D01*
X1109386Y877886D01*
X1108866D01*
Y869866D01*
X1108500Y869500D01*
X1102500D01*
X1101298Y870702D01*
G37*
G36*
G01X1288500Y741000D02*
X1268000Y720500D01*
X1248000D01*
X1246000Y722500D01*
Y729500D01*
X1248500Y732000D01*
Y736836D01*
G03Y740164I-2000J1664D01*
G01Y759693D01*
X1248667Y759721D01*
G03X1249984Y761065I-267J1579D01*
G01X1249994Y761130D01*
X1251202Y762338D01*
Y763949D01*
G03X1250932Y767302I-1702J1550D01*
G02X1250898Y767898I249J313D01*
G01X1259698Y776698D01*
X1260000D01*
G03X1261602Y778300I0J1602D01*
G01Y779700D01*
G03X1261528Y780181I-1602J0D01*
G02X1261927Y780700I381J120D01*
G03X1262000Y780698I80J1600D01*
G01X1263400D01*
G03X1263926Y780787I-1J1602D01*
G01X1263958Y780798D01*
X1266827D01*
X1266854Y780790D01*
G03Y785210I646J2210D01*
G01X1266827Y785202D01*
X1263958D01*
X1263926Y785213D01*
G03X1263400Y785302I-527J-1513D01*
G01X1262000D01*
G03X1261520Y785228I1J-1602D01*
G02X1261000Y785609I-120J381D01*
G01Y802500D01*
X1267000Y808500D01*
Y832898D01*
X1268559D01*
X1268597Y832882D01*
G03X1270606Y837019I903J2118D01*
G01X1270581Y837033D01*
X1270312Y837302D01*
X1269546D01*
G03X1269454I-46J-2302D01*
G01X1267000D01*
Y838469D01*
G03X1267302Y839525I-1700J1057D01*
G01Y840925D01*
G03X1267000Y841981I-2002J-1D01*
G01Y845000D01*
X1265500Y846500D01*
X1258856D01*
G03X1257800Y846802I-1057J-1700D01*
G01X1254900D01*
G03X1253844Y846500I1J-2002D01*
G01X1244000D01*
X1240500Y850000D01*
Y872000D01*
X1205000Y907500D01*
X1204017D01*
X1203545Y907972D01*
X1099230D01*
G03X1095328Y907500I-1807J-1426D01*
G01X1094641D01*
X1094596Y907524D01*
G03X1091476Y904404I-1096J-2024D01*
G01X1091500Y904359D01*
Y903500D01*
X1092500Y902500D01*
X1167000D01*
X1169500Y900000D01*
Y882500D01*
X1168500Y881500D01*
X1134000D01*
X1132000Y883500D01*
X1121000D01*
X1120829Y883328D01*
X1119684D01*
Y878184D01*
X1119500Y878000D01*
X1113500D01*
X1113252Y878248D01*
Y883328D01*
X1113202D01*
Y884498D01*
X1113000Y884699D01*
Y885000D01*
X1111000Y887000D01*
X1110699D01*
X1110498Y887202D01*
X1083298D01*
X1082500Y888000D01*
Y921000D01*
X1087500Y926000D01*
X1296500D01*
X1299500Y923000D01*
Y877000D01*
X1288500Y866000D01*
Y741000D01*
G37*
G36*
G01X1113500Y852500D02*
X1113052Y852948D01*
Y857240D01*
X1113252D01*
Y862252D01*
X1113500Y862500D01*
X1119500D01*
X1119684Y862316D01*
Y857240D01*
X1119884D01*
Y852884D01*
X1119500Y852500D01*
X1113500D01*
G37*
G36*
G01X1177039Y229000D02*
X1178315D01*
X1178347Y228989D01*
G03X1178877Y228898I532J1511D01*
G01X1180477D01*
G03X1181007Y228989I-2J1602D01*
G01X1181039Y229000D01*
X1181815D01*
X1181847Y228989D01*
G03X1182377Y228898I532J1511D01*
G01X1183977D01*
G03X1184401Y228956I-3J1602D01*
G01X1184513Y228987D01*
X1185500Y228000D01*
Y225500D01*
X1186950Y224050D01*
X1191150D01*
X1191200Y224100D01*
X1194178D01*
X1194204Y224093D01*
G03X1195596I696J2507D01*
G01X1195622Y224100D01*
X1198378D01*
X1198404Y224093D01*
G03X1199381Y224013I697J2507D01*
G01X1199476Y224024D01*
X1207000Y216500D01*
Y213640D01*
G03X1206976Y211404I2000J-1140D01*
G01X1207000Y211359D01*
Y210500D01*
X1210000Y207500D01*
X1210004D01*
Y207248D01*
X1219252D01*
X1219304Y207196D01*
Y205352D01*
X1208738D01*
X1207887Y204500D01*
X1203000D01*
X1202000Y205500D01*
Y214000D01*
X1198000Y218000D01*
X1126000D01*
X1125000Y219000D01*
Y230500D01*
X1126000Y231500D01*
X1158500D01*
X1161000Y229000D01*
X1173315D01*
X1173347Y228989D01*
G03X1173877Y228898I532J1511D01*
G01X1176477D01*
G03X1177007Y228989I-2J1602D01*
G01X1177039Y229000D01*
G37*
G36*
G01X1133000Y748000D02*
X1131500Y749500D01*
Y753000D01*
X1133443Y754943D01*
X1133504Y755000D01*
X1135991D01*
G03X1136948Y754682I958J1284D01*
G01X1138548D01*
G03X1139505Y755000I-1J1602D01*
G01X1141679D01*
G03X1142518Y754762I840J1364D01*
G01X1143918D01*
G03X1144757Y755000I-1J1602D01*
G01X1148391D01*
G03X1149458Y754592I1068J1194D01*
G01X1149770D01*
X1149789Y754589D01*
G03X1150727I469J2355D01*
G01X1150746Y754592D01*
X1151058D01*
G03X1152125Y755000I-1J1602D01*
G01X1155011D01*
G03X1155968Y754682I958J1284D01*
G01X1156280D01*
X1156299Y754679D01*
G03X1157237I469J2355D01*
G01X1157256Y754682D01*
X1157568D01*
G03X1158525Y755000I-1J1602D01*
G01X1162339D01*
G03X1163400Y754598I1061J1199D01*
G01X1163712D01*
X1163731Y754595D01*
G03X1164669I469J2355D01*
G01X1164688Y754598D01*
X1165000D01*
G03X1165262Y754620I-3J1602D01*
G01X1165363Y754637D01*
X1165500Y754500D01*
Y751000D01*
X1165000Y750500D01*
X1157500D01*
X1155000Y748000D01*
X1133000D01*
G37*
G36*
G01X1152500Y834500D02*
X1146500Y840500D01*
Y860000D01*
X1145500Y861000D01*
X1142102D01*
Y862800D01*
G03X1140500Y864402I-1602J0D01*
G01X1138900D01*
G03X1137757Y863922I0J-1601D01*
G02X1137211Y863899I-285J280D01*
G03X1136168Y864286I-1044J-1215D01*
G01X1135714D01*
X1132715Y867285D01*
X1132740Y867392D01*
G03X1130942Y869190I-1465J333D01*
G01X1130835Y869165D01*
X1130500Y869500D01*
X1125000D01*
X1124070Y870430D01*
Y877886D01*
X1121202D01*
Y882002D01*
X1121498Y882298D01*
X1131502D01*
X1133502Y880298D01*
X1133702D01*
X1134000Y880000D01*
X1167500D01*
X1169500Y878000D01*
Y865500D01*
X1163632Y859632D01*
G03X1162476Y856404I868J-2132D01*
G01X1162500Y856359D01*
Y856000D01*
X1167000Y851500D01*
X1181500D01*
X1185000Y848000D01*
Y835500D01*
X1184000Y834500D01*
X1152500D01*
G37*
G36*
G01X1157000Y255500D02*
X1160262Y252238D01*
X1160277Y252199D01*
G03X1161768Y251182I1491J584D01*
G01X1163168D01*
G03X1164125Y251500I-1J1602D01*
G01X1165500D01*
X1167000Y250000D01*
Y240000D01*
X1166500Y239500D01*
X1145000D01*
X1144000Y240500D01*
Y255000D01*
X1144500Y255500D01*
X1157000D01*
G37*
G36*
G01X1150002Y605388D02*
X1150912Y606298D01*
X1151827D01*
X1151854Y606290D01*
G03X1153640Y606500I646J2210D01*
G01X1163500D01*
X1164000Y606000D01*
Y602124D01*
X1155482D01*
Y601098D01*
X1154581D01*
X1154532Y601049D01*
X1154430Y601066D01*
G03X1151560Y599403I-430J-2566D01*
G02X1151028Y599173I-375J138D01*
G03X1150400Y599302I-630J-1473D01*
G01X1149000D01*
G03X1147398Y597700I0J-1602D01*
G01Y596300D01*
G03X1148113Y594967I1602J1D01*
G02X1148168Y594689I-111J-166D01*
G03X1147898Y593800I1332J-890D01*
G01Y591200D01*
G03X1149500Y589598I1602J0D01*
G01X1152100D01*
G03X1153424Y590298I0J1602D01*
G01X1153912D01*
X1156081Y592467D01*
X1156106Y592481D01*
G03X1156241Y596439I-1106J2019D01*
G02X1156130Y597005I216J336D01*
G03X1156266Y597220I-2129J1497D01*
G01X1164000D01*
Y584500D01*
X1163000Y583500D01*
X1151529D01*
G03X1150634Y583774I-896J-1328D01*
G01X1149234D01*
G03X1148339Y583500I1J-1602D01*
G01X1143500D01*
X1142962Y584038D01*
X1143048Y584173D01*
G03X1142500Y587227I-1948J1227D01*
G01Y587859D01*
X1142524Y587904D01*
G03X1142500Y590140I-2024J1096D01*
G01Y599500D01*
X1145000Y602000D01*
X1145022D01*
G03X1145800Y601798I779J1400D01*
G01X1148400D01*
G03X1150002Y603400I0J1602D01*
G01Y605388D01*
G37*
G36*
G01X1169745Y680697D02*
X1170284Y680158D01*
X1170620D01*
Y677630D01*
X1170020Y677030D01*
X1162192D01*
X1162139Y677148D01*
G03X1159397I-1371J-613D01*
G01X1159344Y677030D01*
X1155270D01*
X1153940Y678360D01*
X1152750D01*
X1152710Y678378D01*
G03X1151470I-620J-1368D01*
G01X1151430Y678360D01*
X1140850D01*
X1140340Y678870D01*
Y681680D01*
X1141060Y682400D01*
Y691173D01*
G03Y692975I-1202J901D01*
G01Y701998D01*
X1143835D01*
X1147946Y706110D01*
X1169689D01*
X1169716Y705941D01*
G03X1170512Y704835I1484J229D01*
G01X1170620Y704779D01*
Y703578D01*
X1170616Y703557D01*
G03X1170590Y703308I1175J-249D01*
G01Y699651D01*
X1170620Y699621D01*
Y697280D01*
X1170616Y697259D01*
G03Y696757I1175J-251D01*
G01X1170620Y696736D01*
Y694131D01*
X1170616Y694110D01*
G03Y693608I1175J-251D01*
G01X1170620Y693587D01*
Y690979D01*
X1170616Y690958D01*
G03Y690460I1175J-249D01*
G01X1170620Y690439D01*
Y687830D01*
X1170616Y687809D01*
G03Y687311I1175J-249D01*
G01X1170620Y687290D01*
Y684797D01*
X1169495Y683672D01*
X1169441Y683658D01*
G03X1169672Y680703I359J-1458D01*
G01X1169745Y680697D01*
G37*
G36*
G01X1189888Y235276D02*
X1190465Y234698D01*
X1190731D01*
X1190756Y234674D01*
X1201500D01*
Y233000D01*
X1201013Y232513D01*
X1200901Y232544D01*
G03X1200477Y232602I-427J-1544D01*
G01X1198877D01*
G03X1198347Y232511I2J-1602D01*
G01X1198315Y232500D01*
X1197039D01*
X1197007Y232511D01*
G03X1196477Y232602I-532J-1511D01*
G01X1194877D01*
G03X1194347Y232511I2J-1602D01*
G01X1194315Y232500D01*
X1193500D01*
X1192500Y231500D01*
X1188500D01*
X1187000Y230000D01*
X1185199D01*
X1184998Y230202D01*
X1165298D01*
X1164500Y231000D01*
Y233000D01*
X1165000Y233500D01*
X1186000D01*
X1187555Y235055D01*
X1187672Y235015D01*
G03X1189756Y235203I828J2467D01*
G01X1189888Y235276D01*
G37*
G36*
G01X1182500Y814000D02*
X1177000D01*
X1173500Y817500D01*
Y826500D01*
X1175500Y828500D01*
X1184000D01*
X1184500Y828000D01*
Y816000D01*
X1182500Y814000D01*
G37*
G36*
G01X1208202Y216798D02*
Y216998D01*
X1199898Y225302D01*
X1190702D01*
X1190652Y225252D01*
X1188948D01*
X1188500Y225700D01*
Y229500D01*
X1189000Y230000D01*
X1192500D01*
X1192798Y230298D01*
X1192998D01*
X1193998Y231298D01*
X1201498D01*
X1201699Y231500D01*
X1203500D01*
X1209000Y226000D01*
X1219000D01*
X1219304Y225696D01*
Y215000D01*
X1210000D01*
X1208202Y216798D01*
G37*
G36*
G01X1253286Y508714D02*
X1253500Y508500D01*
X1317500D01*
X1337000Y489000D01*
X1361000D01*
X1362000Y488000D01*
Y473500D01*
X1360500Y472000D01*
X1345000D01*
X1340500Y467500D01*
X1299500D01*
X1299000Y468000D01*
Y475500D01*
X1293000Y481500D01*
X1268000D01*
X1266000Y479500D01*
Y473980D01*
G03X1265566Y472884I1167J-1096D01*
G01Y471066D01*
X1265500Y471000D01*
X1262500D01*
X1262000Y471500D01*
Y479500D01*
X1260000Y481500D01*
X1247000D01*
X1240000Y474500D01*
X1188517D01*
X1185000Y478017D01*
Y495500D01*
X1187226Y497726D01*
X1187355Y497664D01*
G03X1190164Y498000I1145J2336D01*
G01X1228500D01*
X1242000Y511500D01*
X1250500D01*
X1250714Y511286D01*
X1250706Y511193D01*
G03X1253193Y508706I2294J-193D01*
G01X1253286Y508714D01*
G37*
G36*
G01X1207549Y199838D02*
X1209588Y197798D01*
X1210702D01*
X1211000Y197500D01*
X1219000D01*
X1219304Y197196D01*
Y189550D01*
X1219500D01*
Y188000D01*
X1218661Y187161D01*
X1212838D01*
X1212677Y187000D01*
X1203000D01*
X1202000Y188000D01*
Y199338D01*
X1202500Y199838D01*
X1207549D01*
G37*
G36*
G01X1210199Y209000D02*
X1208202Y210998D01*
Y213702D01*
X1208500Y214000D01*
X1209301D01*
X1209502Y213798D01*
X1210004D01*
Y213546D01*
X1219304D01*
Y209304D01*
X1219000Y209000D01*
X1210199D01*
G37*
G36*
G01X1239812Y205812D02*
X1242000Y208000D01*
Y211000D01*
X1243000Y212000D01*
X1250500D01*
X1251000Y211500D01*
Y206862D01*
X1250989Y206830D01*
G03X1250898Y206300I1511J-532D01*
G01Y204700D01*
G03X1250989Y204170I1602J2D01*
G01X1251000Y204138D01*
Y202862D01*
X1250989Y202830D01*
G03X1250898Y202300I1511J-532D01*
G01Y200700D01*
G03X1250989Y200170I1602J2D01*
G01X1251000Y200138D01*
Y198862D01*
X1250989Y198830D01*
G03X1250898Y198300I1511J-532D01*
G01Y196700D01*
G03X1250989Y196170I1602J2D01*
G01X1251000Y196138D01*
Y163500D01*
X1250000Y162500D01*
X1236500D01*
X1232500Y166500D01*
Y188350D01*
X1238175D01*
X1238209Y188338D01*
G03X1238549Y192757I791J2162D01*
G01X1238530Y192754D01*
X1229246D01*
X1228728Y193272D01*
Y200728D01*
X1229000Y201000D01*
X1235000D01*
X1235648Y201648D01*
X1239272D01*
X1240562Y202938D01*
G03Y205062I-1062J1062D01*
G01X1239812Y205812D01*
G37*
G36*
G01X1243720Y229500D02*
X1246000Y227220D01*
Y219000D01*
X1245000Y218000D01*
X1230000D01*
X1228728Y219272D01*
Y228228D01*
X1229794Y229294D01*
X1238028D01*
Y229500D01*
X1243720D01*
G37*
G36*
G01X1252202Y211702D02*
X1253000Y212500D01*
X1265500D01*
X1266500Y211500D01*
Y167000D01*
X1264500Y165000D01*
X1253000D01*
X1252202Y165798D01*
Y211702D01*
G37*
G36*
G01X1312500Y432500D02*
X1311000Y431000D01*
X1303500D01*
X1302000Y432500D01*
Y437500D01*
X1301620Y437880D01*
Y438736D01*
X1300764D01*
X1300500Y439000D01*
X1293000D01*
X1292000Y438000D01*
X1281113D01*
Y438043D01*
X1271603D01*
Y438042D01*
X1267666D01*
Y438000D01*
X1261426D01*
Y438042D01*
X1258458D01*
X1257500Y439000D01*
Y449500D01*
X1259000Y451000D01*
X1267666D01*
Y450526D01*
X1271603D01*
Y450525D01*
X1280975D01*
X1282500Y449000D01*
X1310000D01*
X1312500Y446500D01*
Y432500D01*
G37*
G36*
G01X1267000Y634000D02*
X1266500Y633500D01*
X1253000D01*
X1252563Y633937D01*
X1252580Y634038D01*
G03X1252602Y634300I-1580J265D01*
G01Y635700D01*
G03X1252511Y636230I-1602J-2D01*
G01X1252500Y636262D01*
Y637738D01*
X1252511Y637770D01*
G03X1252602Y638300I-1511J532D01*
G01Y639700D01*
G03X1252511Y640230I-1602J-2D01*
G01X1252500Y640262D01*
Y641738D01*
X1252511Y641770D01*
G03X1252602Y642300I-1511J532D01*
G01Y643700D01*
G03X1252511Y644230I-1602J-2D01*
G01X1252500Y644262D01*
Y645738D01*
X1252511Y645770D01*
G03X1252602Y646300I-1511J532D01*
G01Y647700D01*
G03X1252580Y647962I-1602J-3D01*
G01X1252563Y648063D01*
X1253198Y648698D01*
X1254400D01*
G03X1255335Y649000I-1J1602D01*
G01X1256165D01*
G03X1257100Y648698I936J1300D01*
G01X1258500D01*
G03X1260102Y650300I0J1602D01*
G01Y651084D01*
X1260416Y651398D01*
X1262012D01*
X1262284Y651126D01*
X1263653D01*
G03X1266437Y650397I1847J1374D01*
G02X1267000Y650032I163J-365D01*
G01Y634000D01*
G37*
G36*
G01X1264254Y655950D02*
X1264002Y656202D01*
X1260816D01*
X1260102Y656916D01*
Y657700D01*
G03X1259718Y658740I-1602J-1D01*
G02Y659260I304J260D01*
G03X1260102Y660300I-1218J1041D01*
G01Y661700D01*
G03X1260069Y662020I-1602J-3D01*
G02X1260461Y662500I392J80D01*
G01X1266000D01*
X1266500Y662000D01*
Y656000D01*
X1266450Y655950D01*
X1264254D01*
G37*
G36*
G01X1269691Y346203D02*
G03Y351829I2986J2813D01*
G02X1269000Y352103I-291J274D01*
G01Y382500D01*
X1271500Y385000D01*
X1288000D01*
X1289500Y383500D01*
Y342500D01*
X1286500Y339500D01*
X1282246D01*
G03X1278754I-1746J-1500D01*
G01X1271500D01*
X1269000Y342000D01*
Y345929D01*
G02X1269691Y346203I400J0D01*
G37*
G36*
G01X1275500Y406500D02*
X1268500Y413500D01*
Y421344D01*
X1269200Y422044D01*
Y434641D01*
G03X1268783Y435757I-1702J0D01*
G02X1268802Y436302I302J262D01*
G01X1269032Y436532D01*
X1281620D01*
Y436798D01*
X1287702D01*
X1288000Y436500D01*
Y432500D01*
X1296500Y424000D01*
X1307000D01*
X1309500Y421500D01*
Y408000D01*
X1308000Y406500D01*
X1281723D01*
G03X1279277I-1223J-1950D01*
G01X1275500D01*
G37*
G36*
G01X1271351Y464398D02*
X1271827D01*
X1271854Y464390D01*
G03X1274681Y465864I646J2210D01*
G01X1274727Y466000D01*
X1305500D01*
X1306500Y465000D01*
Y452000D01*
X1305000Y450500D01*
X1284000D01*
X1282000Y452500D01*
Y457500D01*
X1281500Y458000D01*
X1269300D01*
Y462300D01*
X1270121Y463121D01*
X1270173Y463135D01*
G03X1271310Y464252I-405J1549D01*
G01X1271351Y464398D01*
G37*
G36*
G01X1274619Y467500D02*
G03X1273500Y468673I-2118J-901D01*
G01Y477000D01*
X1274500Y478000D01*
X1287500D01*
X1288500Y477000D01*
Y468000D01*
X1288000Y467500D01*
X1274619D01*
G37*
G36*
G01X1274362Y708000D02*
X1274330Y708011D01*
G03X1273800Y708102I-532J-1511D01*
G01X1272200D01*
G03X1272016Y708091I3J-1602D01*
G01X1271920Y708080D01*
X1271500Y708500D01*
Y717000D01*
X1271920Y717420D01*
X1272016Y717409D01*
G03X1272200Y717398I187J1591D01*
G01X1273800D01*
G03X1274330Y717489I-2J1602D01*
G01X1274362Y717500D01*
X1275738D01*
X1275770Y717489D01*
G03X1276300Y717398I532J1511D01*
G01X1277700D01*
G03X1277962Y717420I-3J1602D01*
G01X1278063Y717437D01*
X1278500Y717000D01*
Y708500D01*
X1278063Y708063D01*
X1277962Y708080D01*
G03X1277700Y708102I-265J-1580D01*
G01X1276300D01*
G03X1275770Y708011I2J-1602D01*
G01X1275738Y708000D01*
X1274362D01*
G37*
G36*
G01X1325937Y331063D02*
X1325000Y332000D01*
Y336500D01*
X1324786Y336714D01*
X1324794Y336807D01*
G03X1320754Y338500I-2294J193D01*
G01X1308309D01*
X1308295Y338684D01*
G03X1303705I-2295J-184D01*
G01X1303691Y338500D01*
X1294500D01*
X1291500Y341500D01*
Y402500D01*
X1292000Y403000D01*
X1294500D01*
X1297500Y400000D01*
X1307500D01*
X1308500Y399000D01*
Y385500D01*
X1305500Y382500D01*
Y353500D01*
X1307500Y351500D01*
X1346000D01*
X1350000Y347500D01*
Y334500D01*
X1346500Y331000D01*
X1328262D01*
X1328230Y331011D01*
G03X1327700Y331102I-532J-1511D01*
G01X1326300D01*
G03X1326038Y331080I3J-1602D01*
G01X1325937Y331063D01*
G37*
G36*
G01X1309000Y356500D02*
X1307500Y358000D01*
Y382500D01*
X1309000Y384000D01*
X1323500D01*
X1325000Y382500D01*
Y374940D01*
G02X1324387Y374602I-400J0D01*
G03X1321230Y370493I-1387J-2201D01*
G02Y369907I-273J-293D01*
G03X1324387Y365798I1770J-1908D01*
G02X1325000Y365460I213J-338D01*
G01Y359500D01*
X1322000Y356500D01*
X1309000D01*
G37*
G36*
G01X1303000Y768500D02*
X1302000Y769500D01*
Y776000D01*
X1302500D01*
X1302935Y776435D01*
X1303022Y776432D01*
G03X1303084Y776430I83J1599D01*
G01X1304484D01*
G03X1304925Y776492I0J1602D01*
G01X1304952Y776500D01*
X1307616D01*
X1307643Y776492D01*
G03X1308084Y776430I441J1540D01*
G01X1309484D01*
G03X1309925Y776492I0J1602D01*
G01X1309952Y776500D01*
X1312616D01*
X1312643Y776492D01*
G03X1313084Y776430I441J1540D01*
G01X1314484D01*
G03X1314951Y776500I-1J1602D01*
G01X1315000D01*
X1315500Y776000D01*
Y769000D01*
X1315000Y768500D01*
X1303000D01*
G37*
G36*
G01X1327000Y399000D02*
X1326000Y400000D01*
Y412000D01*
X1329000Y415000D01*
Y422500D01*
X1333500Y427000D01*
X1344500D01*
X1346500Y425000D01*
Y418000D01*
X1354000Y410500D01*
Y400000D01*
X1353000Y399000D01*
X1327000D01*
G37*
G36*
G01X1323000Y424000D02*
X1322000Y425000D01*
Y434000D01*
X1322437Y434437D01*
X1322538Y434420D01*
G03X1322800Y434398I265J1580D01*
G01X1324200D01*
G03X1324730Y434489I-2J1602D01*
G01X1324762Y434500D01*
X1326138D01*
X1326170Y434489D01*
G03X1326700Y434398I532J1511D01*
G01X1328300D01*
G03X1328830Y434489I-2J1602D01*
G01X1328862Y434500D01*
X1331500D01*
X1332798Y435798D01*
X1335711D01*
X1335724Y435797D01*
G03X1337049Y436190I220J1687D01*
G01X1337190Y436310D01*
X1337500Y436000D01*
Y433396D01*
X1337246D01*
Y431746D01*
X1333702Y428202D01*
X1333002D01*
X1328801Y424000D01*
X1323000D01*
G37*
G36*
G01X1334000Y370736D02*
G03Y374064I-2000J1664D01*
G01Y390500D01*
X1335500Y392000D01*
X1366000D01*
X1367500Y390500D01*
Y358202D01*
X1366198D01*
Y354798D01*
X1367500D01*
Y346000D01*
X1365000Y343500D01*
X1353000D01*
X1351500Y345000D01*
Y349500D01*
X1334274Y366726D01*
X1334336Y366855D01*
G03X1334000Y369664I-2336J1145D01*
G01Y370736D01*
G37*
G36*
G01X1356538Y438125D02*
X1358413Y440000D01*
X1364500D01*
X1366000Y441500D01*
X1378500D01*
X1379500Y440500D01*
Y428000D01*
X1378500Y427000D01*
X1352000D01*
X1346502Y432498D01*
Y435682D01*
X1353530D01*
X1353945Y436097D01*
X1354027Y436098D01*
G03X1356525Y438071I-27J2602D01*
G01X1356538Y438125D01*
G37*
G36*
G01X1369000Y406500D02*
X1357818Y417682D01*
G03X1357702Y417887I-2320J-1178D01*
G01Y420662D01*
X1357500Y420863D01*
Y425000D01*
X1358000Y425500D01*
X1378000D01*
X1379500Y424000D01*
Y357500D01*
X1378000Y356000D01*
X1373200D01*
G02X1372800Y356415I0J400D01*
G03X1369563Y358603I-2300J85D01*
G02X1369000Y358968I-163J365D01*
G01Y406500D01*
G37*
%LPC*%
G75*
G36*
G01X238492Y707202D02*
G03X238692Y707402I0J200D01*
G01Y725403D01*
G02X241544I1426J4006D01*
G01Y706027D01*
X240696Y705179D01*
X240700Y705091D01*
G02X238492Y707202I-2200J-91D01*
G37*
G36*
G01X364697Y213835D02*
G03X365351Y213702I371J150D01*
G01X365883Y214235D01*
G02X367583Y212535I850J-850D01*
G01X366646Y211599D01*
X366635Y211538D01*
G02X363656Y211815I-1477J272D01*
G03X363338Y212208I-400J2D01*
G02X364697Y213835I245J1177D01*
G37*
G36*
G01X436900Y214207D02*
X437809Y213298D01*
X437870Y213287D01*
G02X439075Y212082I-272J-1477D01*
G01X439086Y212021D01*
X439995Y211112D01*
G02X439173Y209034I-822J-876D01*
G01X439172D01*
G02X438322Y209386I0J1202D01*
G01X437387Y210322D01*
X437326Y210333D01*
G02X436121Y211538I272J1477D01*
G01X436110Y211599D01*
X435174Y212534D01*
G02X434822Y213384I850J850D01*
G01Y213385D01*
G02X436900Y214207I1202J0D01*
G37*
G36*
G01X401291Y212021D02*
X402200Y211112D01*
G02X401378Y209034I-822J-876D01*
G01X401377D01*
G02X400527Y209386I0J1202D01*
G01X399592Y210322D01*
X399531Y210333D01*
G02X401280Y212082I272J1477D01*
G01X401291Y212021D01*
G37*
G36*
G01X436900Y207908D02*
X437809Y206999D01*
X437870Y206988D01*
G02X439075Y205783I-272J-1477D01*
G01X439086Y205722D01*
X439995Y204813D01*
G02X439173Y202736I-822J-876D01*
G01X439172D01*
G02X438322Y203087I-1J1202D01*
G01X437387Y204023D01*
X437326Y204034D01*
G02X436121Y205239I272J1477D01*
G01X436110Y205300D01*
X435174Y206235D01*
G02X434822Y207085I850J850D01*
G01Y207086D01*
G02X436900Y207908I1202J0D01*
G37*
G36*
G01X367609D02*
X368518Y206999D01*
X368579Y206988D01*
G02X369784Y205783I-272J-1477D01*
G01X369795Y205722D01*
X370704Y204813D01*
G02X369882Y202736I-822J-876D01*
G01X369881D01*
G02X369031Y203087I-1J1202D01*
G01X368096Y204023D01*
X368035Y204034D01*
G02X366830Y205239I272J1477D01*
G01X366819Y205300D01*
X365883Y206235D01*
G02X365532Y207085I851J849D01*
G01Y207086D01*
G02X367609Y207908I1201J0D01*
G37*
G36*
G01X436900Y201609D02*
X437809Y200700D01*
X437870Y200689D01*
G02X439075Y199484I-272J-1477D01*
G01X439086Y199423D01*
X440023Y198487D01*
G02X438323Y196787I-850J-850D01*
G01X437387Y197724D01*
X437326Y197735D01*
G02X436121Y198940I272J1477D01*
G01X436110Y199001D01*
X435174Y199936D01*
G02X434822Y200786I850J850D01*
G01Y200787D01*
G02X436900Y201609I1202J0D01*
G37*
G36*
G01X369795Y199422D02*
X370704Y198513D01*
G02X369882Y196436I-822J-876D01*
G01X369881D01*
G02X369031Y196787I-1J1202D01*
G01X368096Y197723D01*
X368035Y197734D01*
G02X366830Y198939I272J1477D01*
G01X366819Y199000D01*
X365532Y200287D01*
Y200787D01*
G02X367620Y201598I1202J0D01*
G01X367623Y201594D01*
X368518Y200699D01*
X368579Y200688D01*
G02X369784Y199483I-272J-1477D01*
G01X369795Y199422D01*
G37*
G36*
G01X393358Y194792D02*
X391692Y196457D01*
X391639Y196471D01*
G02X393095Y197927I290J1166D01*
G01X393109Y197874D01*
X394748Y196234D01*
X394750Y196232D01*
G02X394775Y196208I-681J-734D01*
G01X395316Y195668D01*
X395369Y195654D01*
G02X396195Y194041I-290J-1166D01*
G01X396180Y194005D01*
Y194004D01*
X396179Y194002D01*
X396164Y193971D01*
G02X395596Y193403I-1085J517D01*
G01X395565Y193388D01*
X395022Y192845D01*
X395016Y192772D01*
G02X393310Y194387I-1497J128D01*
G01X393376Y194397D01*
X393565Y194585D01*
X393385Y194766D01*
X393383Y194768D01*
G02X393358Y194792I681J734D01*
G37*
G36*
G01X436900Y195310D02*
X437809Y194401D01*
X437870Y194390D01*
G02X439075Y193185I-272J-1477D01*
G01X439086Y193124D01*
X440023Y192188D01*
G02X438323Y190488I-850J-850D01*
G01X437387Y191425D01*
X437326Y191436D01*
G02X436121Y192641I272J1477D01*
G01X436110Y192702D01*
X435174Y193637D01*
G02X434822Y194487I850J850D01*
G01Y194488D01*
G02X436900Y195310I1202J0D01*
G37*
G36*
G01X422575Y192188D02*
X423511Y193123D01*
X423522Y193184D01*
G02X425271Y191435I1477J-272D01*
G01X425210Y191424D01*
X424275Y190488D01*
G02X422575Y192188I-850J850D01*
G37*
G36*
G01X418455Y194379D02*
X418516Y194390D01*
X419268Y195142D01*
X419279Y195158D01*
G02X421478Y194488I997J-670D01*
G01Y193953D01*
X420215Y192691D01*
X420204Y192630D01*
G02X418999Y191425I-1477J272D01*
G01X418938Y191414D01*
X417661Y190136D01*
X417126D01*
G02X416456Y192335I0J1202D01*
G01X416472Y192346D01*
X417239Y193113D01*
X417250Y193174D01*
G02X418455Y194379I1477J-272D01*
G37*
G36*
G01X410159Y192337D02*
X410176Y192348D01*
X410940Y193112D01*
X410951Y193173D01*
G02X412700Y191424I1477J-272D01*
G01X412639Y191413D01*
X411363Y190136D01*
X410827D01*
G02X410159Y192337I0J1202D01*
G37*
G36*
G01X403858Y192335D02*
X403874Y192346D01*
X404640Y193112D01*
X404651Y193173D01*
G02X406400Y191424I1477J-272D01*
G01X406339Y191413D01*
X405063Y190136D01*
X404528D01*
G02X403858Y192335I0J1202D01*
G37*
G36*
G01X397028Y191338D02*
Y191874D01*
X398303Y193149D01*
X398314Y193210D01*
G02X400063Y191461I1477J-272D01*
G01X400002Y191450D01*
X399238Y190686D01*
G02X397028Y191338I-1009J652D01*
G37*
G36*
G01X367825Y194990D02*
X367840Y194958D01*
X368391Y194407D01*
X368464Y194401D01*
G02X369834Y193013I-128J-1497D01*
G01X369839Y192938D01*
X370320Y192458D01*
X370355Y192443D01*
G02X368777Y190865I-473J-1105D01*
G01X368762Y190900D01*
X368260Y191402D01*
X368189Y191409D01*
G02X366839Y192776I147J1495D01*
G01X366833Y192849D01*
X366326Y193356D01*
X366288Y193372D01*
G02X367825Y194990I445J1116D01*
G37*
G36*
G01X381280Y188189D02*
Y188690D01*
X382548Y189958D01*
X382559Y190019D01*
G02X384308Y188270I1477J-272D01*
G01X384247Y188259D01*
X383380Y187392D01*
X383376Y187387D01*
G02X381280Y188189I-895J802D01*
G37*
G36*
G01X388182Y191785D02*
Y190522D01*
X389682Y189022D01*
Y188987D01*
X389724Y188933D01*
G02X387602Y188426I-944J-744D01*
G01X387623Y188531D01*
X386378Y189776D01*
Y191678D01*
G02X388182Y191785I831J1252D01*
G37*
G36*
G01X374601Y188261D02*
G03X374209Y187943I-1J-400D01*
G02X372786Y189366I-1177J246D01*
G03X373104Y189758I-82J391D01*
G02Y189768I1502J5D01*
G03X372786Y190161I-400J2D01*
G02Y192515I246J1177D01*
G03X373104Y192907I-82J391D01*
G02Y192918I1502J5D01*
G03X372786Y193311I-400J2D01*
G02X374209Y194733I246J1177D01*
G03X374602Y194414I392J81D01*
G02X375449Y191669I4J-1502D01*
G03Y191006I224J-331D01*
G02X374601Y188261I-843J-1243D01*
G37*
G36*
G01X416276Y185889D02*
X417213Y186825D01*
X417224Y186886D01*
G02X418429Y188091I1477J-272D01*
G01X418490Y188102D01*
X419426Y189039D01*
G02X421126Y187339I850J-850D01*
G01X420189Y186403D01*
X420178Y186342D01*
G02X418973Y185137I-1477J272D01*
G01X418912Y185126D01*
X417976Y184189D01*
G02X416276Y185889I-850J850D01*
G37*
G36*
G01X412167Y188091D02*
X412228Y188102D01*
X412969Y188843D01*
X412980Y188859D01*
G02X415178Y188189I997J-670D01*
G01Y187654D01*
X413927Y186403D01*
X413916Y186342D01*
G02X412711Y185137I-1477J272D01*
G01X412650Y185126D01*
X411362Y183838D01*
X410827D01*
G02X410157Y186036I0J1201D01*
G01X410173Y186047D01*
X410951Y186825D01*
X410962Y186886D01*
G02X412167Y188091I1477J-272D01*
G37*
G36*
G01X406312Y185125D02*
X405404Y184217D01*
G02X403326Y185039I-876J822D01*
G01Y185040D01*
G02X403678Y185890I1202J0D01*
G01X404613Y186824D01*
X404624Y186885D01*
G02X405829Y188090I1477J-272D01*
G01X405890Y188101D01*
X406827Y189039D01*
G02X408527Y187339I850J-850D01*
G01X407589Y186402D01*
X407578Y186341D01*
G02X406373Y185136I-1477J272D01*
G01X406312Y185125D01*
G37*
G36*
G01X399569Y188091D02*
X399630Y188102D01*
X400368Y188840D01*
X400379Y188857D01*
G02X402580Y188189I999J-668D01*
G01Y187653D01*
X401329Y186403D01*
X401318Y186342D01*
G02X400113Y185137I-1477J272D01*
G01X400052Y185126D01*
X398764Y183838D01*
X398229D01*
G02X397559Y186036I0J1201D01*
G01X397575Y186047D01*
X398353Y186825D01*
X398364Y186886D01*
G02X399569Y188091I1477J-272D01*
G37*
G36*
G01X391261Y186038D02*
X391278Y186049D01*
X392054Y186825D01*
X392065Y186886D01*
G02X393270Y188091I1477J-272D01*
G01X393331Y188102D01*
X394069Y188840D01*
X394080Y188857D01*
G02X396280Y188189I999J-668D01*
G01Y187653D01*
X395030Y186403D01*
X395019Y186342D01*
G02X393814Y185137I-1477J272D01*
G01X393753Y185126D01*
X392465Y183838D01*
X391929D01*
G02X391261Y186038I0J1201D01*
G37*
G36*
G01X436900Y182711D02*
X437809Y181802D01*
X437870Y181791D01*
G02X439075Y180586I-272J-1477D01*
G01X439086Y180525D01*
X439995Y179616D01*
G02X439173Y177538I-822J-876D01*
G01X439172D01*
G02X438322Y177890I0J1202D01*
G01X437387Y178826D01*
X437326Y178837D01*
G02X436121Y180042I272J1477D01*
G01X436110Y180103D01*
X435174Y181038D01*
G02X434822Y181888I850J850D01*
G01Y181889D01*
G02X436900Y182711I1202J0D01*
G37*
G36*
G01X418454Y181780D02*
X418515Y181791D01*
X419270Y182547D01*
G02X421478Y181889I1006J-658D01*
G01Y181355D01*
X420214Y180092D01*
X420203Y180031D01*
G02X418998Y178826I-1477J272D01*
G01X418937Y178815D01*
X417661Y177538D01*
X417126D01*
G02X416456Y179737I0J1202D01*
G01X416472Y179748D01*
X417238Y180514D01*
X417249Y180575D01*
G02X418454Y181780I1477J-272D01*
G37*
G36*
G01X412611Y178826D02*
X411703Y177918D01*
G02X409626Y178740I-876J822D01*
G01Y178741D01*
G02X409977Y179591I1202J1D01*
G01X410912Y180525D01*
X410923Y180586D01*
G02X412128Y181791I1477J-272D01*
G01X412189Y181802D01*
X413477Y183090D01*
X413977D01*
G02X414788Y181002I0J-1202D01*
G01X414784Y180999D01*
X413888Y180103D01*
X413877Y180042D01*
G02X412672Y178837I-1477J272D01*
G01X412611Y178826D01*
G37*
G36*
G01X403870Y179746D02*
X404651Y180526D01*
X404662Y180587D01*
G02X405867Y181792I1477J-272D01*
G01X405928Y181803D01*
X406671Y182547D01*
G02X408878Y181889I1005J-658D01*
G01Y181355D01*
X407627Y180104D01*
X407616Y180043D01*
G02X406411Y178838I-1477J272D01*
G01X406350Y178827D01*
X405062Y177538D01*
X404528D01*
G02X403870Y179746I0J1202D01*
G37*
G36*
G01X397571D02*
X398352Y180526D01*
X398363Y180587D01*
G02X399568Y181792I1477J-272D01*
G01X399629Y181803D01*
X400372Y182547D01*
G02X402580Y181889I1006J-658D01*
G01Y181355D01*
X401328Y180104D01*
X401317Y180043D01*
G02X400112Y178838I-1477J272D01*
G01X400051Y178827D01*
X398763Y177538D01*
X398229D01*
G02X397571Y179746I0J1202D01*
G37*
G36*
G01X391283Y179753D02*
X392052Y180522D01*
X392063Y180584D01*
G02X393269Y181792I1478J-269D01*
G01X393330Y181803D01*
X394073Y182547D01*
G02X396280Y181889I1005J-658D01*
G01Y181355D01*
X395029Y180104D01*
X395018Y180043D01*
G02X393816Y178838I-1477J272D01*
G01X393755Y178827D01*
X392467Y177538D01*
X391929D01*
G02X391283Y179753I0J1202D01*
G37*
G36*
G01X384302Y175643D02*
X384241Y175632D01*
X383035Y174426D01*
X382778D01*
X382755Y174420D01*
G02X381631Y176440I-274J1170D01*
G01X382020Y176828D01*
X382039D01*
X382542Y177331D01*
X382553Y177392D01*
G02X384302Y175643I1477J-272D01*
G37*
G36*
G01X436900Y176412D02*
X437809Y175503D01*
X437870Y175492D01*
G02X439075Y174287I-272J-1477D01*
G01X439086Y174226D01*
X439995Y173317D01*
G02X439173Y171240I-822J-876D01*
G01X439172D01*
G02X438322Y171591I-1J1202D01*
G01X437387Y172527D01*
X437326Y172538D01*
G02X436121Y173743I272J1477D01*
G01X436110Y173804D01*
X435174Y174739D01*
G02X434822Y175589I850J850D01*
G01Y175590D01*
G02X436900Y176412I1202J0D01*
G37*
G36*
G01X418454Y175480D02*
X418515Y175491D01*
X419268Y176244D01*
X419279Y176260D01*
G02X421478Y175590I997J-670D01*
G01Y175055D01*
X420214Y173792D01*
X420203Y173731D01*
G02X418998Y172526I-1477J272D01*
G01X418937Y172515D01*
X417662Y171240D01*
X417126D01*
G02X416458Y173440I0J1201D01*
G01X416475Y173451D01*
X417238Y174214D01*
X417249Y174275D01*
G02X418454Y175480I1477J-272D01*
G37*
G36*
G01X412154D02*
X412215Y175491D01*
X412971Y176248D01*
G02X415178Y175590I1005J-658D01*
G01Y175056D01*
X413914Y173792D01*
X413903Y173731D01*
G02X412698Y172526I-1477J272D01*
G01X412637Y172515D01*
X411362Y171240D01*
X410827D01*
G02X410157Y173438I0J1201D01*
G01X410173Y173449D01*
X410938Y174214D01*
X410949Y174275D01*
G02X412154Y175480I1477J-272D01*
G37*
G36*
G01X403870Y173447D02*
X404638Y174214D01*
X404649Y174275D01*
G02X405854Y175480I1477J-272D01*
G01X405915Y175491D01*
X406671Y176248D01*
G02X408878Y175590I1005J-658D01*
G01Y175056D01*
X407614Y173792D01*
X407603Y173731D01*
G02X406398Y172526I-1477J272D01*
G01X406337Y172515D01*
X405062Y171240D01*
X404528D01*
G02X403870Y173447I0J1202D01*
G37*
G36*
G01X397028Y172441D02*
Y172976D01*
X398302Y174250D01*
X398313Y174311D01*
G02X399518Y175516I1477J-272D01*
G01X399579Y175527D01*
X400843Y176792D01*
X401378D01*
G02X402048Y174593I0J-1202D01*
G01X402032Y174582D01*
X401278Y173828D01*
X401267Y173767D01*
G02X400062Y172562I-1477J272D01*
G01X400001Y172551D01*
X399236Y171786D01*
G02X397028Y172441I-1007J655D01*
G37*
G36*
G01X390728D02*
Y172976D01*
X392002Y174250D01*
X392013Y174311D01*
G02X393218Y175516I1477J-272D01*
G01X393279Y175527D01*
X394543Y176792D01*
X395079D01*
G02X395747Y174591I0J-1202D01*
G01X395730Y174580D01*
X394978Y173828D01*
X394967Y173767D01*
G02X393762Y172562I-1477J272D01*
G01X393701Y172551D01*
X392936Y171786D01*
G02X390728Y172441I-1007J655D01*
G37*
G36*
G01X375331Y170141D02*
X376264Y171073D01*
X376276Y171133D01*
G02X378007Y169366I1474J-287D01*
G01X377944Y169355D01*
X377031Y168441D01*
G02X375331Y170141I-850J850D01*
G37*
G36*
G01X386994Y169203D02*
X387904Y170113D01*
G02X389982Y169291I876J-822D01*
G01Y169290D01*
G02X389630Y168440I-1202J0D01*
G01X388693Y167504D01*
X388682Y167443D01*
G02X386933Y169192I-1477J272D01*
G01X386994Y169203D01*
G37*
G36*
G01X393256Y169179D02*
X393317Y169190D01*
X394069Y169942D01*
X394080Y169959D01*
G02X396280Y169291I999J-668D01*
G01Y168755D01*
X395016Y167491D01*
X395005Y167430D01*
G02X393256Y169179I-1477J272D01*
G37*
G36*
G01X380656Y169178D02*
X380717Y169189D01*
X381473Y169945D01*
X381484Y169961D01*
G02X382225Y170465I997J-670D01*
G03X382539Y170862I-86J391D01*
G02X383967Y172388I1502J26D01*
G01X384044Y172392D01*
X384497Y172845D01*
X384512Y172883D01*
G02X386135Y171350I1118J-442D01*
G01X386103Y171336D01*
X385540Y170772D01*
X385532Y170704D01*
G02X384074Y169386I-1491J184D01*
G03X383682Y168986I8J-400D01*
G01Y168756D01*
X382416Y167490D01*
X382405Y167429D01*
G02X380656Y169178I-1477J272D01*
G37*
G36*
G01X436900Y170113D02*
X437809Y169204D01*
X437870Y169193D01*
G02X439075Y167988I-272J-1477D01*
G01X439086Y167927D01*
X440023Y166991D01*
G02X438323Y165291I-850J-850D01*
G01X437387Y166228D01*
X437326Y166239D01*
G02X436121Y167444I272J1477D01*
G01X436110Y167505D01*
X435174Y168440D01*
G02X434822Y169290I850J850D01*
G01Y169291D01*
G02X436900Y170113I1202J0D01*
G37*
G36*
G01X412154Y169180D02*
X412215Y169191D01*
X412969Y169945D01*
X412980Y169961D01*
G02X415178Y169291I997J-670D01*
G01Y168756D01*
X413914Y167492D01*
X413903Y167431D01*
G02X412698Y166226I-1477J272D01*
G01X412637Y166215D01*
X411362Y164940D01*
X410827D01*
G02X410157Y167138I0J1201D01*
G01X410173Y167149D01*
X410938Y167914D01*
X410949Y167975D01*
G02X412154Y169180I1477J-272D01*
G37*
G36*
G01X405868Y169193D02*
X405929Y169204D01*
X406667Y169942D01*
X406678Y169959D01*
G02X408878Y169291I999J-668D01*
G01Y168755D01*
X407628Y167505D01*
X407617Y167444D01*
G02X406412Y166239I-1477J272D01*
G01X406351Y166228D01*
X405063Y164940D01*
X404528D01*
G02X403858Y167138I0J1201D01*
G01X403874Y167149D01*
X404652Y167927D01*
X404663Y167988D01*
G02X405868Y169193I1477J-272D01*
G37*
G36*
G01X399555Y169179D02*
X399616Y169190D01*
X400368Y169942D01*
X400379Y169959D01*
G02X402580Y169291I999J-668D01*
G01Y168755D01*
X401315Y167491D01*
X401304Y167430D01*
G02X400099Y166225I-1477J272D01*
G01X400038Y166214D01*
X398764Y164940D01*
X398229D01*
G02X397559Y167138I0J1201D01*
G01X397575Y167149D01*
X398339Y167913D01*
X398350Y167974D01*
G02X399555Y169179I1477J-272D01*
G37*
G36*
G01X419269Y162337D02*
X416474Y165132D01*
G02X416458Y167140I652J1009D01*
G01X416475Y167151D01*
X417238Y167914D01*
X417249Y167975D01*
G02X418454Y169180I1477J-272D01*
G01X418515Y169191D01*
X419266Y169942D01*
X419277Y169959D01*
G02X421478Y169291I999J-668D01*
G01Y168755D01*
X420214Y167492D01*
X420203Y167431D01*
G02X419393Y166357I-1477J272D01*
G03X419288Y165716I178J-358D01*
G01X421478Y163527D01*
Y162992D01*
G02X419269Y162337I-1202J0D01*
G37*
G36*
G01X412155Y162881D02*
X412216Y162892D01*
X412967Y163643D01*
X412978Y163660D01*
G02X415178Y162992I999J-668D01*
G01Y162456D01*
X413915Y161193D01*
X413904Y161132D01*
G02X412155Y162881I-1477J272D01*
G37*
G36*
G01X405855D02*
X405916Y162892D01*
X406667Y163643D01*
X406678Y163660D01*
G02X408878Y162992I999J-668D01*
G01Y162456D01*
X407615Y161193D01*
X407604Y161132D01*
G02X405855Y162881I-1477J272D01*
G37*
G36*
G01X436900Y163814D02*
X437809Y162905D01*
X437870Y162894D01*
G02X439075Y161689I-272J-1477D01*
G01X439086Y161628D01*
X440023Y160692D01*
G02X438323Y158992I-850J-850D01*
G01X437387Y159929D01*
X437326Y159940D01*
G02X436121Y161145I272J1477D01*
G01X436110Y161206D01*
X435174Y162141D01*
G02X434822Y162991I850J850D01*
G01Y162992D01*
G02X436900Y163814I1202J0D01*
G37*
G36*
G01X425725Y160692D02*
X426661Y161627D01*
X426672Y161688D01*
G02X428421Y159939I1477J-272D01*
G01X428360Y159928D01*
X427425Y158992D01*
G02X425725Y160692I-850J850D01*
G37*
G36*
G01X436900Y157515D02*
X437809Y156606D01*
X437870Y156595D01*
G02X439075Y155390I-272J-1477D01*
G01X439086Y155329D01*
X440023Y154393D01*
G02X438323Y152693I-850J-850D01*
G01X437387Y153630D01*
X437326Y153641D01*
G02X436121Y154846I272J1477D01*
G01X436110Y154907D01*
X435174Y155842D01*
G02X434822Y156692I850J850D01*
G01Y156693D01*
G02X436900Y157515I1202J0D01*
G37*
G36*
G01X400576Y151288D02*
X400581Y151292D01*
X401450Y152161D01*
X401461Y152222D01*
G02X403210Y150473I1477J-272D01*
G01X403149Y150462D01*
X401879Y149192D01*
X401378D01*
G02X400576Y151288I0J1201D01*
G37*
G36*
G01X393878Y150393D02*
Y150928D01*
X395151Y152201D01*
X395162Y152262D01*
G02X396911Y150513I1477J-272D01*
G01X396850Y150502D01*
X396086Y149738D01*
G02X393878Y150393I-1007J655D01*
G37*
G36*
G01X388780Y154744D02*
X389284D01*
X390550Y153478D01*
X390611Y153467D01*
G02Y150513I-272J-1477D01*
G01X390550Y150502D01*
X389789Y149741D01*
G02X387578Y150393I-1009J652D01*
G01Y150929D01*
X388640Y151990D01*
X388005Y152625D01*
X387999Y152630D01*
G02X388780Y154744I781J913D01*
G37*
G36*
G01X374980Y150393D02*
Y150920D01*
X376271Y152211D01*
X376282Y152272D01*
G02X378031Y150523I1477J-272D01*
G01X377970Y150512D01*
X377173Y149715D01*
X377163Y149701D01*
G02X374980Y150393I-982J692D01*
G37*
G36*
G01X415546Y147316D02*
G03X415154Y146998I-1J-400D01*
G02X413731Y148421I-1177J246D01*
G03X414049Y148813I-82J391D01*
G02X416794Y149661I1502J5D01*
G03X417457I332J224D01*
G02X419944Y149660I1243J-843D01*
G03X420606I331J224D01*
G02X423093Y149661I1244J-842D01*
G03X423756I331J224D01*
G02X426243Y149660I1243J-843D01*
G03X426905I331J224D01*
G02X428144Y147316I1244J-842D01*
G03X427752Y146998I-1J-400D01*
G02X425398I-1177J246D01*
G03X425005Y147316I-391J-82D01*
G02X424994I-5J1502D01*
G03X424602Y146998I-1J-400D01*
G02X422248I-1177J246D01*
G03X421855Y147316I-391J-82D01*
G02X421845I-5J1502D01*
G03X421453Y146998I-1J-400D01*
G02X419099I-1177J246D01*
G03X418706Y147316I-391J-82D01*
G02X418695I-6J1502D01*
G03X418303Y146998I-1J-400D01*
G02X415949I-1177J246D01*
G03X415556Y147316I-391J-82D01*
G02X415546I-5J1502D01*
G37*
G36*
G01X428023Y144017D02*
X428096Y144023D01*
X428605Y144532D01*
X428620Y144567D01*
G02X430198Y142989I1105J-473D01*
G01X430163Y142974D01*
X429654Y142465D01*
X429648Y142392D01*
G02X428279Y141023I-1497J128D01*
G01X428206Y141017D01*
X427695Y140506D01*
X427679Y140470D01*
G02X426103Y142051I-1104J475D01*
G01X426139Y142066D01*
X426648Y142575D01*
X426654Y142648D01*
G02X428023Y144017I1497J-128D01*
G37*
G36*
G01X421723D02*
X421796Y144023D01*
X422305Y144532D01*
X422320Y144567D01*
G02X423898Y142989I1105J-473D01*
G01X423863Y142974D01*
X423354Y142465D01*
X423348Y142392D01*
G02X421979Y141023I-1497J128D01*
G01X421906Y141017D01*
X421396Y140507D01*
X421381Y140472D01*
G02X419803Y142050I-1105J473D01*
G01X419838Y142065D01*
X420348Y142575D01*
X420354Y142648D01*
G02X421723Y144017I1497J-128D01*
G37*
G36*
G01X376181Y155492D02*
X375646D01*
X374359Y156779D01*
X374298Y156790D01*
G02X373725Y159509I272J1477D01*
G03X373728Y160169I-225J331D01*
G02X373105Y161132I854J1235D01*
G01X373094Y161193D01*
X371830Y162456D01*
Y162992D01*
G02X372905Y164187I1202J0D01*
G03X373083Y164406I-21J199D01*
G02X376054Y164831I1494J153D01*
G01X376065Y164770D01*
X376835Y164000D01*
X376851Y163989D01*
G02X376408Y161812I-670J-997D01*
G03X376084Y161416I76J-393D01*
G02X375427Y160162I-1502J-12D01*
G03X375424Y159502I225J-331D01*
G02X376047Y158539I-854J-1235D01*
G01X376058Y158478D01*
X376835Y157701D01*
X376851Y157690D01*
G02X376181Y155492I-670J-997D01*
G37*
G36*
G01X436960Y6440D02*
Y4540D01*
X430056D01*
Y11444D01*
X436960D01*
G03X437528Y11087I400J6D01*
G02X438477Y6698I972J-2087D01*
G01X438393Y6699D01*
X438135Y6440D01*
X436960D01*
G37*
G36*
G01X674583Y966475D02*
G03X673917I-333J-221D01*
G02Y969025I-1917J1275D01*
G03X674583I333J221D01*
G02Y966475I1917J-1275D01*
G37*
G36*
G01X774723Y918950D02*
G02X771277I-1723J-1950D01*
G03Y919550I-264J300D01*
G02X771957Y923884I1723J1950D01*
G03Y924616I-161J366D01*
G02X770616Y925957I1043J2384D01*
G03X769884I-366J-161D01*
G02Y928043I-2384J1043D01*
G03X770616I366J161D01*
G02X774043Y924616I2384J-1043D01*
G03Y923884I161J-366D01*
G02X774723Y919550I-1043J-2384D01*
G03Y918950I264J-300D01*
G37*
G36*
G01X606286Y876257D02*
G02X606231Y878839I-2286J1243D01*
G03X606925Y878854I343J206D01*
G02X606980Y876272I2286J-1243D01*
G03X606286Y876257I-343J-206D01*
G37*
G36*
G01X1087298Y407542D02*
X1087287Y407574D01*
G02X1087198Y408100I1513J527D01*
G01Y409500D01*
G02X1088800Y411102I1602J0D01*
G01X1090200D01*
G02X1091802Y409500I0J-1602D01*
G01Y408100D01*
G02X1091713Y407574I-1602J1D01*
G01X1091702Y407542D01*
Y405000D01*
G02X1087298I-2202J0D01*
G01Y407542D01*
G37*
G36*
G01X1050700Y298900D02*
X1051700D01*
Y297900D01*
X1051724Y297856D01*
Y296856D01*
X1050724D01*
Y297856D01*
X1050700Y297900D01*
Y298900D01*
G37*
G36*
G01X1036275Y802583D02*
G03Y801917I221J-333D01*
G02X1033725I-1275J-1917D01*
G03Y802583I-221J333D01*
G02X1036275I1275J1917D01*
G37*
G36*
G01X1157108Y449111D02*
G03Y448539I280J-286D01*
G02X1153208Y446675I-1608J-1647D01*
G03X1152616Y446987I-398J-38D01*
G02X1152659Y450989I-1116J2013D01*
G03X1153251Y451249I201J346D01*
G02X1157108Y449111I2249J-491D01*
G37*
G36*
G01X1057700Y298900D02*
Y297900D01*
X1057724Y297856D01*
Y296856D01*
X1056724D01*
Y297856D01*
X1056700Y297900D01*
Y298900D01*
X1057700D01*
G37*
G36*
G01X1255200Y208500D02*
X1256200D01*
Y207500D01*
X1255000Y206200D01*
X1254000D01*
Y207200D01*
X1255200Y208500D01*
G37*
G54D196*
X360433Y203937D03*
Y207086D03*
X357284D03*
X360433Y210236D03*
X357284D03*
X360433Y213385D03*
X357284D03*
X373032Y181889D03*
Y185039D03*
Y197637D03*
X363583D03*
X373032Y200787D03*
X363583D03*
X373032Y203937D03*
X363583D03*
X379331Y207086D03*
X376181D03*
X373032D03*
X363583D03*
X366733Y216535D03*
X385630Y207086D03*
X382481D03*
G54D201*
X482429Y139000D03*
X685000Y150500D03*
X609500Y778500D03*
X603000D03*
Y785000D03*
X609000Y870000D03*
G54D202*
X538875Y138000D03*
X622500Y696500D03*
X625000Y706000D03*
X1002500Y653000D03*
X691400Y231100D03*
X1027504Y853366D03*
X1132500Y333000D03*
G54D197*
X360433Y216535D03*
X357284Y219685D03*
X360433Y222834D03*
X363583Y216535D03*
Y219685D03*
Y222834D03*
G54D199*
X651968Y55512D03*
G54D191*
X321500Y688000D03*
X157500Y867500D03*
X338500Y397500D03*
X525679Y136250D03*
X667000Y969700D03*
X666750Y961550D03*
X680000Y640000D03*
X733000Y969700D03*
X749500Y974300D03*
X766000Y635000D03*
X1083200Y956500D03*
X1162000Y960625D03*
X757500Y743500D03*
X776750Y964750D03*
X917000Y752500D03*
X1044000Y763940D03*
X1052500Y773350D03*
X1063000Y780000D03*
X1040208Y745020D03*
X1124327Y465391D03*
X1130000Y361500D03*
X1279000Y746575D03*
X1302000Y475000D03*
X1280000Y420500D03*
G54D188*
X34500Y692000D03*
G54D203*
X580514Y298230D03*
X584449Y290355D03*
X588384Y298230D03*
X592324Y290355D03*
X564764Y298230D03*
X568699Y290355D03*
X572639Y298230D03*
X576574Y290355D03*
X549014Y298230D03*
X552954Y290355D03*
X556889Y298230D03*
X560829Y290355D03*
X545079D03*
G54D190*
X200118Y739409D03*
X190118D03*
X210118D03*
X230118Y729409D03*
Y739409D03*
X220118D03*
X250118D03*
X240118D03*
X260118Y729409D03*
Y739409D03*
X270118Y729409D03*
Y739409D03*
G54D189*
X66672Y793204D03*
X64372D03*
X62172D03*
X59872D03*
X57672D03*
X154000Y849200D03*
X178300Y904500D03*
X181700D03*
X183300D03*
X186700D03*
X188300D03*
X191700D03*
X170300Y905500D03*
X172700D03*
X174300D03*
X176700D03*
X191700Y913500D03*
X188300D03*
X186700D03*
X183300D03*
X181700D03*
X178300D03*
X176700Y911500D03*
X174300D03*
X172700D03*
X170300D03*
X233523Y570483D03*
X235723D03*
X237255Y570600D03*
X239655D03*
X208600Y706200D03*
X210900D03*
X213100D03*
X215400D03*
X217600D03*
X219900D03*
X222100D03*
X271700Y216000D03*
X269300D03*
X267700D03*
X265300D03*
X268200Y883400D03*
Y885600D03*
X271700Y210000D03*
X269300D03*
X267700D03*
X265300D03*
X272400Y202300D03*
Y196700D03*
X274600D03*
X372300Y13500D03*
X299700Y67900D03*
X303100D03*
X304700D03*
X308400Y63400D03*
Y60000D03*
Y58400D03*
X308100Y67900D03*
X308400Y55000D03*
Y53400D03*
Y50000D03*
X299700Y76900D03*
X303100D03*
X304700D03*
X314705Y312052D03*
Y314252D03*
X313629Y355100D03*
X360255Y392900D03*
Y372100D03*
Y374900D03*
Y377100D03*
Y379400D03*
Y381600D03*
Y383900D03*
Y386100D03*
Y388400D03*
Y390600D03*
Y369900D03*
X303859Y432178D03*
X300459D03*
X374005Y429900D03*
Y427600D03*
Y425400D03*
Y423100D03*
X360505Y420100D03*
Y417900D03*
Y415600D03*
Y413400D03*
Y411100D03*
Y408900D03*
Y406370D03*
Y404170D03*
X360515Y401600D03*
X366300Y439100D03*
X313655Y438200D03*
X311455D03*
X317400Y63400D03*
Y60000D03*
Y58400D03*
Y55000D03*
Y53400D03*
Y50000D03*
X312385Y244072D03*
X309229Y263000D03*
X311629D03*
X314229D03*
X316629D03*
X319229D03*
X321629D03*
X319085Y249672D03*
X316885D03*
X314585D03*
X312385D03*
X319229Y269000D03*
X316629D03*
X314229D03*
X311629D03*
X314629Y335600D03*
Y333400D03*
X313629Y347400D03*
X366300Y442900D03*
X311455Y443800D03*
X313655D03*
X344255Y448640D03*
X315993Y449173D03*
X372300Y19500D03*
X381700D03*
X393700Y38000D03*
X390300D03*
X344700Y66000D03*
X341300D03*
X319085Y244072D03*
X345729Y313600D03*
X320305Y312052D03*
Y314252D03*
X345729Y333900D03*
X320229Y333400D03*
X345229Y348400D03*
X319229Y355100D03*
X366300Y868500D03*
X383400Y869200D03*
X385600D03*
X396900D03*
X399100D03*
X334200Y943100D03*
X332300Y945100D03*
X334700D03*
X339100Y957300D03*
X341400D03*
X343600D03*
X345900D03*
X348100D03*
X350400D03*
X352600D03*
X354900D03*
X357100D03*
X359400D03*
X361600D03*
X351829Y251300D03*
X354029D03*
X356329D03*
X358529D03*
X360829D03*
X363029D03*
X365329D03*
X367529D03*
X369829D03*
X372029D03*
X374329D03*
X376529D03*
X378829D03*
X381029D03*
X351729Y270000D03*
X354129D03*
X360729D03*
X363129D03*
X369729D03*
X372129D03*
X373800D03*
X376200D03*
X377729D03*
X380129D03*
X351729Y276000D03*
X354129D03*
X360729D03*
X363129D03*
X369729D03*
X372129D03*
X373800D03*
X376200D03*
X377729D03*
X380129D03*
X390300Y47000D03*
X387500Y941300D03*
X403300Y264300D03*
Y266500D03*
X575500Y60800D03*
Y63200D03*
Y64800D03*
X542900Y150200D03*
X552900D03*
X555100D03*
X557900D03*
X560100D03*
X562900D03*
X603898Y449416D03*
Y447816D03*
Y444416D03*
Y442816D03*
Y439416D03*
Y437816D03*
Y452816D03*
Y434416D03*
Y432816D03*
Y429416D03*
Y427816D03*
Y424416D03*
X594898D03*
Y427816D03*
Y429416D03*
Y432816D03*
Y434416D03*
Y437816D03*
Y439416D03*
Y442816D03*
Y444416D03*
Y447816D03*
Y449416D03*
Y452816D03*
X581500Y67200D03*
Y64800D03*
Y63200D03*
X593300Y245000D03*
X595700D03*
X637776Y98014D03*
X639976D03*
X642276D03*
X644476D03*
X646776D03*
X648976D03*
X651276D03*
X653476D03*
X655776D03*
X657976D03*
X660276D03*
X672922Y131432D03*
X689916Y138884D03*
X699116Y153084D03*
X701316D03*
X703616D03*
X705816D03*
X708116D03*
X710316D03*
X712616D03*
X714816D03*
X717116D03*
X719316D03*
X721616D03*
X723816D03*
X726116D03*
X797094Y584668D03*
X850500Y867300D03*
Y869700D03*
X791500Y898700D03*
X689962Y456664D03*
X690000Y474700D03*
Y471300D03*
X932000Y50300D03*
X725632Y52916D03*
X983060Y194007D03*
X985460D03*
X987460D03*
X989860D03*
X1099000Y68200D03*
Y64800D03*
Y62700D03*
Y59300D03*
X673855Y261500D03*
X676255D03*
X677855D03*
X680255D03*
X681855D03*
X684255D03*
X685855D03*
X688255D03*
X704855D03*
X707255D03*
X708855D03*
X711255D03*
X712855D03*
X715255D03*
X716855D03*
X719255D03*
X681000Y471300D03*
Y474700D03*
X724648Y185300D03*
X726848D03*
X728548Y185500D03*
X730948D03*
X730448Y188400D03*
X718200Y192400D03*
X765700Y852400D03*
Y854600D03*
Y856900D03*
X721000Y862800D03*
X723200Y862900D03*
Y865100D03*
X721000Y865200D03*
X745500Y693000D03*
X750000D03*
X745500Y704000D03*
X750000D03*
X737268Y762884D03*
X786300Y773500D03*
X788700D03*
X790300D03*
X807300Y336500D03*
X810700D03*
X780500Y356700D03*
Y354300D03*
X786274Y432378D03*
Y435778D03*
X771274Y439378D03*
X807300Y345500D03*
X810700D03*
X786500Y356700D03*
X805074Y443578D03*
X807474D03*
X804574Y452578D03*
X807974D03*
X818000Y367300D03*
Y369700D03*
X824000D03*
X825300Y403000D03*
X827700D03*
X823600Y403200D03*
X854000Y383800D03*
X848000Y386200D03*
X868100Y431700D03*
X865900D03*
X863600D03*
X861400D03*
X859700Y431500D03*
X857300D03*
X868500Y410700D03*
X868700Y412900D03*
X856300Y654000D03*
X858700D03*
X905700Y66500D03*
X926000Y50300D03*
X920100Y50700D03*
X926000Y52700D03*
X1088400Y413300D03*
X1090600D03*
X1086500Y413700D03*
X997950Y72250D03*
X1066700Y63000D03*
X1064300D03*
X1078429Y74958D03*
Y72558D03*
X1005550Y72250D03*
X1010050D03*
X1021500Y282700D03*
Y280300D03*
Y278700D03*
Y276300D03*
X1051200Y300800D03*
X1051224Y294956D03*
Y292956D03*
Y290556D03*
X1051500Y288700D03*
Y286300D03*
X1049000Y284700D03*
Y281300D03*
X1049216Y279668D03*
Y276268D03*
X1015500Y276300D03*
Y278700D03*
Y280300D03*
X1064588Y754404D03*
X1064738Y762344D03*
X1059000Y843300D03*
Y845700D03*
X1053216Y902168D03*
Y899768D03*
X1091468Y862084D03*
X1023916Y865868D03*
Y868068D03*
X1010716Y897268D03*
Y881168D03*
Y878768D03*
X1064300Y69000D03*
X1066700D03*
X1037000Y107200D03*
Y109300D03*
Y112700D03*
Y103800D03*
X1053000Y843300D03*
Y845700D03*
X1025916Y857468D03*
X1027616Y857668D03*
X1029816D03*
X1047216Y902168D03*
Y899768D03*
X1090000Y59300D03*
Y62700D03*
Y64800D03*
X1046000Y112700D03*
Y109300D03*
Y107200D03*
Y103800D03*
X1066000Y139300D03*
Y142700D03*
X1067200Y157000D03*
X1063800D03*
X1085750Y170950D03*
X1080250D03*
X1067200Y166000D03*
X1063800D03*
X1085750Y175450D03*
X1080250D03*
X1052000Y928800D03*
Y931200D03*
X1058216Y276268D03*
Y279668D03*
X1058000Y281300D03*
Y284700D03*
X1057500Y286300D03*
Y288700D03*
X1057224Y290556D03*
Y292956D03*
Y294956D03*
X1057200Y300800D03*
X1080250Y183050D03*
X1085750D03*
X1100668Y883284D03*
X1098268D03*
X1263800Y777900D03*
X1134268Y883784D03*
X1136668D03*
X1098268Y889284D03*
X1100668D03*
X1173477Y224500D03*
X1176877D03*
X1178477Y226500D03*
X1184377D03*
X1149058Y752194D03*
X1151458D03*
X1163000Y752200D03*
X1136548Y752284D03*
X1138948D03*
X1155568D03*
X1157968D03*
X1142118Y752564D03*
X1144318D03*
X1144500Y863200D03*
X1134268Y877784D03*
X1136668D03*
X1161368Y248984D03*
X1163568D03*
X1147468Y251084D03*
Y254484D03*
X1148834Y585972D03*
X1151034D03*
X1145200Y595900D03*
Y598100D03*
X1154400Y603000D03*
X1200877Y229000D03*
X1198477D03*
X1196877D03*
X1194477D03*
X1304750Y472550D03*
X1246700Y208000D03*
X1248500Y206700D03*
Y204300D03*
Y202700D03*
Y200300D03*
Y198700D03*
Y196300D03*
X1254500D03*
Y198700D03*
Y200300D03*
Y202700D03*
Y204300D03*
X1255700Y211400D03*
X1288700Y445500D03*
X1285300D03*
X1254800Y636100D03*
Y637900D03*
Y640100D03*
Y641900D03*
Y644100D03*
Y645900D03*
X1262300Y649900D03*
Y658100D03*
Y659900D03*
X1286000Y364700D03*
Y361300D03*
X1284412Y433012D03*
X1304750Y464950D03*
X1299250D03*
X1304750Y460450D03*
X1299250D03*
X1288700Y454500D03*
X1285300D03*
X1275900Y710300D03*
X1274200Y710500D03*
Y715000D03*
X1275900Y715200D03*
X1302500Y361300D03*
Y364700D03*
X1328100Y333300D03*
X1295000Y361300D03*
Y364700D03*
X1311500Y361300D03*
Y364700D03*
X1304884Y774232D03*
X1307684D03*
X1309884D03*
X1312684D03*
X1332500Y418300D03*
X1343000D03*
X1332500Y421700D03*
X1343000D03*
X1326300Y432000D03*
X1328700D03*
X1324600Y432200D03*
X1364200Y436500D03*
X1360800D03*
X1361700Y431000D03*
X1358300D03*
X1361700Y422000D03*
G54D198*
X387500Y945250D03*
G54D192*
X378750Y13500D03*
X375250D03*
Y19500D03*
X378750D03*
X1181427Y226500D03*
G54D195*
X308085Y221372D03*
Y217872D03*
X311885Y221372D03*
Y217872D03*
X304329Y336000D03*
Y332000D03*
X329385Y221872D03*
Y218372D03*
X404029Y241900D03*
Y245400D03*
G54D194*
X345929Y361900D03*
X342429D03*
X363555Y439100D03*
X359555D03*
X355555D03*
X351555D03*
X347555D03*
X343555D03*
X339555D03*
X335555D03*
X331555D03*
Y442900D03*
X335555D03*
X339555D03*
X343555D03*
X347555D03*
X351555D03*
X355555D03*
X359555D03*
X363555D03*
X342429Y313600D03*
Y333900D03*
Y348400D03*
G54D193*
X332550Y123100D03*
G54D200*
X585315Y44134D03*
X654527D03*
G54D204*
X1045000Y32598D03*
X1096732D03*
%LPD*%
G75*
G54D100*
X402953Y23622D03*
X413189D03*
X423425D03*
G54D110*
X639300Y612460D03*
Y609900D03*
Y607340D03*
X646700D03*
Y609900D03*
Y612460D03*
X866200Y636940D03*
Y639500D03*
Y642060D03*
X858800D03*
Y639500D03*
Y636940D03*
G54D101*
G01X343750Y893000D02*
X340000D01*
X339000Y894000D01*
G01X343750Y884500D02*
X340000D01*
X339000Y885500D01*
G01X343750Y878500D02*
X339000D01*
G01X395450Y265400D02*
X398750D01*
G01X396929Y257250D02*
Y262500D01*
X395450Y263979D01*
Y265400D01*
G01X406889Y332086D02*
X404920Y330117D01*
G01X414763Y332086D02*
X412794Y330117D01*
G01X406889Y336023D02*
X404920Y334054D01*
G01X414763Y336023D02*
X412794Y334054D01*
G01X410826Y343897D02*
X408857Y341928D01*
G01X414763Y343897D02*
X412794Y341928D01*
G01X410826Y359645D02*
X408857Y357676D01*
G01X410826Y367519D02*
X408857Y365550D01*
G01X414763Y367519D02*
X412794Y365550D01*
G01X414763Y359645D02*
X412794Y357676D01*
G01X410826Y375394D02*
X408857Y377363D01*
G01X410826Y383268D02*
X408857Y385237D01*
G01X410826Y391142D02*
X408857Y393111D01*
G01X410826Y399016D02*
X408857Y400985D01*
G01X414763Y399016D02*
X412794Y400985D01*
G01X414763Y391142D02*
X412794Y393111D01*
G01X414763Y383268D02*
X412794Y385237D01*
G01X410826Y406890D02*
X408857Y408859D01*
G01X414763Y414764D02*
X412794Y416733D01*
G01X414763Y406890D02*
X412794Y408859D01*
G01X410826Y422638D02*
X408857Y424607D01*
G01X414763Y422638D02*
X412794Y424607D01*
G01X430511Y332086D02*
X428542Y330117D01*
G01X422637Y332086D02*
X420668Y330117D01*
G01X422637Y336023D02*
X420668Y334054D01*
G01X428542D02*
X430511Y336023D01*
G01X426574Y347834D02*
X424605Y345865D01*
G01X430511Y347834D02*
X428542Y345865D01*
G01X426574Y355708D02*
X424605Y353739D01*
G01X426574Y363582D02*
X424605Y361613D01*
G01X426574Y371456D02*
X424605Y369487D01*
G01X430511Y363582D02*
X428542Y361613D01*
G01X430511Y355708D02*
X428542Y353739D01*
G01X418700Y355708D02*
X416731Y353739D01*
G01X426574Y383268D02*
X424605Y385237D01*
G01X430511Y383268D02*
X428542Y385237D01*
G01X430511Y371456D02*
X428542Y369487D01*
G01X422637Y399016D02*
X420668Y400985D01*
G01X430511Y395079D02*
X428542Y397048D01*
G01X426574Y391142D02*
X424605Y393111D01*
G01X426574Y399016D02*
X424605Y400985D01*
G01X430511Y399016D02*
X428542Y400985D01*
G01X418700Y414764D02*
X422637Y410827D01*
G01X416731Y416733D02*
X418700Y414764D01*
G01Y418701D02*
X416731Y420670D01*
G01X426574Y410827D02*
X424605Y412796D01*
G01X422637Y414764D02*
X424605Y412796D01*
G01X418700Y422638D02*
X416731Y424607D01*
G01X430511Y324212D02*
X430523Y324200D01*
Y320851D01*
X430513Y320841D01*
G01X440353Y330117D02*
X442322Y332086D01*
G01X434448Y324212D02*
Y320783D01*
G01X438385Y347834D02*
X436416Y345865D01*
G01X446259Y351771D02*
X444290Y349802D01*
G01X442322Y351771D02*
X440353Y349802D01*
G01X438385Y351771D02*
X440353Y353739D01*
G01X434448Y351771D02*
Y347834D01*
G01X446259Y343897D02*
X444290Y341928D01*
G01X446259Y347834D02*
X444290Y345865D01*
G01X442322Y347834D02*
X440353Y345865D01*
G01X434448Y363582D02*
X432479Y361613D01*
G01X434448Y371456D02*
X432479Y369487D01*
G01X446259Y359645D02*
X444290Y357676D01*
G01X442322Y355708D02*
X440353Y353739D01*
G01X446259Y367519D02*
X444290Y365550D01*
G01X442322Y371456D02*
X440353Y369487D01*
G01X434448Y359645D02*
Y359644D01*
X436416Y357676D01*
G01X438385Y367519D02*
X440353Y369487D01*
G01X434448Y367519D02*
X434447D01*
X432479Y369487D01*
G01X438385Y359645D02*
X436416Y357676D01*
G01X442322Y363582D02*
X438385Y359645D01*
G01X444290Y365550D02*
X442322Y363582D01*
G01X446259Y371456D02*
X444290Y369487D01*
G01X438385Y371456D02*
X436416Y369487D01*
G01X442322Y359645D02*
X440353Y357676D01*
G01X446259Y363582D02*
X442322Y359645D01*
G01X446259Y355708D02*
X444290Y353739D01*
G01X442322Y367519D02*
X440353Y365550D01*
G01X438385Y355708D02*
X436416Y353739D01*
G01X438385Y363582D02*
X436416Y361613D01*
G01X434448Y375394D02*
X432479Y377363D01*
G01X438385Y375394D02*
X436416Y377363D01*
G01X434448Y383268D02*
X432479Y385237D01*
G01X442322Y379331D02*
X440353Y381300D01*
G01X446259Y375394D02*
X444290Y377363D01*
G01X446259Y383268D02*
X444290Y385237D01*
G01X438385Y383268D02*
X440353Y381300D01*
G01X434448Y379331D02*
X432479Y381300D01*
G01X442322Y383268D02*
X444290Y381300D01*
G01X446259Y379331D02*
X444290Y381300D01*
G01X442322Y375394D02*
X440353Y377363D01*
G01X438385Y379331D02*
X436416Y381300D01*
G01X442322Y399016D02*
X440353Y400985D01*
G01X434448Y387205D02*
X432479Y389174D01*
G01X434448Y391142D02*
X432479Y393111D01*
G01X434448Y395079D02*
X432479Y397048D01*
G01X434448Y399016D02*
X432479Y400985D01*
G01X442322Y387205D02*
X440353Y389174D01*
G01X442322Y391142D02*
X442321D01*
X440353Y389174D01*
G01X438385Y391142D02*
X440353Y389174D01*
G01X446259Y395079D02*
X444290Y397048D01*
G01X442322Y395079D02*
X440353Y397048D01*
G01X438385Y395079D02*
X436416Y397048D01*
G01X446259Y399016D02*
X444290Y400985D01*
G01X438385Y399016D02*
X436416Y400985D01*
G01X446259Y387205D02*
X444290Y389174D01*
G01X438385Y387205D02*
X436416Y389174D01*
G01X442322Y410827D02*
X440353Y412796D01*
G01X438385Y414764D02*
X440353Y412796D01*
G01X434448Y410827D02*
X432479Y412796D01*
G01X430511Y414764D02*
X432479Y412796D01*
G01X458071Y332086D02*
X460040Y330117D01*
G01X450196Y332086D02*
X448227Y330117D01*
G01X450196Y343897D02*
X448227Y341928D01*
G01X458071Y343897D02*
X460040Y341928D01*
G01X462008Y343897D02*
X463977Y341928D01*
G01X454134Y343897D02*
X456103Y341928D01*
G01X454134Y367519D02*
X456103Y365550D01*
G01X450196Y363582D02*
X448227Y361613D01*
G01X450196Y371456D02*
X448227Y369487D01*
G01X462008Y359645D02*
X463977Y357676D01*
G01X458071Y363582D02*
X460040Y361613D01*
G01X462008Y367519D02*
X463977Y365550D01*
G01X458071Y371456D02*
X460040Y369487D01*
G01X454134Y371456D02*
X456103Y369487D01*
G01X462008Y363582D02*
X463977Y361613D01*
G01X454134Y355708D02*
X456103Y353739D01*
G01X454134Y363582D02*
X456103Y361613D01*
G01X462008Y355708D02*
X460040Y357676D01*
G01X458071Y359645D02*
X460040Y357676D01*
G01X458071Y367519D02*
X460040Y365550D01*
G01X450196Y367519D02*
X448227Y365550D01*
G01D02*
X446259Y363582D01*
G01X450196Y359645D02*
X448227Y357676D01*
G01X462008Y383268D02*
X463977Y385237D01*
G01X450196Y379331D02*
X448227Y381300D01*
G01X458071Y379331D02*
X460040Y381300D01*
G01X454134Y375394D02*
X456103Y377363D01*
G01X462008Y375394D02*
X463977Y377363D01*
G01X454134Y383268D02*
X456103Y385237D01*
G01X458071Y383268D02*
X460040Y385237D01*
G01X462008Y371456D02*
X463977Y369487D01*
G01X462008Y379331D02*
X463977Y381300D01*
G01X454134Y379331D02*
X456103Y381300D01*
G01X458071Y375394D02*
X460040Y377363D01*
G01X450196Y383268D02*
X448227Y385237D01*
G01X450196Y375394D02*
X448227Y377363D01*
G01X458071Y387205D02*
X460040Y389174D01*
G01X450196Y391142D02*
X448227Y393111D01*
G01X450196Y399016D02*
X448227Y400985D01*
G01X458071Y395079D02*
X460040Y397048D01*
G01X458071Y391142D02*
X460040Y393111D01*
G01X454134Y391142D02*
X456103Y393111D01*
G01X462008Y395079D02*
X463977Y397048D01*
G01X462008Y391142D02*
X463977Y393111D01*
G01X458071Y399016D02*
X460040Y400985D01*
G01X454134Y399016D02*
X456103Y400985D01*
G01X450196Y387205D02*
X448227Y389174D01*
G01X446259Y391142D02*
X448227Y389174D01*
G01X454134Y395079D02*
X456103Y397048D01*
G01X450196Y395079D02*
X448227Y397048D01*
G01X462008Y399016D02*
X463977Y400985D01*
G01X462008Y387205D02*
X463977Y389174D01*
G01X454134Y387205D02*
X456103Y389174D01*
G01X454134Y410827D02*
X456103Y412796D01*
G01X454134Y414764D02*
Y414772D01*
X452123Y416783D01*
G01X458071Y410827D02*
X460040Y412796D01*
G01X462008Y414764D02*
X460040Y412796D01*
G01X450196Y410827D02*
X448227Y412796D01*
G01X446259Y414764D02*
X448227Y412796D01*
G01X465945Y332086D02*
X467914Y330117D01*
G01X473819Y332086D02*
X475788Y330117D01*
G01X469882Y351771D02*
X471851Y349802D01*
G01X477756Y351771D02*
X479725Y349802D01*
G01X477756Y343897D02*
X479725Y341928D01*
G01X465945Y347834D02*
X467914Y345865D01*
G01X465945Y355708D02*
X467914Y353739D01*
G01X465945Y359645D02*
X467914Y357676D01*
G01X465945Y367519D02*
X467914Y365550D01*
G01X465945Y363582D02*
X467914Y361613D01*
G01X465945Y371456D02*
X467914Y369487D01*
G01X473819Y359645D02*
X475788Y357676D01*
G01X473819Y363582D02*
X475788Y361613D01*
G01X477756Y363582D02*
X479725Y361613D01*
G01X473819Y371456D02*
X475788Y369487D01*
G01X473819Y367519D02*
X473820D01*
X475788Y369487D01*
G01X469882Y363582D02*
X471851Y361613D01*
G01X469882Y367519D02*
X469883D01*
X471851Y369487D01*
G01X469882Y371456D02*
X471851Y369487D01*
G01X469882Y355708D02*
X471851Y353739D01*
G01X469882Y359645D02*
X471851Y357676D01*
G01X477756Y367519D02*
X479725Y365550D01*
G01X477756Y359645D02*
X479725Y357676D01*
G01X465945Y379331D02*
X467914Y381300D01*
G01X465945Y375394D02*
X467914Y377363D01*
G01X465945Y383268D02*
X467914Y385237D01*
G01X473819Y375394D02*
X475788Y377363D01*
G01X473819Y379331D02*
X475788Y381300D01*
G01X477756Y379331D02*
X479725Y381300D01*
G01X477756Y371456D02*
X479725Y369487D01*
G01X473819Y383268D02*
X473820D01*
X475788Y381300D01*
G01X469882Y383268D02*
Y383269D01*
X467914Y385237D01*
G01X469882Y375394D02*
X471851Y377363D01*
G01X469882Y379331D02*
X471851Y381300D01*
G01X477756Y375394D02*
X479725Y377363D01*
G01X477756Y383268D02*
X479725Y385237D01*
G01X465945Y387205D02*
X467914Y389174D01*
G01X465945Y391142D02*
X467914Y393111D01*
G01X465945Y395079D02*
X467914Y397048D01*
G01X465945Y399016D02*
X467914Y400985D01*
G01X473819Y387205D02*
X475788Y389174D01*
G01X477756Y387205D02*
X479725Y389174D01*
G01X469882Y395079D02*
X471851Y397048D01*
G01X469882Y391142D02*
X471851Y393111D01*
G01X473819Y391142D02*
X475788Y393111D01*
G01X473819Y395079D02*
X475788Y397048D01*
G01X477756Y395079D02*
X479725Y397048D01*
G01X473819Y399016D02*
X475788Y400985D01*
G01X469882Y387205D02*
X471851Y389174D01*
G01X477756Y391142D02*
X479725Y393111D01*
G01X469882Y399016D02*
X471851Y400985D01*
G01X477756Y399016D02*
X479725Y400985D01*
G01X469882Y410827D02*
X471851Y412796D01*
G01X477756Y410827D02*
X479725Y412796D01*
G01X465945Y410827D02*
X467914Y412796D01*
G01X469882Y414764D02*
X471851Y416733D01*
G01X473819Y410827D02*
X475788Y412796D01*
G01X477756Y414764D02*
X479725Y416733D01*
G01X473819Y422638D02*
X475788Y424607D01*
G01X489567Y328149D02*
X493504Y324212D01*
G01X489567Y336023D02*
X491536Y334054D01*
G01X495473D02*
X493504Y336023D01*
G01D02*
X492527Y337000D01*
X492055D01*
X489567Y339488D01*
Y339960D01*
G01Y343897D02*
X491536Y341928D01*
G01X493504Y351771D02*
X489567Y347834D01*
G01X495473Y341928D02*
X493504Y343897D01*
G01D02*
X489567Y347834D01*
G01X493504Y367519D02*
X491536Y369487D01*
G01X489567Y371456D02*
X491536Y369487D01*
G01X493504Y359645D02*
X491536Y361613D01*
G01X489567Y355708D02*
X493504Y359645D01*
G01X489567Y363582D02*
X491536Y361613D01*
G01X489567Y375394D02*
X491536Y377363D01*
G01X489567Y383268D02*
X491536Y385237D01*
G01X489567Y379331D02*
X491536Y381300D01*
G01X493504Y375394D02*
X495473Y377363D01*
G01X493504Y383268D02*
X495473Y385237D01*
G01X489567Y391142D02*
X491536Y393111D01*
G01X489567Y399016D02*
X491536Y400985D01*
G01X489567Y387205D02*
X491536Y389174D01*
G01X489567Y395079D02*
X491536Y397048D01*
G01X493504Y391142D02*
X495473Y393111D01*
G01X493504Y399016D02*
X495473Y400985D01*
G01X485630Y402953D02*
X487599Y404922D01*
G01X481693Y406890D02*
X483662Y408859D01*
G01X485630Y414764D02*
X487599Y416733D01*
G01X489567Y406890D02*
X491536Y408859D01*
G01X493504Y406890D02*
X495473Y408859D01*
G01X493504Y410827D02*
X495473Y412796D01*
G01X489567Y414764D02*
X491536Y416733D01*
G01X489567Y418701D02*
X491536Y420670D01*
G01X481693Y402953D02*
X483662Y404922D01*
G01X481693Y410827D02*
X483662Y412796D01*
G01X485630Y418701D02*
X487599Y420670D01*
G01X489567Y402953D02*
X491536Y404922D01*
G01X489567Y410827D02*
X491536Y412796D01*
G01X485630Y422638D02*
X487599Y424607D01*
G01X481693Y422638D02*
X483662Y424607D01*
G01X489567Y422638D02*
X491536Y424607D01*
G01X501378Y332086D02*
X505523D01*
G01X501378Y339960D02*
X510195D01*
X511455Y338700D01*
G01X501378Y379331D02*
X503347Y381300D01*
G01X501378Y387205D02*
X503347Y389174D01*
G01X501378Y395079D02*
X503347Y397048D01*
G01X501378Y402953D02*
X503347Y404922D01*
G01X501378Y406890D02*
X503347Y408859D01*
G01X497441Y406890D02*
X499410Y408859D01*
G01X497441Y410827D02*
X499410Y412796D01*
G01X849750Y638500D02*
X850940D01*
X852500Y636940D01*
X410826Y336023D03*
X406889D03*
X402952D03*
X410826Y351771D03*
Y347834D03*
Y343897D03*
Y339960D03*
X406889Y351771D03*
Y347834D03*
Y343897D03*
Y339960D03*
X402952Y351771D03*
Y347834D03*
Y343897D03*
Y339960D03*
X410826Y367519D03*
Y363582D03*
Y359645D03*
Y355708D03*
X406889Y367519D03*
Y363582D03*
Y359645D03*
Y355708D03*
X402952Y367519D03*
Y363582D03*
Y359645D03*
Y355708D03*
X410826Y383268D03*
Y379331D03*
Y375394D03*
Y371456D03*
X406889Y383268D03*
Y379331D03*
Y375394D03*
Y371456D03*
X402952Y383268D03*
Y379331D03*
Y375394D03*
Y371456D03*
X410826Y399016D03*
Y395079D03*
Y391142D03*
Y387205D03*
X406889Y399016D03*
Y395079D03*
Y391142D03*
Y387205D03*
X402952Y399016D03*
Y395079D03*
Y391142D03*
Y387205D03*
X410826Y410827D03*
Y406890D03*
Y402953D03*
X406889Y410827D03*
Y406890D03*
Y402953D03*
X402952Y410827D03*
Y406890D03*
Y402953D03*
X426574Y336023D03*
Y332086D03*
Y328149D03*
Y324212D03*
X422637Y336023D03*
Y332086D03*
Y328149D03*
Y324212D03*
X418700Y336023D03*
Y332086D03*
Y328149D03*
Y324212D03*
X414763Y336023D03*
Y332086D03*
Y328149D03*
Y324212D03*
X426574Y351771D03*
Y347834D03*
Y343897D03*
Y339960D03*
X422637Y351771D03*
Y347834D03*
Y343897D03*
Y339960D03*
X418700Y351771D03*
Y347834D03*
Y343897D03*
Y339960D03*
X414763Y351771D03*
Y347834D03*
Y343897D03*
Y339960D03*
X426574Y367519D03*
Y363582D03*
Y359645D03*
Y355708D03*
X422637Y367519D03*
Y363582D03*
Y359645D03*
Y355708D03*
X418700Y367519D03*
Y363582D03*
Y359645D03*
Y355708D03*
X414763Y367519D03*
Y363582D03*
Y359645D03*
Y355708D03*
X426574Y383268D03*
Y379331D03*
Y375394D03*
Y371456D03*
X422637Y383268D03*
Y379331D03*
Y375394D03*
Y371456D03*
X418700Y383268D03*
Y379331D03*
Y375394D03*
Y371456D03*
X414763Y383268D03*
Y379331D03*
Y375394D03*
Y371456D03*
X426574Y399016D03*
Y395079D03*
Y391142D03*
Y387205D03*
X422637Y399016D03*
Y395079D03*
Y391142D03*
Y387205D03*
X418700Y399016D03*
Y395079D03*
Y391142D03*
Y387205D03*
X414763Y399016D03*
Y395079D03*
Y391142D03*
Y387205D03*
X426574Y414764D03*
Y410827D03*
Y406890D03*
Y402953D03*
X422637Y414764D03*
Y410827D03*
Y406890D03*
Y402953D03*
X418700Y414764D03*
Y410827D03*
Y406890D03*
Y402953D03*
X414763Y414764D03*
Y410827D03*
Y406890D03*
Y402953D03*
X426574Y422638D03*
Y418701D03*
X422637Y422638D03*
Y418701D03*
X418700Y422638D03*
Y418701D03*
X414763Y422638D03*
Y418701D03*
X442322Y336023D03*
Y332086D03*
Y328149D03*
Y324212D03*
X438385Y336023D03*
Y332086D03*
Y328149D03*
Y324212D03*
X434448Y336023D03*
Y332086D03*
Y328149D03*
Y324212D03*
X430511Y336023D03*
Y332086D03*
Y328149D03*
Y324212D03*
X442322Y351771D03*
Y347834D03*
Y343897D03*
Y339960D03*
X438385Y351771D03*
Y347834D03*
Y343897D03*
Y339960D03*
X434448Y351771D03*
Y347834D03*
Y343897D03*
Y339960D03*
X430511Y351771D03*
Y347834D03*
Y343897D03*
Y339960D03*
X442322Y367519D03*
Y363582D03*
Y359645D03*
Y355708D03*
X438385Y367519D03*
Y363582D03*
Y359645D03*
Y355708D03*
X434448Y367519D03*
Y363582D03*
Y359645D03*
Y355708D03*
X430511Y367519D03*
Y363582D03*
Y359645D03*
Y355708D03*
X442322Y383268D03*
Y379331D03*
Y375394D03*
Y371456D03*
X438385Y383268D03*
Y379331D03*
Y375394D03*
Y371456D03*
X434448Y383268D03*
Y379331D03*
Y375394D03*
Y371456D03*
X430511Y383268D03*
Y379331D03*
Y375394D03*
Y371456D03*
X442322Y399016D03*
Y395079D03*
Y391142D03*
Y387205D03*
X438385Y399016D03*
Y395079D03*
Y391142D03*
Y387205D03*
X434448Y399016D03*
Y395079D03*
Y391142D03*
Y387205D03*
X430511Y399016D03*
Y395079D03*
Y391142D03*
Y387205D03*
X442322Y414764D03*
Y410827D03*
Y406890D03*
Y402953D03*
X438385Y414764D03*
Y410827D03*
Y406890D03*
Y402953D03*
X434448Y414764D03*
Y410827D03*
Y406890D03*
Y402953D03*
X430511Y414764D03*
Y410827D03*
Y406890D03*
Y402953D03*
X442322Y422638D03*
Y418701D03*
X438385Y422638D03*
Y418701D03*
X434448Y422638D03*
Y418701D03*
X430511Y422638D03*
Y418701D03*
X458071Y336023D03*
Y332086D03*
Y328149D03*
Y324212D03*
X454134Y336023D03*
Y332086D03*
Y328149D03*
Y324212D03*
X450196Y336023D03*
Y332086D03*
Y328149D03*
Y324212D03*
X446259Y336023D03*
Y332086D03*
Y328149D03*
Y324212D03*
X458071Y351771D03*
Y347834D03*
Y343897D03*
Y339960D03*
X454134Y351771D03*
Y347834D03*
Y343897D03*
Y339960D03*
X450196Y351771D03*
Y347834D03*
Y343897D03*
Y339960D03*
X446259Y351771D03*
Y347834D03*
Y343897D03*
Y339960D03*
X458071Y367519D03*
Y363582D03*
Y359645D03*
Y355708D03*
X454134Y367519D03*
Y363582D03*
Y359645D03*
Y355708D03*
X450196Y367519D03*
Y363582D03*
Y359645D03*
Y355708D03*
X446259Y367519D03*
Y363582D03*
Y359645D03*
Y355708D03*
X458071Y383268D03*
Y379331D03*
Y375394D03*
Y371456D03*
X454134Y383268D03*
Y379331D03*
Y375394D03*
Y371456D03*
X450196Y383268D03*
Y379331D03*
Y375394D03*
Y371456D03*
X446259Y383268D03*
Y379331D03*
Y375394D03*
Y371456D03*
X458071Y399016D03*
Y395079D03*
Y391142D03*
Y387205D03*
X454134Y399016D03*
Y395079D03*
Y391142D03*
Y387205D03*
X450196Y399016D03*
Y395079D03*
Y391142D03*
Y387205D03*
X446259Y399016D03*
Y395079D03*
Y391142D03*
Y387205D03*
X458071Y414764D03*
Y410827D03*
Y406890D03*
Y402953D03*
X454134Y414764D03*
Y410827D03*
Y406890D03*
Y402953D03*
X450196Y414764D03*
Y410827D03*
Y406890D03*
Y402953D03*
X446259Y414764D03*
Y410827D03*
Y406890D03*
Y402953D03*
X458071Y422638D03*
Y418701D03*
X454134Y422638D03*
Y418701D03*
X450196Y422638D03*
Y418701D03*
X446259Y422638D03*
Y418701D03*
X477756Y336023D03*
Y332086D03*
Y328149D03*
Y324212D03*
X473819Y336023D03*
Y332086D03*
Y328149D03*
Y324212D03*
X469882Y336023D03*
Y332086D03*
Y328149D03*
Y324212D03*
X465945Y336023D03*
Y332086D03*
Y328149D03*
Y324212D03*
X462008Y336023D03*
Y332086D03*
Y328149D03*
Y324212D03*
X477756Y351771D03*
Y347834D03*
Y343897D03*
Y339960D03*
X473819Y351771D03*
Y347834D03*
Y343897D03*
Y339960D03*
X469882Y351771D03*
Y347834D03*
Y343897D03*
Y339960D03*
X465945Y351771D03*
Y347834D03*
Y343897D03*
Y339960D03*
X462008Y351771D03*
Y347834D03*
Y343897D03*
Y339960D03*
X477756Y367519D03*
Y363582D03*
Y359645D03*
Y355708D03*
X473819Y367519D03*
Y363582D03*
Y359645D03*
Y355708D03*
X469882Y367519D03*
Y363582D03*
Y359645D03*
Y355708D03*
X465945Y367519D03*
Y363582D03*
Y359645D03*
Y355708D03*
X462008Y367519D03*
Y363582D03*
Y359645D03*
Y355708D03*
X477756Y383268D03*
Y379331D03*
Y375394D03*
Y371456D03*
X473819Y383268D03*
Y379331D03*
Y375394D03*
Y371456D03*
X469882Y383268D03*
Y379331D03*
Y375394D03*
Y371456D03*
X465945Y383268D03*
Y379331D03*
Y375394D03*
Y371456D03*
X462008Y383268D03*
Y379331D03*
Y375394D03*
Y371456D03*
X477756Y399016D03*
Y395079D03*
Y391142D03*
Y387205D03*
X473819Y399016D03*
Y395079D03*
Y391142D03*
Y387205D03*
X469882Y399016D03*
Y395079D03*
Y391142D03*
Y387205D03*
X465945Y399016D03*
Y395079D03*
Y391142D03*
Y387205D03*
X462008Y399016D03*
Y395079D03*
Y391142D03*
Y387205D03*
X477756Y414764D03*
Y410827D03*
Y406890D03*
Y402953D03*
X473819Y414764D03*
Y410827D03*
Y406890D03*
Y402953D03*
X469882Y414764D03*
Y410827D03*
Y406890D03*
Y402953D03*
X465945Y414764D03*
Y410827D03*
Y406890D03*
Y402953D03*
X462008Y414764D03*
Y410827D03*
Y406890D03*
Y402953D03*
X477756Y422638D03*
Y418701D03*
X473819Y422638D03*
Y418701D03*
X469882Y422638D03*
Y418701D03*
X465945Y422638D03*
Y418701D03*
X462008Y422638D03*
Y418701D03*
X493504Y336023D03*
X489567D03*
Y332086D03*
Y328149D03*
Y324212D03*
X485630Y336023D03*
Y332086D03*
Y328149D03*
Y324212D03*
X481693Y336023D03*
Y332086D03*
Y328149D03*
Y324212D03*
X493504Y351771D03*
Y347834D03*
Y343897D03*
Y339960D03*
X489567Y351771D03*
Y347834D03*
Y343897D03*
Y339960D03*
X485630Y351771D03*
Y347834D03*
Y343897D03*
Y339960D03*
X481693Y351771D03*
Y347834D03*
Y343897D03*
Y339960D03*
X493504Y367519D03*
Y363582D03*
Y359645D03*
Y355708D03*
X489567Y367519D03*
Y363582D03*
Y359645D03*
Y355708D03*
X485630Y367519D03*
Y363582D03*
Y359645D03*
Y355708D03*
X481693Y367519D03*
Y363582D03*
Y359645D03*
Y355708D03*
X493504Y383268D03*
Y379331D03*
Y375394D03*
Y371456D03*
X489567Y383268D03*
Y379331D03*
Y375394D03*
Y371456D03*
X485630Y383268D03*
Y379331D03*
Y375394D03*
Y371456D03*
X481693Y383268D03*
Y379331D03*
Y375394D03*
Y371456D03*
X493504Y399016D03*
Y395079D03*
Y391142D03*
Y387205D03*
X489567Y399016D03*
Y395079D03*
Y391142D03*
Y387205D03*
X485630Y399016D03*
Y395079D03*
Y391142D03*
Y387205D03*
X481693Y399016D03*
Y395079D03*
Y391142D03*
Y387205D03*
X493504Y410827D03*
Y406890D03*
Y402953D03*
X489567Y414764D03*
Y410827D03*
Y406890D03*
Y402953D03*
X485630Y414764D03*
Y410827D03*
Y406890D03*
Y402953D03*
X481693Y414764D03*
Y410827D03*
Y406890D03*
Y402953D03*
X489567Y422638D03*
Y418701D03*
X485630Y422638D03*
Y418701D03*
X481693Y422638D03*
Y418701D03*
X501378Y336023D03*
X497441D03*
X501378Y351771D03*
Y347834D03*
Y343897D03*
Y339960D03*
X497441Y351771D03*
Y347834D03*
Y343897D03*
Y339960D03*
X501378Y367519D03*
Y363582D03*
Y359645D03*
Y355708D03*
X497441Y367519D03*
Y363582D03*
Y359645D03*
Y355708D03*
X501378Y383268D03*
Y379331D03*
Y375394D03*
Y371456D03*
X497441Y383268D03*
Y379331D03*
Y375394D03*
Y371456D03*
X501378Y399016D03*
Y395079D03*
Y391142D03*
Y387205D03*
X497441Y399016D03*
Y395079D03*
Y391142D03*
Y387205D03*
X501378Y410827D03*
Y406890D03*
Y402953D03*
X497441Y410827D03*
Y406890D03*
Y402953D03*
G54D102*
X444177Y299000D03*
Y291000D03*
X452977Y295000D03*
G54D120*
X698818Y764644D03*
Y767204D03*
Y769764D03*
Y772324D03*
X696818Y800144D03*
Y802704D03*
Y805264D03*
Y807824D03*
X715118Y772324D03*
Y769764D03*
Y767204D03*
Y764644D03*
X713118Y807824D03*
Y805264D03*
Y802704D03*
Y800144D03*
G54D111*
X655750Y462500D03*
G54D112*
X653250D03*
G54D121*
X706560Y876750D03*
X704000D03*
X701440D03*
Y870250D03*
X706560D03*
X724940Y464572D03*
X730060D03*
Y471072D03*
X727500D03*
X724940D03*
X788060Y871250D03*
X785500D03*
X782940D03*
Y864750D03*
X788060D03*
X1101986Y823344D03*
Y816844D03*
X1107106Y823344D03*
X1104546D03*
X1107106Y816844D03*
X1195940Y862250D03*
X1198500D03*
X1195940Y868750D03*
X1208940Y862250D03*
X1211500D03*
X1214060D03*
X1201060D03*
X1214060Y868750D03*
X1208940D03*
X1201060D03*
X1240660Y840850D03*
X1238100D03*
X1235540D03*
Y834350D03*
X1240660D03*
G54D103*
X479923Y298683D03*
Y306883D03*
X494123Y298683D03*
Y306883D03*
G54D130*
X761966Y183784D03*
X769466Y179909D03*
Y187659D03*
X775534Y658532D03*
X783034Y654657D03*
Y662407D03*
X885750Y56500D03*
X893250Y52625D03*
Y60375D03*
X1256250Y559000D03*
X1263750Y562875D03*
Y555125D03*
X1256350Y844100D03*
X1263850Y840225D03*
Y847975D03*
G54D10*
X8590Y318590D03*
X4500Y329297D03*
Y349297D03*
Y369297D03*
Y389297D03*
Y409297D03*
Y429297D03*
Y449297D03*
Y469297D03*
Y489297D03*
Y509297D03*
Y529297D03*
Y549297D03*
Y569297D03*
Y589297D03*
Y609297D03*
Y629297D03*
Y649297D03*
Y669297D03*
Y689297D03*
Y709297D03*
Y729297D03*
Y749297D03*
Y769297D03*
Y789297D03*
Y809297D03*
Y829297D03*
Y849297D03*
Y869297D03*
Y889297D03*
Y909297D03*
Y929297D03*
Y949297D03*
Y969297D03*
X20000Y380000D03*
Y440000D03*
Y460000D03*
Y480000D03*
Y500000D03*
X25500Y836000D03*
X32304Y834720D03*
X30500Y855000D03*
X28790Y880734D03*
X25304Y899220D03*
X29804Y904220D03*
X25000Y980000D03*
X51304Y875720D03*
X51043Y889981D03*
X42000Y884000D03*
X36054Y910720D03*
X45000Y980000D03*
X66860Y648370D03*
X67304Y715720D03*
X62804Y722720D03*
X55304Y742720D03*
X60804Y843720D03*
X56304Y888720D03*
X63304Y882220D03*
X55000Y975000D03*
X65000Y980000D03*
X80926Y644426D03*
X74500Y644000D03*
X69500Y642500D03*
X76000Y652500D03*
X70500Y651500D03*
X79500Y656500D03*
X82000Y650500D03*
X81304Y722220D03*
X78304Y759720D03*
X71804Y801720D03*
X80304Y847220D03*
X70304Y889720D03*
X75000Y975000D03*
X98304Y721720D03*
X93347Y722263D03*
X90304Y766720D03*
X100104Y793820D03*
X96704Y809720D03*
X96404Y797320D03*
X96804Y840720D03*
X96304Y846720D03*
X93043Y883220D03*
X90488Y888720D03*
X85495Y892029D03*
X95603Y890421D03*
X95000Y975000D03*
X116000Y628000D03*
X111500Y618500D03*
X106500Y630500D03*
X112000Y636000D03*
X103804Y755720D03*
X106004Y886970D03*
X123406Y327453D03*
X121000Y545500D03*
Y612500D03*
X133500Y618500D03*
X119500Y621000D03*
X133500Y657500D03*
X130000Y678500D03*
X134000Y686500D03*
X131204Y789970D03*
X133004Y802520D03*
X133104Y807420D03*
X133174Y796750D03*
X146364Y296000D03*
X141500Y615000D03*
X150000Y650500D03*
X140000Y720000D03*
Y740000D03*
X145000Y792000D03*
X149250Y851750D03*
X148500Y884500D03*
X164300Y453800D03*
X159200Y470300D03*
X159500Y475500D03*
X161805Y525750D03*
X154500Y686500D03*
X156500Y939500D03*
X162000D03*
X176400Y454200D03*
X169500Y462800D03*
X175900Y463000D03*
X182800Y474800D03*
X177555Y530000D03*
X169555D03*
X168000Y575000D03*
Y580000D03*
X178000Y590000D03*
X171500Y681500D03*
X180000Y760000D03*
X179500Y843500D03*
X175000Y861000D03*
X167500Y939500D03*
X172500D03*
X177500D03*
X182000D03*
X195800Y530000D03*
X188955Y534100D03*
X193115Y545060D03*
X195555Y558060D03*
X186000Y818000D03*
X199750Y864750D03*
X188000Y939500D03*
X193500D03*
X199500D03*
X208000Y506500D03*
X215153Y521183D03*
X215055Y556500D03*
X214555Y564000D03*
X207100Y703600D03*
X211500Y842000D03*
X204500Y842500D03*
X204000Y850000D03*
X200016Y859484D03*
X205000Y856000D03*
X203500Y878500D03*
X212500Y876000D03*
X204500Y868500D03*
X216000Y879500D03*
X208000Y925500D03*
X206000Y982000D03*
X224148Y577400D03*
X221805Y569750D03*
X222000Y703500D03*
X220000Y760000D03*
X217000Y807500D03*
X218500Y839500D03*
X228890Y838890D03*
X224000Y838500D03*
Y875000D03*
X221016Y876984D03*
X228500Y895000D03*
X225500Y879500D03*
X230000D03*
X226000Y900000D03*
X225000Y920500D03*
X232000Y921000D03*
X227500Y957500D03*
Y963500D03*
X226000Y982000D03*
X245000Y427000D03*
X234000Y558500D03*
X235000Y839000D03*
X239000Y853000D03*
X240000Y858500D03*
X239500Y847500D03*
X235500Y875500D03*
X247500Y883000D03*
X243000D03*
X237000Y919900D03*
X246968Y957784D03*
X233468Y957284D03*
X239968Y957784D03*
X246968Y963784D03*
X239968D03*
X233468D03*
X246000Y982000D03*
X254500Y184000D03*
X261500Y188900D03*
X256300Y188800D03*
X258800Y184200D03*
X261400Y179800D03*
X255800Y179600D03*
X261500Y203000D03*
X259000Y211000D03*
Y206000D03*
X262500Y208500D03*
X260000Y260000D03*
X250500Y419000D03*
X264500Y422078D03*
X264409Y439354D03*
X260000Y760000D03*
X263000Y879000D03*
X252000Y883000D03*
X256500D03*
X261000D03*
X265500D03*
X265000Y893000D03*
X252000Y957500D03*
X252500Y963500D03*
X262178Y976000D03*
X261178Y981040D03*
X281800Y183700D03*
Y188500D03*
X281900Y178500D03*
X277000Y194500D03*
X271500Y888500D03*
X281000Y882500D03*
X277500Y902800D03*
X278500Y965000D03*
X277500Y969500D03*
X272500D03*
X268000D03*
X296000Y105000D03*
X285800Y180800D03*
X285600Y186100D03*
X285500Y330000D03*
X286000Y336000D03*
X287929Y356500D03*
X285678Y995500D03*
X293178D03*
X299500Y5500D03*
X311500Y71500D03*
X310000Y84500D03*
X302000Y97500D03*
X306000Y105000D03*
X301000D03*
X310929Y257500D03*
X311500Y272000D03*
X306429Y310000D03*
X311429Y334500D03*
X307429Y336000D03*
Y331500D03*
X312929Y382000D03*
X299055Y419500D03*
X301178Y995500D03*
X309678D03*
X320500Y11000D03*
X316000D03*
X324000Y24000D03*
Y19500D03*
Y15000D03*
X321000Y29000D03*
Y33500D03*
Y38000D03*
X330500Y38500D03*
Y33500D03*
X321000Y57000D03*
Y52500D03*
Y48000D03*
Y42500D03*
Y61500D03*
X330000Y90500D03*
X315000Y89000D03*
X317147Y93294D03*
X315929Y253000D03*
X316000Y271500D03*
X315929Y257500D03*
X322429Y349300D03*
X326555Y425500D03*
X325224Y455669D03*
X329055Y548500D03*
X324678Y995500D03*
X317178D03*
X344000Y27000D03*
X336000D03*
X347500Y66000D03*
X343000Y77500D03*
X337000Y90500D03*
X337500Y102000D03*
X342429Y327500D03*
X346500Y341500D03*
X335645Y445630D03*
X347055Y468450D03*
X336055Y552000D03*
X339888Y611888D03*
X340500Y873600D03*
X335500Y881500D03*
X338000Y907000D03*
X341000Y902500D03*
X336000Y899500D03*
X340300Y948500D03*
X341178Y996000D03*
X332678Y995500D03*
X349000Y38500D03*
Y33500D03*
X362500Y64000D03*
X360200Y77400D03*
X357429Y237500D03*
X352929Y242000D03*
X361929D03*
X351929Y266000D03*
X352429Y279000D03*
X357929Y277000D03*
X347929Y321500D03*
X353429Y344000D03*
X357661Y434216D03*
X364055Y428500D03*
X361055Y431500D03*
X351555Y465480D03*
X354988Y456325D03*
X350055Y484623D03*
X351055Y550500D03*
X362500Y608500D03*
X355500D03*
Y614000D03*
X362500D03*
X361500Y880500D03*
X358500Y884500D03*
X360900Y890100D03*
X362780Y895220D03*
X361178Y991000D03*
X358268Y995500D03*
X348678Y996000D03*
X370000Y51000D03*
Y55500D03*
Y60000D03*
X370500Y72100D03*
X375429Y237500D03*
X366429Y238000D03*
X370929Y242000D03*
X378429D03*
X366000Y277500D03*
X374000Y392500D03*
X369500Y401000D03*
X370155Y463000D03*
X366500Y549500D03*
X376500Y608500D03*
X369500D03*
Y614000D03*
X376500D03*
X378500Y812000D03*
Y824500D03*
X373000Y915000D03*
X374018Y991000D03*
X377953Y995725D03*
X393800Y25100D03*
X389300Y20100D03*
X393800D03*
X384800Y25100D03*
X389300D03*
X384800Y20100D03*
X391000Y35500D03*
X395500D03*
X393900Y30400D03*
X389400D03*
X384900D03*
X386000Y53000D03*
X381500D03*
Y58000D03*
X381000Y63500D03*
X381429Y237500D03*
X386500D03*
X384500Y243000D03*
X388055Y307500D03*
X384055Y311500D03*
Y317000D03*
X392555Y309500D03*
X386555Y333000D03*
X384000Y323000D03*
X388829Y328323D03*
X384055Y339500D03*
X383555Y353000D03*
X385055Y347500D03*
X384055Y371000D03*
X380500Y393000D03*
X385023Y387783D03*
X388023Y412283D03*
X391000Y417500D03*
X383555Y403000D03*
X382500Y413000D03*
X384504Y408000D03*
X387555Y459700D03*
X394155Y460000D03*
X390555Y455500D03*
X395000Y877500D03*
X389000D03*
X380500Y915000D03*
X389763Y996085D03*
X398300Y20100D03*
Y25100D03*
X400000Y35500D03*
X398400Y30400D03*
X398000Y39500D03*
X397500Y249000D03*
X410400Y242116D03*
X401429Y244400D03*
X402800Y282700D03*
X399755Y295700D03*
X409000Y295500D03*
X404000Y290500D03*
X406055Y307500D03*
X401555Y309500D03*
X411555D03*
X397055Y307500D03*
X403155Y437600D03*
X406500Y713500D03*
X412000Y724000D03*
X409500Y775500D03*
X398000Y885000D03*
X411500Y893000D03*
X406000Y895500D03*
X411000Y898500D03*
X407500Y903775D03*
X398500Y908000D03*
X427000Y111000D03*
X424500Y116000D03*
X423500Y122000D03*
X428375Y122635D03*
X415100Y235900D03*
X417970Y231884D03*
X416200Y245300D03*
X429429Y252900D03*
X425000Y245500D03*
X419205Y240000D03*
X426555Y271500D03*
X418755Y290000D03*
X426470Y299463D03*
X416555Y307500D03*
X425755Y309800D03*
X429355Y306100D03*
X422500Y764500D03*
X438429Y100500D03*
X440000Y115000D03*
X434209Y232474D03*
X434000Y244500D03*
X438000Y300500D03*
X433500Y297500D03*
X439055Y309900D03*
X445855Y309200D03*
X437155Y305300D03*
X442155Y306000D03*
X432955Y309700D03*
X445395Y317610D03*
X431000Y713500D03*
Y724000D03*
X432678Y827300D03*
X430778Y864000D03*
X435678Y996000D03*
X443178D03*
X446500Y120500D03*
X459283Y169140D03*
X461500Y157000D03*
X457934Y164526D03*
X458929Y180500D03*
X458529Y189761D03*
X457500Y199500D03*
X461000Y215000D03*
X461500Y224500D03*
X457500Y269400D03*
X456170Y281419D03*
X459000Y302000D03*
X453500Y303500D03*
X448000Y304500D03*
X452055Y308500D03*
X457055Y308000D03*
X460055Y312000D03*
X453878Y824900D03*
X456278Y866500D03*
X458678Y996000D03*
X450178D03*
X463000Y117500D03*
X465500Y122500D03*
X467000Y118500D03*
X466000Y137000D03*
X462429Y133500D03*
X466000Y130000D03*
X462500Y126500D03*
X463500Y141500D03*
X466500Y155500D03*
X466000Y176500D03*
X465055Y313500D03*
X477500Y715000D03*
X474178Y995500D03*
X466178Y996000D03*
X482429Y139000D03*
X491500Y715000D03*
X490500Y800000D03*
X482778Y832000D03*
X482278Y867500D03*
X495000Y883000D03*
X489678Y995500D03*
X482178D03*
X511200Y412600D03*
X511255Y420200D03*
X504500Y715000D03*
X502500Y800000D03*
X501000Y876000D03*
X499000Y883000D03*
X505678Y995500D03*
X498178D03*
X516000Y134000D03*
X519929Y135500D03*
X524635Y212188D03*
X521055Y528500D03*
Y533500D03*
X516555Y528500D03*
Y533500D03*
X526055D03*
X526000Y524500D03*
Y529000D03*
X521000Y524000D03*
X521055Y544000D03*
Y548900D03*
X516555Y543500D03*
X516655Y548900D03*
X521055Y538500D03*
X516555Y539000D03*
X526055Y538500D03*
Y544000D03*
Y548900D03*
X516500Y556000D03*
X521178Y995500D03*
X513678D03*
X537500Y154750D03*
X538500Y160000D03*
X543600Y161020D03*
X536678Y996000D03*
X530083Y995500D03*
X560000Y20000D03*
X556500Y158500D03*
X552000Y161000D03*
X560355Y333600D03*
X559555Y362500D03*
X553055Y364500D03*
X560678Y996000D03*
X567429Y159500D03*
X572629D03*
X562231Y159650D03*
X567500Y457500D03*
X563000Y453000D03*
X567500D03*
Y462000D03*
Y466500D03*
X563000Y457500D03*
Y462000D03*
Y466500D03*
X569178Y996000D03*
X576678D03*
X592500Y205000D03*
Y217500D03*
X593000Y212500D03*
X592500Y223000D03*
X591000Y253500D03*
Y262500D03*
X586000Y267000D03*
Y262500D03*
X591000Y258000D03*
X586150Y383000D03*
X586200Y378500D03*
X581950Y383000D03*
X582000Y378500D03*
X590500Y383000D03*
X586150Y396000D03*
X590500D03*
X581950D03*
X586150Y409500D03*
X581950D03*
X590500D03*
X582700Y431500D03*
X590500Y423500D03*
X586150D03*
X587000Y431500D03*
X578500D03*
X581950Y423500D03*
X582200Y439500D03*
X578000D03*
X586500D03*
X593500Y648500D03*
Y659500D03*
Y654000D03*
X584678Y994500D03*
X597000Y196500D03*
X595500Y253500D03*
Y258000D03*
X610500Y333000D03*
X606000Y341500D03*
X609000Y345500D03*
X610000Y415500D03*
Y434000D03*
Y428500D03*
Y422000D03*
X610100Y439500D03*
X602500Y465900D03*
X608000Y465800D03*
X602500Y470100D03*
X608000Y470300D03*
X601000Y543000D03*
X599500Y648500D03*
Y654000D03*
Y659500D03*
X604500Y714500D03*
X609500Y778500D03*
X603000D03*
Y785000D03*
X609000Y870000D03*
X604000Y877500D03*
X609211Y877611D03*
X606000Y918500D03*
X598178Y983500D03*
X615000Y333000D03*
X620500D03*
X611500Y341500D03*
X613500Y345500D03*
X616500Y341500D03*
X621500D03*
X614200Y415500D03*
X614500Y434000D03*
X614200Y422000D03*
Y428500D03*
X614300Y439500D03*
X620000Y465800D03*
X613500D03*
X626500D03*
X613500Y470000D03*
X620000D03*
X626500D03*
Y557350D03*
X618950Y597000D03*
X616500Y714500D03*
X613500Y744500D03*
Y759000D03*
X620500Y848500D03*
X642000Y335000D03*
X639000Y332000D03*
X637500Y367900D03*
X630500Y368500D03*
X642000D03*
X638500Y409000D03*
X634500Y427000D03*
X637000Y431500D03*
X632500D03*
X637000Y436500D03*
X632500D03*
X638100Y462500D03*
X632000Y571000D03*
X631000Y603000D03*
X631500Y617000D03*
X634000Y734500D03*
X633500Y749500D03*
X630500Y912000D03*
X650000Y110000D03*
X647500Y368500D03*
X653500D03*
X659500D03*
X651500Y408500D03*
X646500D03*
X655751Y448519D03*
X644000Y453000D03*
X645500Y481000D03*
X653955Y594955D03*
X654500Y602500D03*
Y617000D03*
X657500Y827000D03*
X656500Y906000D03*
X674666Y82002D03*
X670454Y94544D03*
X670998Y116010D03*
X660000Y120000D03*
X670522Y130200D03*
X673500Y334000D03*
X668000D03*
X662000D03*
X665000Y368500D03*
X670000Y395000D03*
X670500Y414000D03*
X660500Y440000D03*
X659462Y475500D03*
X670000Y476500D03*
X663962Y473500D03*
X685898Y133380D03*
X681748Y134000D03*
X682418Y129980D03*
X690966Y142028D03*
X685000Y150500D03*
X690500Y468000D03*
X686718Y793718D03*
X690000Y810500D03*
X682500Y917500D03*
X699500Y56775D03*
X695000Y63500D03*
X699000Y72500D03*
X698000Y80500D03*
X702473Y87000D03*
X704933Y98147D03*
X701949Y118331D03*
X699716Y137284D03*
X701828Y129550D03*
X698500Y132500D03*
X697248Y128000D03*
X694466Y133282D03*
X703053Y133568D03*
X700748Y144000D03*
X706822Y141225D03*
X704716Y156520D03*
X700216Y156368D03*
X693055Y261500D03*
X692555Y267500D03*
X705500Y352500D03*
X707000Y340500D03*
X708500Y365000D03*
X707000Y385000D03*
Y378000D03*
X708500Y371000D03*
X695500Y460500D03*
X694000Y483500D03*
X693500Y472000D03*
X694000Y492000D03*
Y500500D03*
Y507500D03*
Y514000D03*
X692500Y767204D03*
X694500Y779500D03*
X694750Y884750D03*
X697925Y894425D03*
X724000Y69016D03*
X715940Y71750D03*
X724716Y94784D03*
X710748Y100000D03*
X718448Y100900D03*
X716048Y95900D03*
X709848Y94100D03*
X715748Y143000D03*
X719839Y140488D03*
X723248Y144500D03*
X710748Y144000D03*
X722716Y156520D03*
X718216D03*
X713716D03*
X709216D03*
X719500Y185600D03*
X725000Y189000D03*
X711500Y385000D03*
Y378000D03*
X724887Y566963D03*
X718000Y571000D03*
X711000Y758000D03*
X723000Y767204D03*
X721500Y802704D03*
X720500Y797500D03*
X720000Y849000D03*
X721900Y852750D03*
X714000Y879000D03*
X720000Y905000D03*
X731500Y57500D03*
X728500Y61500D03*
X737000Y90000D03*
X730748Y99500D03*
X734500Y97500D03*
X740000Y109534D03*
X732248Y140000D03*
X737500Y145000D03*
X731716Y156500D03*
X736000Y142000D03*
X731716Y144984D03*
X740748Y140500D03*
X727248Y141500D03*
X727216Y156520D03*
X738748Y189500D03*
X726100Y195600D03*
X729800Y210000D03*
X740000Y681000D03*
X740500Y755000D03*
X739900Y760000D03*
X736377Y894123D03*
X738000Y889000D03*
X730000Y891560D03*
X732500Y899000D03*
X755000Y56500D03*
X754500Y62000D03*
X746500Y105000D03*
X741500Y100500D03*
X748248Y118500D03*
X749500Y110000D03*
X744000Y115500D03*
X755248Y123500D03*
X746716Y130238D03*
X750916Y130272D03*
X744000Y157500D03*
X757000Y435500D03*
X752100Y435600D03*
X751500Y431000D03*
X756500D03*
X744000Y465500D03*
X757802Y474000D03*
X744000Y471500D03*
X745000Y553500D03*
X744500Y558500D03*
X744000Y563500D03*
X743000Y587500D03*
X757500Y590000D03*
X751000Y874500D03*
X765500Y83500D03*
X768200Y92800D03*
X769000Y101500D03*
X760522Y116784D03*
X770000Y123500D03*
X758748Y137500D03*
X773000Y339500D03*
X761600Y435600D03*
X761500Y431000D03*
X766000D03*
X758000Y448500D03*
X763000Y463000D03*
Y467800D03*
X764500Y483000D03*
X771000Y644500D03*
X770000Y677000D03*
Y681500D03*
X772250Y672250D03*
X764500Y668000D03*
X774271Y699729D03*
X767000Y845000D03*
X762000Y874500D03*
X773000Y917000D03*
Y921500D03*
Y927000D03*
X767500D03*
X771000Y958500D03*
X766600D03*
X762100Y958600D03*
X771500Y963500D03*
X767100D03*
X762600Y963600D03*
X771400Y968900D03*
X767000D03*
X762500Y969000D03*
X783000Y133500D03*
X778000Y152250D03*
X777500Y351000D03*
X782500D03*
X777500Y339500D03*
X782400Y339400D03*
X782600Y411000D03*
X776468Y447600D03*
X775000Y455000D03*
X789000Y471500D03*
X784000Y469500D03*
X778000D03*
Y548500D03*
Y553491D03*
X778454Y559445D03*
X787000Y583500D03*
X786500Y648000D03*
X788500Y653000D03*
X785500Y685500D03*
X775500Y717500D03*
X775103Y857397D03*
X775500Y881250D03*
X800000Y100000D03*
X792000Y356500D03*
X796000Y430000D03*
X793000Y439500D03*
X800000Y458000D03*
X802000Y466000D03*
X805500Y475078D03*
X801500Y573000D03*
X794000Y737500D03*
X799968Y737000D03*
X800500Y977500D03*
X794500D03*
X800500Y982000D03*
X794500D03*
X810000Y120000D03*
X818500Y361600D03*
X813500Y367000D03*
X818500Y407500D03*
X819000Y451000D03*
X810000Y484078D03*
X819000Y473000D03*
X823000Y519000D03*
X813000Y743500D03*
X820500Y754000D03*
Y765500D03*
X832500Y363500D03*
X828500Y361500D03*
X837000D03*
X829500Y373500D03*
Y380000D03*
Y385500D03*
X830250Y727250D03*
X826500Y776430D03*
Y851500D03*
X828940Y873500D03*
X846500Y362000D03*
X842000Y367000D03*
Y372000D03*
Y377500D03*
X849500Y429000D03*
X846500Y468000D03*
X848600Y517100D03*
X843100Y517000D03*
X843200Y512800D03*
X843300Y507900D03*
X848800Y508000D03*
X848700Y512900D03*
X853095Y649905D03*
X841000Y715500D03*
X854500Y778000D03*
X850000D03*
X854500Y783000D03*
X850000D03*
X857000Y80500D03*
X872750Y96500D03*
X870000Y160000D03*
X872500Y338460D03*
X862240D03*
X871820Y353380D03*
X860820D03*
X868500Y390000D03*
X864500Y411000D03*
X861000Y429000D03*
X869250Y471250D03*
X862750Y613750D03*
X869000Y629500D03*
X858500Y656500D03*
X861000Y680000D03*
X869000Y679000D03*
X860000Y702000D03*
X857500Y715250D03*
X865300Y748000D03*
X879500Y56500D03*
Y67500D03*
X878500Y77000D03*
X879736Y290000D03*
X875500Y290500D03*
X878500Y294178D03*
X880000Y371500D03*
X884000Y396500D03*
X879500D03*
X874500Y449000D03*
X881500Y467500D03*
X876500Y475000D03*
X889000Y617000D03*
X879060Y642060D03*
X880000Y657500D03*
X877500Y700500D03*
Y705500D03*
X899750Y53250D03*
X895000Y96000D03*
X899500Y92500D03*
X890000Y140000D03*
X899000Y405500D03*
X894000D03*
X899000Y410500D03*
X894000D03*
X895000Y617500D03*
X920000Y66250D03*
X912250D03*
X910000Y160000D03*
X915000Y805000D03*
Y825000D03*
Y845000D03*
Y865000D03*
Y885000D03*
Y905000D03*
Y925000D03*
Y945000D03*
Y965000D03*
X930500Y219000D03*
X936500D03*
X930500Y232000D03*
X936500D03*
Y225500D03*
X930500D03*
Y536500D03*
X939678Y54300D03*
X941000Y59500D03*
X949950Y443200D03*
X943450Y452700D03*
X950950Y458700D03*
X943500Y488000D03*
X966000Y200500D03*
Y209500D03*
X961000Y212500D03*
X961950Y443200D03*
X957068Y458600D03*
X963500Y488000D03*
Y536500D03*
Y654500D03*
X958000D03*
Y659500D03*
X963500D03*
X969000Y655100D03*
Y659500D03*
X965000Y725500D03*
X975500Y205000D03*
X981000Y386500D03*
X982500Y397500D03*
X985000Y388000D03*
X980500Y391000D03*
X984500Y392500D03*
X974500Y655100D03*
Y659500D03*
X980000Y725500D03*
X1004500Y84000D03*
X998000Y80000D03*
X991000Y204578D03*
Y214578D03*
Y209578D03*
X1003750Y475873D03*
X998000Y470500D03*
X994000Y507800D03*
X997900Y503700D03*
X1002200Y506700D03*
X998200Y532300D03*
X1000500Y667500D03*
X990000D03*
X1007000Y12000D03*
X1013200Y52600D03*
X1013500Y84000D03*
X1009000D03*
X1016500Y75500D03*
X1019000Y78500D03*
X1013000Y91500D03*
Y282500D03*
X1012900Y275300D03*
X1010250Y459346D03*
X1008000Y492000D03*
X1008100Y504000D03*
X1012500Y506500D03*
Y532900D03*
X1018200Y532400D03*
X1004400D03*
X1017000Y545300D03*
X1013000Y554100D03*
X1011500Y642000D03*
Y648000D03*
X1020500Y862218D03*
X1015500Y876000D03*
Y894500D03*
X1020500Y882500D03*
Y887000D03*
X1022500Y51500D03*
X1034500D03*
X1028000D03*
X1021000Y75500D03*
X1032000Y82500D03*
Y90000D03*
Y97000D03*
Y103500D03*
Y110000D03*
X1025000Y124500D03*
X1022000Y147500D03*
X1031000Y141000D03*
X1032500Y165000D03*
X1036000Y171000D03*
X1023922Y199578D03*
Y204578D03*
X1023422Y209578D03*
X1031800Y248800D03*
X1027500Y248500D03*
X1036300Y248800D03*
X1033000Y290000D03*
X1027500D03*
X1027700Y294200D03*
X1033200D03*
X1032100Y577100D03*
X1028900Y583700D03*
X1035500Y825500D03*
Y830000D03*
X1027716Y902500D03*
X1035000Y970000D03*
X1045000Y128500D03*
X1039285Y139500D03*
X1051500Y172500D03*
X1051600Y214500D03*
X1053000Y228000D03*
X1041000Y276000D03*
X1046000Y290000D03*
X1039500D03*
X1039700Y294200D03*
X1046200D03*
X1051500Y601000D03*
X1050000Y669500D03*
X1051600Y688700D03*
X1040000Y825500D03*
X1044500D03*
X1049000D03*
X1053400D03*
X1040000Y830000D03*
X1038500Y855000D03*
X1051000Y883600D03*
Y888500D03*
X1038500Y914500D03*
X1065000Y154000D03*
X1067500Y222000D03*
X1057000Y229500D03*
X1056716Y224500D03*
X1060500Y282500D03*
Y275000D03*
X1060600Y303150D03*
X1056100Y303200D03*
X1059900Y295200D03*
X1059800Y290600D03*
X1067900Y485600D03*
X1056000Y673500D03*
X1057300Y694200D03*
X1055900Y703500D03*
X1056000Y708900D03*
X1057776Y699081D03*
X1055400Y714600D03*
X1065688Y746000D03*
X1058000Y889500D03*
Y902500D03*
Y896000D03*
X1060000Y929500D03*
X1055000Y970000D03*
X1078000Y141000D03*
X1084988Y154203D03*
X1080500Y153500D03*
X1077500Y150000D03*
X1086000Y167000D03*
X1085150Y158400D03*
X1086000Y187500D03*
Y192500D03*
X1075800Y204900D03*
X1070500Y229000D03*
X1079000Y434000D03*
X1085000D03*
X1079100Y429000D03*
X1085900Y644900D03*
X1086200Y656300D03*
X1084900Y690594D03*
X1085992Y707113D03*
X1075289Y738000D03*
X1075000Y970000D03*
X1100000Y180000D03*
X1088000Y220500D03*
X1092200Y258100D03*
X1097000Y423100D03*
X1088000Y450000D03*
X1098500Y449500D03*
X1101500Y461500D03*
X1099600Y643900D03*
X1087200Y664900D03*
X1101534Y650852D03*
X1091300Y650500D03*
X1094500Y678600D03*
X1087000Y676000D03*
X1093600Y670024D03*
X1100900Y694624D03*
X1097000Y686224D03*
X1086800Y696849D03*
X1086700Y682600D03*
X1094800Y691800D03*
X1095000Y712000D03*
X1086324Y702324D03*
X1094449Y698500D03*
X1091000Y705000D03*
X1096500Y717000D03*
X1101500Y718000D03*
X1095900Y722000D03*
X1101100Y723000D03*
X1091299Y719103D03*
X1086500Y719000D03*
X1102500Y762500D03*
X1097500D03*
X1102500Y767400D03*
X1097500D03*
X1093000Y766500D03*
X1097500Y797500D03*
X1098000Y810000D03*
X1099550Y838740D03*
X1096218Y859500D03*
X1101700Y854100D03*
X1091500Y846500D03*
X1099000Y877500D03*
X1103200Y259300D03*
X1105000Y400500D03*
X1114900Y641800D03*
X1111824Y648376D03*
X1110000Y642300D03*
X1104500Y643500D03*
X1107274Y650126D03*
X1106500Y718100D03*
X1106200Y723100D03*
X1115200Y745400D03*
X1118000Y739000D03*
X1114450Y735550D03*
X1106600Y753000D03*
X1107500Y801500D03*
X1114500Y855500D03*
X1119000D03*
X1105000Y970000D03*
X1134000Y229000D03*
X1128500D03*
X1121500Y257500D03*
X1134000Y266500D03*
Y261500D03*
X1134500Y282284D03*
X1135000Y274500D03*
X1129000Y502500D03*
X1123500D03*
Y507500D03*
X1129000D03*
X1135500D03*
Y502500D03*
X1120000Y629500D03*
X1128700Y622000D03*
X1124000Y644500D03*
X1120000Y634500D03*
X1120500Y639500D03*
X1129400Y641300D03*
X1132795Y644695D03*
X1127184Y648612D03*
X1129911Y746600D03*
X1131661Y756839D03*
X1126000Y850534D03*
X1125000Y970000D03*
X1141000Y291750D03*
Y507500D03*
Y502500D03*
X1141421Y632142D03*
X1146000Y630700D03*
X1139500Y644500D03*
Y639500D03*
X1145500Y644500D03*
X1150400Y641800D03*
X1135600Y649100D03*
X1140300Y745100D03*
X1141500Y761500D03*
X1139718Y854218D03*
X1137000Y890000D03*
X1144500D03*
X1152000D03*
X1145000Y970000D03*
X1161500Y222000D03*
X1166500D03*
X1160500Y242000D03*
Y246500D03*
X1165000Y242000D03*
Y246500D03*
X1154000Y598500D03*
X1163500Y620500D03*
X1155500Y624500D03*
X1163600Y642700D03*
X1152785Y646200D03*
X1156400Y642600D03*
X1157285Y649100D03*
X1157680Y739518D03*
X1153777Y736723D03*
X1156000Y866000D03*
X1158000Y890000D03*
X1164500D03*
X1171000Y222000D03*
X1176000D03*
X1179345Y253661D03*
X1179500Y367500D03*
X1169000Y398000D03*
X1171000Y394000D03*
X1183000Y396500D03*
X1170500Y461000D03*
X1173100Y499200D03*
X1173500Y550400D03*
X1173000Y626000D03*
X1180500Y621000D03*
X1182000Y643000D03*
X1182900Y649100D03*
X1183370Y735070D03*
X1178500Y741500D03*
X1182000Y745500D03*
X1172000Y744000D03*
X1175500Y748000D03*
X1172000Y761000D03*
X1182000Y816000D03*
X1181500Y820500D03*
X1177000D03*
X1175000Y970000D03*
X1188500Y237482D03*
X1199100Y226600D03*
X1194900D03*
X1199677Y242913D03*
Y251000D03*
X1187000Y255000D03*
X1195677Y257000D03*
X1185000Y367500D03*
X1188000Y396500D03*
X1198500Y396000D03*
X1195000Y422500D03*
X1194000Y484000D03*
X1189500D03*
X1194000Y488500D03*
X1189500D03*
Y492900D03*
X1194000Y493000D03*
X1188500Y500000D03*
X1186500Y604600D03*
X1191500Y631000D03*
X1193500Y626500D03*
X1188000Y634500D03*
X1185500Y639500D03*
X1195000Y643000D03*
X1194000Y637200D03*
X1195920Y753700D03*
X1195500Y776500D03*
X1191500Y807000D03*
X1195000Y970000D03*
X1203500Y193800D03*
Y198000D03*
X1208000D03*
Y193800D03*
X1204000Y206000D03*
X1208500Y207000D03*
X1204000Y210500D03*
Y215000D03*
X1207500Y235750D03*
Y225000D03*
X1203300Y226600D03*
X1207700Y244095D03*
X1217000Y537000D03*
X1203000Y645500D03*
X1214000Y642500D03*
X1207869Y643674D03*
X1202500Y638500D03*
X1212000Y685000D03*
X1211000Y696075D03*
X1213000Y712500D03*
X1208500Y710500D03*
X1202000Y709000D03*
X1206500Y706000D03*
X1216500Y710125D03*
X1209500Y701500D03*
X1207000Y715500D03*
X1202500Y727500D03*
X1202000Y720000D03*
X1207000Y720500D03*
X1202000Y715000D03*
X1208000Y727500D03*
X1215500Y723000D03*
X1216000Y741000D03*
X1206040Y732500D03*
X1208000Y738500D03*
X1204500Y769000D03*
X1215500Y800500D03*
X1207688Y800688D03*
X1205100Y855000D03*
X1215000Y970000D03*
X1230500Y431500D03*
X1231500Y439000D03*
X1230500Y643000D03*
X1231000Y665000D03*
X1227500Y651500D03*
X1228000Y673000D03*
X1224750Y692250D03*
X1223500Y709000D03*
X1226500Y767500D03*
X1221016Y840984D03*
X1229500Y831500D03*
X1219100Y855500D03*
X1249300Y166000D03*
X1240600Y167000D03*
X1240700Y171200D03*
X1240800Y179800D03*
X1240700Y175500D03*
Y184000D03*
X1244000Y200500D03*
X1241000Y219000D03*
X1244997Y238331D03*
X1239500Y227500D03*
X1242000Y223500D03*
X1244000Y227500D03*
X1241000Y235671D03*
X1249000Y230500D03*
X1249649Y225588D03*
X1242000Y243500D03*
X1242636Y248258D03*
X1240377Y255000D03*
Y259843D03*
X1246000Y263500D03*
X1237000Y432000D03*
X1235500Y449000D03*
X1237000Y463500D03*
X1245500Y461700D03*
X1242500Y588000D03*
X1248000Y593000D03*
Y598000D03*
X1242900Y647000D03*
X1238838Y653662D03*
X1238500Y663000D03*
X1246855Y665100D03*
X1243500Y679000D03*
X1239500Y671000D03*
X1239100Y696500D03*
X1240000Y683000D03*
X1246000Y687500D03*
X1244824Y702176D03*
X1246500Y738500D03*
X1236500Y757500D03*
X1241500Y757000D03*
X1237000Y750000D03*
X1246000Y841000D03*
X1238100Y848400D03*
X1261862Y38583D03*
X1261677Y231000D03*
X1261177Y226000D03*
X1264600Y238800D03*
X1265500Y246500D03*
X1265900Y254900D03*
X1252677Y259500D03*
X1252000Y439500D03*
X1263968Y463032D03*
X1253500Y461500D03*
X1252500Y453927D03*
X1254000Y564500D03*
X1265500Y577500D03*
X1253500Y661000D03*
X1266000Y669000D03*
X1258500Y684000D03*
X1263000Y717000D03*
X1269500Y30000D03*
X1281000Y475000D03*
X1276500D03*
X1267500Y549500D03*
X1278000Y573200D03*
X1277000Y656000D03*
X1282000Y649000D03*
X1280500Y681500D03*
Y674500D03*
X1278815Y668315D03*
X1277500Y757500D03*
Y778500D03*
X1284000Y30000D03*
X1295500Y26500D03*
X1287500Y428000D03*
X1291000Y425000D03*
X1299000Y429000D03*
X1288000Y442000D03*
X1292500Y441000D03*
X1285500Y475000D03*
X1293500D03*
X1283225Y579501D03*
X1284825Y631901D03*
X1295500Y656000D03*
X1291000Y735000D03*
X1293000Y862100D03*
X1299500Y865000D03*
X1306500Y38000D03*
X1302500Y455000D03*
X1308617Y568912D03*
X1314500Y642500D03*
X1315500Y650925D03*
X1303500Y655500D03*
X1314500Y679500D03*
X1308500Y771500D03*
X1303000D03*
X1314000D03*
X1303784Y794284D03*
X1308784D03*
X1314000Y794000D03*
X1306000Y827000D03*
X1312500D03*
Y862000D03*
X1303070Y909853D03*
X1306968Y898500D03*
X1318500Y37500D03*
Y55000D03*
X1328200Y50000D03*
X1316250Y323250D03*
X1324500Y345400D03*
Y341000D03*
X1329000Y341100D03*
Y345500D03*
X1323000Y368000D03*
X1327500D03*
X1332000D03*
X1318000Y369500D03*
X1332000Y372400D03*
X1327500D03*
X1323000D03*
X1318000Y375500D03*
Y381500D03*
X1317700Y421000D03*
X1330000Y428000D03*
X1331500Y432500D03*
X1323500Y441500D03*
X1321707Y565252D03*
X1324117Y575512D03*
X1322717Y592412D03*
X1320617Y587312D03*
X1324917Y584912D03*
X1321617Y613812D03*
X1325900Y602100D03*
X1329017Y613012D03*
X1322617Y608912D03*
X1318700Y665800D03*
X1324000Y675000D03*
X1317500Y827000D03*
X1320000Y862000D03*
X1316968Y909984D03*
X1337612Y63000D03*
X1337500Y77000D03*
X1336500Y129000D03*
X1338000Y341100D03*
X1333500D03*
Y345500D03*
X1338000D03*
X1344500Y450500D03*
X1340000Y448000D03*
X1343867Y571200D03*
X1348500Y574500D03*
X1334384Y613278D03*
X1338867Y615534D03*
X1342000Y673000D03*
X1355000Y106000D03*
X1358500Y346500D03*
Y351000D03*
X1354000D03*
Y346500D03*
X1355500Y416500D03*
X1360000Y433500D03*
X1351250Y424500D03*
X1354945Y444400D03*
X1354000Y438700D03*
X1352500Y460500D03*
X1354500Y480500D03*
Y475000D03*
X1360500D03*
Y480500D03*
X1354500Y486500D03*
X1360500D03*
X1354117Y574912D03*
X1360117D03*
X1350017Y615812D03*
X1355517Y613612D03*
X1360000Y631500D03*
X1355500Y631000D03*
X1358000Y626000D03*
X1357500Y635500D03*
X1351000Y677000D03*
Y672000D03*
X1355000Y674500D03*
X1354500Y669000D03*
Y703500D03*
X1371500Y254000D03*
X1366000D03*
X1371500Y264000D03*
X1366000D03*
X1371500Y259500D03*
X1366000D03*
X1378500Y370000D03*
Y365000D03*
Y360000D03*
X1377000Y384000D03*
Y379000D03*
X1378500Y374500D03*
X1377000Y390000D03*
X1374500Y395000D03*
Y402000D03*
X1372500Y415000D03*
G54D11*
X19272Y337795D03*
Y396850D03*
X98838Y337795D03*
Y396850D03*
G54D113*
X672600Y348500D03*
Y369000D03*
X697400Y348500D03*
Y369000D03*
G54D131*
X786500Y397557D03*
Y419443D03*
X1343500Y383557D03*
Y405443D03*
G54D122*
X722700Y107784D03*
X720732D03*
X718763D03*
X716795D03*
X714826D03*
X712858D03*
Y134784D03*
X714826D03*
X716795D03*
X718763D03*
X720732D03*
X722700D03*
X730574Y107784D03*
X728606D03*
X726637D03*
X724669D03*
Y134784D03*
X726637D03*
X728606D03*
X730574D03*
G54D140*
X851892Y391835D03*
X849333D03*
X846774D03*
X844215D03*
X841656D03*
Y411321D03*
X844215D03*
X846774D03*
X849333D03*
X851892D03*
X1116468Y860541D03*
X1113909D03*
X1111350D03*
Y880027D03*
X1113909D03*
X1116468D03*
X1121586Y860541D03*
X1119027D03*
Y880027D03*
X1121586D03*
G54D104*
X543699Y168150D03*
X541729D03*
X539759D03*
X537789D03*
X535824D03*
X533854D03*
Y243850D03*
X535824D03*
X537789D03*
X539759D03*
X541729D03*
X543699D03*
X559444Y168150D03*
X557474D03*
X555509D03*
X553539D03*
X551569D03*
X549604D03*
X547634D03*
X545664D03*
Y243850D03*
X547634D03*
X549604D03*
X551569D03*
X553539D03*
X555509D03*
X557474D03*
X559444D03*
X575194Y168150D03*
X573224D03*
X571254D03*
X569289D03*
X567319D03*
X565349D03*
X563384D03*
X561414D03*
Y243850D03*
X563384D03*
X565349D03*
X567319D03*
X569289D03*
X571254D03*
X573224D03*
X575194D03*
X587004Y168150D03*
X585034D03*
X583069D03*
X581099D03*
X579129D03*
X577159D03*
Y243850D03*
X579129D03*
X581099D03*
X583069D03*
X585034D03*
X587004D03*
X1311403Y874634D03*
X1309438D03*
X1307468D03*
X1305498D03*
X1303533D03*
Y890934D03*
X1305498D03*
X1307468D03*
X1309438D03*
X1311403D03*
X1331438Y643634D03*
X1329468D03*
X1327498D03*
X1325533D03*
Y659934D03*
X1327498D03*
X1329468D03*
X1331438D03*
X1333403Y643634D03*
Y659934D03*
G54D20*
X34304Y893920D03*
X29804D03*
X25304D03*
X38804D03*
Y901920D03*
X47804Y935920D03*
X58804Y717920D03*
X65804Y843420D03*
X76804Y717920D03*
X77804Y769920D03*
X73804D03*
X74304Y843420D03*
X83304D03*
X78804D03*
X99536Y762926D03*
X96772Y771204D03*
X92304Y843420D03*
X138000Y319700D03*
X134000Y674700D03*
Y682200D03*
X143500Y706200D03*
X153500Y674200D03*
Y682200D03*
X163000Y706200D03*
X168300Y453500D03*
X172800D03*
X187300D03*
X191800D03*
X195000Y887200D03*
X207500Y710700D03*
X212000D03*
X208000Y887200D03*
X216500Y710700D03*
X221000D03*
X236500Y832700D03*
X250000Y710700D03*
X265500Y901200D03*
X277500Y899200D03*
X296000Y91200D03*
X300500D03*
X305000D03*
X329055Y556200D03*
X333000Y97700D03*
X341000Y108740D03*
X347000Y108629D03*
X341000Y116240D03*
X346500Y914200D03*
X338000Y956200D03*
X342500D03*
X347000D03*
X353000Y84700D03*
X355055Y552700D03*
X355500Y914200D03*
X351000D03*
X359500D03*
X351500Y956200D03*
X356000D03*
X360500D03*
X375055Y467450D03*
X391055Y302700D03*
X380555Y467450D03*
X391555D03*
X386055D03*
X389000Y873700D03*
X393500D03*
X392000Y955200D03*
X420429Y261100D03*
X427555Y295200D03*
X433500Y239700D03*
X429429Y261100D03*
X444778Y812200D03*
X438278D03*
X444278Y875700D03*
X455000Y113200D03*
X459500D03*
X450778Y875700D03*
X475778Y812200D03*
X469278D03*
X473778Y875700D03*
X480278D03*
X544000Y154700D03*
X559000D03*
X554000D03*
X553055Y330700D03*
X557055D03*
X564000Y154700D03*
X585000Y256200D03*
X638876Y96914D03*
X656876D03*
X652376D03*
X647876D03*
X643376D03*
X655964Y444238D03*
X654962Y484164D03*
X674666Y90244D03*
X661376Y96914D03*
X668462Y484164D03*
X663962D03*
X682968Y773684D03*
Y765684D03*
X706716Y90484D03*
X700216Y151984D03*
X720032Y57416D03*
X724532Y65416D03*
X711216Y90484D03*
X720216D03*
X709216Y151984D03*
X713716D03*
X718216D03*
X722716D03*
X714000Y874700D03*
X740500Y82700D03*
X740748Y152200D03*
X727216Y151984D03*
X732500Y482200D03*
X745500Y152200D03*
X767000Y467200D03*
X760500Y484700D03*
X775748Y184200D03*
X779998Y676754D03*
X789500Y884700D03*
X798774Y437278D03*
X792500Y661700D03*
X802000Y731700D03*
X798000D03*
X822500Y407700D03*
X810000Y731700D03*
X829055Y273700D03*
X830500Y410700D03*
X867500Y624700D03*
Y617200D03*
X865468Y709984D03*
X875000Y444200D03*
X879500D03*
X880500Y478700D03*
X873500Y679700D03*
X953450Y441400D03*
X952450Y466900D03*
X957950Y441400D03*
X957068Y466950D03*
X1031000Y148700D03*
X1028716Y862168D03*
X1065688Y753304D03*
X1065838Y761244D03*
X1080468Y210984D03*
X1079688Y753434D03*
X1101500Y457700D03*
X1097000D03*
X1101468Y850484D03*
X1111000Y637700D03*
X1105968Y850484D03*
X1129000Y637700D03*
X1133000D03*
X1125000D03*
X1151500Y622700D03*
X1142000Y625700D03*
X1137000Y634700D03*
X1143218Y757064D03*
X1162468Y253484D03*
X1167500Y624200D03*
X1155500Y637700D03*
X1159500D03*
X1167500D03*
X1163500D03*
X1178000Y363700D03*
X1182000D03*
X1183000Y403700D03*
X1199000D03*
X1187000D03*
X1186500Y600700D03*
X1197000Y855200D03*
X1217000Y634200D03*
X1207000Y764700D03*
X1212500D03*
X1211000Y855200D03*
X1222500Y435700D03*
X1222000Y443700D03*
X1251000Y476200D03*
Y468700D03*
X1250600Y838800D03*
X1277000Y709200D03*
X1281000Y719700D03*
X1284500Y326700D03*
X1289468Y662984D03*
X1292968Y846984D03*
X1297468D03*
X1303784Y778732D03*
X1308784D03*
X1313784D03*
X1312500Y834200D03*
X1308500D03*
X1304500D03*
X1318500Y448700D03*
X1323117Y622112D03*
X1316500Y834200D03*
X1320500D03*
X1317500Y906200D03*
X1342000Y81200D03*
X1337468Y676484D03*
X1333468D03*
X1355000Y423700D03*
X1360617Y623112D03*
G54D141*
X941260Y371535D03*
X949134D03*
X941260Y388465D03*
X949134D03*
X957008Y371535D03*
X964882D03*
X957008Y388465D03*
X964882D03*
X972756Y371535D03*
Y388465D03*
G54D150*
X1093861Y104842D03*
Y98242D03*
X1090061D03*
Y104842D03*
G54D123*
X710889Y107284D03*
Y135284D03*
X732543Y107284D03*
Y135284D03*
X789727Y444972D03*
X783821D03*
Y457184D03*
X789727D03*
X1344953Y430394D03*
X1339047D03*
Y442606D03*
X1344953D03*
G54D30*
X39804Y937020D03*
X97500Y936800D03*
X153200Y666200D03*
X179000Y857300D03*
X180000Y911800D03*
X190000D03*
X185000D03*
X212500Y796300D03*
X343000Y73300D03*
X520000Y151800D03*
X687968Y765784D03*
X727968Y763784D03*
X793500Y733300D03*
X809000Y343800D03*
X810000Y479800D03*
X904500Y81800D03*
X1065500Y164300D03*
X1056700Y178800D03*
X1107968Y256584D03*
X1268468Y471584D03*
X1287000Y452800D03*
X1360000Y429300D03*
X1357500Y466300D03*
G54D21*
X34304Y890520D03*
X29804D03*
X25304D03*
X38804D03*
Y898520D03*
X47804Y932520D03*
X58804Y714520D03*
X65804Y840020D03*
X76804Y714520D03*
X77804Y766520D03*
X73804D03*
X74304Y840020D03*
X83304D03*
X78804D03*
X99536Y759526D03*
X96772Y767804D03*
X92304Y840020D03*
X138000Y316300D03*
X134000Y678800D03*
Y671300D03*
X143500Y702800D03*
X153500Y678800D03*
Y670800D03*
X163000Y702800D03*
X168300Y450100D03*
X172800D03*
X187300D03*
X191800D03*
X195000Y883800D03*
X207500Y707300D03*
X212000D03*
X208000Y883800D03*
X216500Y707300D03*
X221000D03*
X236500Y829300D03*
X250000Y707300D03*
X265500Y897800D03*
X277500Y895800D03*
X296000Y87800D03*
X300500D03*
X305000D03*
X329055Y552800D03*
X341000Y105340D03*
X347000Y105229D03*
X333000Y94300D03*
X341000Y112840D03*
X346500Y910800D03*
X338000Y952800D03*
X342500D03*
X347000D03*
X353000Y81300D03*
X355055Y549300D03*
X355500Y910800D03*
X351000D03*
X359500D03*
X351500Y952800D03*
X356000D03*
X360500D03*
X375055Y464050D03*
X391055Y299300D03*
X380555Y464050D03*
X391555D03*
X386055D03*
X389000Y870300D03*
X393500D03*
X392000Y951800D03*
X420429Y257700D03*
X427555Y291800D03*
X433500Y236300D03*
X429429Y257700D03*
X444778Y808800D03*
X438278D03*
X444278Y872300D03*
X455000Y109800D03*
X459500D03*
X450778Y872300D03*
X475778Y808800D03*
X469278D03*
X473778Y872300D03*
X480278D03*
X544000Y151300D03*
X559000D03*
X554000D03*
X553055Y327300D03*
X557055D03*
X564000Y151300D03*
X585000Y252800D03*
X638876Y93514D03*
X656876D03*
X652376D03*
X647876D03*
X643376D03*
X655964Y440838D03*
X654962Y480764D03*
X674666Y86844D03*
X661376Y93514D03*
X668462Y480764D03*
X663962D03*
X682968Y762284D03*
Y770284D03*
X706716Y87084D03*
X700216Y148584D03*
X720032Y54016D03*
X724532Y62016D03*
X711216Y87084D03*
X720216D03*
X709216Y148584D03*
X713716D03*
X718216D03*
X722716D03*
X714000Y871300D03*
X740500Y79300D03*
X740748Y148800D03*
X727216Y148584D03*
X732500Y478800D03*
X745500Y148800D03*
X767000Y463800D03*
X760500Y481300D03*
X775748Y180800D03*
X779998Y673354D03*
X789500Y881300D03*
X798774Y433878D03*
X792500Y658300D03*
X802000Y728300D03*
X798000D03*
X822500Y404300D03*
X810000Y728300D03*
X829055Y270300D03*
X830500Y407300D03*
X867500Y613800D03*
Y621300D03*
X865468Y706584D03*
X875000Y440800D03*
X879500D03*
X880500Y475300D03*
X873500Y676300D03*
X953450Y438000D03*
X952450Y463500D03*
X957950Y438000D03*
X957068Y463550D03*
X1031000Y145300D03*
X1028716Y858768D03*
X1065688Y749904D03*
X1065838Y757844D03*
X1080468Y207584D03*
X1079688Y750034D03*
X1101500Y454300D03*
X1097000D03*
X1101468Y847084D03*
X1111000Y634300D03*
X1105968Y847084D03*
X1129000Y634300D03*
X1133000D03*
X1125000D03*
X1151500Y619300D03*
X1137000Y631300D03*
X1142000Y622300D03*
X1143218Y753664D03*
X1162468Y250084D03*
X1167500Y620800D03*
X1155500Y634300D03*
X1159500D03*
X1167500D03*
X1163500D03*
X1178000Y360300D03*
X1182000D03*
X1183000Y400300D03*
X1199000D03*
X1187000D03*
X1186500Y597300D03*
X1197000Y851800D03*
X1217000Y630800D03*
X1207000Y761300D03*
X1212500D03*
X1211000Y851800D03*
X1222500Y432300D03*
X1222000Y440300D03*
X1251000Y465300D03*
Y472800D03*
X1250600Y835400D03*
X1277000Y705800D03*
X1281000Y716300D03*
X1284500Y323300D03*
X1289468Y659584D03*
X1292968Y843584D03*
X1297468D03*
X1303784Y775332D03*
X1308784D03*
X1313784D03*
X1312500Y830800D03*
X1308500D03*
X1304500D03*
X1318500Y445300D03*
X1323117Y618712D03*
X1316500Y830800D03*
X1320500D03*
X1317500Y902800D03*
X1342000Y77800D03*
X1337468Y673084D03*
X1333468D03*
X1355000Y420300D03*
X1360617Y619712D03*
G54D132*
X786774Y451078D03*
X1342000Y436500D03*
G54D114*
X678500Y388671D03*
Y420329D03*
G54D105*
X545079Y290355D03*
Y315945D03*
X560829Y290355D03*
X556889Y298230D03*
X552954Y290355D03*
X549014Y298230D03*
X560829Y315945D03*
X556889Y308070D03*
X552954Y315945D03*
X549014Y308070D03*
X576574Y290355D03*
X572639Y298230D03*
X568699Y290355D03*
X564764Y298230D03*
X576574Y315945D03*
X572639Y308070D03*
X568699Y315945D03*
X564764Y308070D03*
X592324Y290355D03*
X588384Y298230D03*
X584449Y290355D03*
X580514Y298230D03*
X592324Y315945D03*
X588384Y308070D03*
X584449Y315945D03*
X580514Y308070D03*
X608069Y290355D03*
X604134Y298230D03*
X600199Y290355D03*
X596259Y298230D03*
X608069Y315945D03*
X604134Y308070D03*
X600199Y315945D03*
X596259Y308070D03*
X627754Y298230D03*
X623819Y290355D03*
X619884Y298230D03*
X615944Y290355D03*
X612009Y298230D03*
X627754Y308070D03*
X623819Y315945D03*
X619884Y308070D03*
X615944Y315945D03*
X612009Y308070D03*
X643504Y298230D03*
X639569Y290355D03*
X635629Y298230D03*
X631694Y290355D03*
X643504Y308070D03*
X639569Y315945D03*
X635629Y308070D03*
X631694Y315945D03*
X659254Y298230D03*
X655314Y290355D03*
X651379Y298230D03*
X647439Y290355D03*
X659254Y308070D03*
X655314Y315945D03*
X651379Y308070D03*
X647439Y315945D03*
X674999Y298230D03*
X671064Y290355D03*
X667124Y298230D03*
X663189Y290355D03*
X674999Y308070D03*
X671064Y315945D03*
X667124Y308070D03*
X663189Y315945D03*
X690749Y298230D03*
X686809Y290355D03*
X682874Y298230D03*
X678939Y290355D03*
X690749Y308070D03*
X686809Y315945D03*
X682874Y308070D03*
X678939Y315945D03*
X706494Y298230D03*
X702559Y290355D03*
X698624Y298230D03*
X694684Y290355D03*
X706494Y308070D03*
X702559Y315945D03*
X698624Y308070D03*
X694684Y315945D03*
X726179Y290355D03*
X722244Y298230D03*
X718309Y290355D03*
X714369Y298230D03*
X710434Y290355D03*
X726179Y315945D03*
X722244Y308070D03*
X718309Y315945D03*
X714369Y308070D03*
X710434Y315945D03*
X741929Y290355D03*
X737994Y298230D03*
X734054Y290355D03*
X730119Y298230D03*
X741929Y315945D03*
X737994Y308070D03*
X734054Y315945D03*
X730119Y308070D03*
X757679Y290355D03*
X753739Y298230D03*
X749804Y290355D03*
X745864Y298230D03*
X757679Y315945D03*
X753739Y308070D03*
X749804Y315945D03*
X745864Y308070D03*
X773424Y290355D03*
X769489Y298230D03*
X765549Y290355D03*
X761614Y298230D03*
X773424Y315945D03*
X769489Y308070D03*
X765549Y315945D03*
X761614Y308070D03*
X789174Y290355D03*
X785234Y298230D03*
X781299Y290355D03*
X777364Y298230D03*
X789174Y315945D03*
X785234Y308070D03*
X781299Y315945D03*
X777364Y308070D03*
X804919Y290355D03*
X800984Y298230D03*
X797049Y290355D03*
X793109Y298230D03*
X804919Y315945D03*
X800984Y308070D03*
X797049Y315945D03*
X793109Y308070D03*
X820669Y290355D03*
X816734Y298230D03*
X812794Y290355D03*
X808859Y298230D03*
X820669Y315945D03*
X816734Y308070D03*
X812794Y315945D03*
X808859Y308070D03*
X840354Y298230D03*
X836419Y290355D03*
X832479Y298230D03*
X840354Y308070D03*
X836419Y315945D03*
X832479Y308070D03*
X856104Y298230D03*
X852164Y290355D03*
X848229Y298230D03*
X844289Y290355D03*
X856104Y308070D03*
X852164Y315945D03*
X848229Y308070D03*
X844289Y315945D03*
X871849Y298230D03*
X867914Y290355D03*
X863974Y298230D03*
X860039Y290355D03*
X871849Y308070D03*
X867914Y315945D03*
X863974Y308070D03*
X860039Y315945D03*
G54D12*
G01X23050Y854200D02*
X17100D01*
X13500Y857800D01*
X8300D01*
X8200Y857700D01*
G01X121200Y584278D02*
Y557300D01*
X124500Y554000D01*
Y532011D01*
X160551Y495960D01*
X183443D01*
X214153Y465250D01*
X221337D01*
X260909Y425678D01*
G01X179000Y857500D02*
X176500D01*
X175000Y859000D01*
Y861000D01*
G01D02*
Y863500D01*
X177250Y865750D01*
X179500D01*
G01D02*
X183000D01*
G01X193750Y844000D02*
X198000D01*
X204000Y850000D01*
G01X204500Y842500D02*
X202000Y840000D01*
X193750D01*
G01X193500Y852000D02*
X193750Y852250D01*
Y856500D01*
G01D02*
X194500Y857250D01*
Y861250D01*
G01X200016Y859484D02*
X196266D01*
X194500Y861250D01*
G01X205000Y856000D02*
X202214D01*
X194214Y848000D01*
X193750D01*
G01X186750Y865500D02*
X186000Y865750D01*
X183000D01*
G01X194250Y878500D02*
X194024Y878274D01*
X194000Y878000D01*
Y874000D01*
G01X194250Y869500D02*
Y873750D01*
X194000Y874000D01*
G01X204500Y868500D02*
X195250D01*
X194250Y869500D01*
G01X199000Y883750D02*
X195000D01*
G01X199000D02*
Y883000D01*
X203500Y878500D01*
G01X190500Y884000D02*
X190750Y883750D01*
X195000D01*
G01X215500Y816500D02*
Y822300D01*
X214800Y823000D01*
G01D02*
X213000Y824800D01*
Y835000D01*
X214000Y836000D01*
X215000D01*
X218500Y839500D01*
G01X210000Y832750D02*
Y840500D01*
X211500Y842000D01*
G01D02*
X215110Y845610D01*
Y848450D01*
G01X211950Y851610D02*
Y849950D01*
X204500Y842500D01*
G01X212250Y861453D02*
X204547D01*
X204000Y862000D01*
G01Y850000D02*
X207579Y853579D01*
X212250D01*
G01Y859484D02*
X200016D01*
G01X205000Y856000D02*
X206516Y857516D01*
X212250D01*
G01X215110Y868550D02*
X213450D01*
X203500Y878500D01*
G01X217079Y868250D02*
Y871421D01*
X212500Y876000D01*
G01X212000Y883750D02*
Y876500D01*
X212500Y876000D01*
G01X204500Y868500D02*
X207000D01*
X210110Y865390D01*
X211950D01*
G01X212000Y883750D02*
X208000D01*
G01X203500Y884000D02*
X203750Y883750D01*
X208000D01*
G01X215750Y812000D02*
Y816250D01*
X215500Y816500D01*
G01X218500Y839500D02*
X221016Y842016D01*
Y848750D01*
G01X222984Y868250D02*
Y873984D01*
X224000Y875000D01*
G01X235500Y875500D02*
X228890Y868890D01*
Y868550D01*
G01X221016Y868250D02*
Y876984D01*
G01D02*
Y880016D01*
X224500Y883500D01*
X225250D01*
G01X224953Y868250D02*
Y871453D01*
X227500Y874000D01*
Y877500D01*
X225500Y879500D01*
G01X226921Y868250D02*
Y870421D01*
X230000Y873500D01*
Y879500D01*
G01X226000Y900000D02*
Y891750D01*
X225000Y890750D01*
G01X228500Y895000D02*
Y891750D01*
X229500Y890750D01*
G01X225000Y887250D02*
Y883750D01*
X225250Y883500D01*
G01X229500Y887250D02*
Y884250D01*
X228750Y883500D01*
G01X230000Y879500D02*
Y882250D01*
X228750Y883500D01*
G01X224297Y905248D02*
X226000Y903545D01*
Y900000D01*
G01X230703Y905248D02*
X228500Y903045D01*
Y895000D01*
G01X236500Y832750D02*
Y837500D01*
X235000Y839000D01*
G01D02*
X232050Y841950D01*
Y851610D01*
G01X243250Y835500D02*
Y837250D01*
X244700Y838700D01*
Y841500D01*
G01D02*
X243750Y842450D01*
Y847500D01*
G01X247500Y829500D02*
X246500D01*
X243250Y832750D01*
Y835500D01*
G01X231750Y859484D02*
X235500D01*
X236984Y858000D01*
X239500D01*
X240000Y858500D01*
G01X243750Y859500D02*
X241000D01*
X240000Y858500D01*
G01X243750Y859500D02*
Y863500D01*
G01X239500Y847500D02*
Y848500D01*
X234421Y853579D01*
X231750D01*
G01X243750Y847500D02*
X239500D01*
G01X235500Y887728D02*
Y875500D01*
G01X232050Y865390D02*
X233000Y866340D01*
Y867500D01*
G01X236386Y891272D02*
Y889228D01*
X235500Y888342D01*
Y887728D01*
G01X264409Y430178D02*
Y425678D01*
G01X264500Y422078D02*
Y422500D01*
X264409Y422591D01*
Y425678D01*
G01D02*
X269784D01*
X270909Y426803D01*
G01X264409Y439354D02*
Y434678D01*
G01D02*
X264534Y434553D01*
X270909D01*
G01X278409Y430678D02*
Y428886D01*
X282135Y425160D01*
X293181D01*
X294959Y426938D01*
G01X300500Y87750D02*
X296000D01*
G01X294959Y426938D02*
Y419728D01*
X294909Y419678D01*
G01D02*
X295087Y419500D01*
X299055D01*
G01X302159Y424678D02*
X297219D01*
X294959Y426938D01*
G01X300500Y87750D02*
X305000D01*
G01X315000Y89000D02*
X314250Y88250D01*
X309500D01*
G01D02*
X305000Y87750D01*
G01X313210Y74290D02*
X323214D01*
G01X310000Y84500D02*
X312500D01*
X313250Y85250D01*
G01X319032Y83682D02*
X317637D01*
X317119Y84200D01*
X317050D01*
X316750Y84500D01*
X314000D01*
X313250Y85250D01*
G01X328875Y83682D02*
Y87000D01*
X329500Y87625D01*
Y90000D01*
X330000Y90500D01*
G01X324938Y83682D02*
Y87562D01*
X323000Y89500D01*
G01X321001Y83682D02*
Y85499D01*
X319500Y87000D01*
X317000D01*
X315000Y89000D01*
G01X322969Y83682D02*
Y86031D01*
X319800Y89200D01*
X319303D01*
X319003Y89500D01*
X319006Y89503D01*
X319309D01*
G01X324250Y93500D02*
X327750D01*
X328500Y94250D01*
G01D02*
X330000Y92750D01*
Y90500D01*
G01X328500Y94250D02*
X328750D01*
X332250Y97750D01*
X333000D01*
G01X324200Y101900D02*
X324250Y101850D01*
Y98000D01*
G01X328500Y97750D02*
X324500D01*
X324250Y98000D01*
G01X320750D02*
Y93500D01*
G01D02*
X320544Y93294D01*
X317147D01*
G01X332000Y126100D02*
Y126429D01*
X329929Y128500D01*
G01X330843Y83682D02*
Y86343D01*
X333000Y88500D01*
Y90500D01*
G01X348000Y87500D02*
X344500D01*
X343000Y89000D01*
G01X334330Y76258D02*
X338500D01*
X339258Y75500D01*
X339500D01*
G01X334330Y80195D02*
X338695D01*
X340000Y81500D01*
X348000D01*
G01X332812Y83682D02*
Y85312D01*
X337000Y89500D01*
Y90500D01*
G01X333000Y94250D02*
Y90500D01*
G01X337000Y97750D02*
X333000D01*
G01X341000Y94250D02*
X337000D01*
G01D02*
Y90500D01*
G01X334500Y126100D02*
X336600D01*
X338000Y127500D01*
G01X348000Y70500D02*
Y70000D01*
X352000Y66000D01*
G01X353000Y71000D02*
X357380D01*
X360200Y73820D01*
Y77400D01*
G01X357500Y79500D02*
X355750Y81250D01*
X353000D01*
G01D02*
X348250D01*
X348000Y81500D01*
G01Y76500D02*
X348500Y77000D01*
X353000D01*
G01D02*
X356000D01*
X357500Y75500D01*
G01X353000Y84750D02*
X356250D01*
X360200Y80800D01*
Y77400D01*
G01X349829Y153400D02*
X357141D01*
X357284Y153543D01*
G01X363583Y181889D02*
X362017Y183455D01*
Y183492D01*
G01X360433Y185039D02*
X360470D01*
X362017Y183492D01*
G01X366733Y178740D02*
X365310Y177317D01*
Y177299D01*
X365186Y177175D01*
G01X391929Y197637D02*
X394066Y195500D01*
X394067D01*
X395079Y194488D01*
G01X391929Y216535D02*
X391930D01*
X393504Y218109D01*
G01X391100Y910580D02*
X395920D01*
X396000Y910500D01*
X396500D01*
G01X420750Y922200D02*
Y915250D01*
X419500Y914000D01*
G01X433500Y239750D02*
X435250D01*
X436500Y241000D01*
G01X541729Y243850D02*
Y248729D01*
X542000Y249000D01*
G01X559500D02*
X559444Y248944D01*
Y243850D01*
G01X579129D02*
Y237342D01*
X579221Y237250D01*
G01X587004Y243850D02*
X592829D01*
G01D02*
X594500Y243750D01*
G01X648250Y448500D02*
X643612D01*
X642412Y447300D01*
X636700D01*
X632325Y451675D01*
Y459825D01*
X635000Y462500D01*
X638100D01*
G01X644750Y444500D02*
X640500D01*
G01X652400Y462500D02*
X638100D01*
G01X644000Y453000D02*
X639250D01*
G01X652714Y432538D02*
Y428214D01*
G01X656214Y432538D02*
Y436538D01*
G01X663119Y446821D02*
X661379D01*
X659900Y448300D01*
X655970D01*
X655751Y448519D01*
G01X651750Y448500D02*
X655750D01*
X655751Y448519D01*
G01X651750Y453000D02*
Y448500D01*
G01X648250Y444500D02*
Y440000D01*
G01X655964Y440788D02*
X651964D01*
G01X655964D02*
X657757D01*
X658545Y440000D01*
X660500D01*
G01X651964Y440788D02*
X651176Y440000D01*
X648250D01*
G01X656214Y436538D02*
X660500D01*
G01X654962Y484214D02*
X652400Y481652D01*
Y462500D01*
G01X651750Y457000D02*
Y453000D01*
G01X648250D02*
X644000D01*
G01X648250Y457000D02*
X648000D01*
X645500Y459500D01*
G01X659462Y480714D02*
X654962D01*
G01X663962Y484214D02*
Y498500D01*
X662424Y500038D01*
X656295D01*
X651500Y495243D01*
Y487962D01*
X654962Y484500D01*
Y484214D01*
G01X665088Y446821D02*
Y443668D01*
X661420Y440000D01*
X660500D01*
G01X667056Y446821D02*
Y442868D01*
X666825Y442637D01*
Y441825D01*
X661538Y436538D01*
X660500D01*
G01X663119Y466107D02*
Y469981D01*
X659462Y473638D01*
Y475500D01*
G01X667056D02*
Y466107D01*
G01X665088D02*
Y471000D01*
X663962Y472126D01*
Y473500D01*
G01X659462Y475500D02*
Y480714D01*
G01X667056Y475500D02*
X669000D01*
X670000Y476500D01*
G01X668462Y480714D02*
X667056Y479308D01*
Y475500D01*
G01X663962Y480714D02*
Y473500D01*
G01X668462Y484214D02*
X663962D01*
G01X728100Y213800D02*
X726400D01*
X721950Y209350D01*
Y209000D01*
G01X760500Y481250D02*
X760250Y481000D01*
X755300D01*
G01X763000Y463000D02*
X763750Y463750D01*
X767000D01*
G01D02*
Y459250D01*
G01X763000Y455750D02*
X767000D01*
G01D02*
X771000D01*
G01D02*
X774250D01*
X775000Y455000D01*
G01X767000Y467250D02*
Y471750D01*
G01X757250Y461500D02*
X757500Y461750D01*
Y462300D01*
X763000Y467800D01*
G01X772024Y478976D02*
Y475078D01*
G01D02*
Y470976D01*
X783821Y459179D01*
Y457184D01*
G01X767000Y471750D02*
X763050Y467800D01*
X763000D01*
G01X764500Y483000D02*
X762750Y481250D01*
X760500D01*
G01X780668Y454031D02*
Y456332D01*
X779000Y458000D01*
G01X789727Y457184D02*
Y470773D01*
X789000Y471500D01*
G01X785790Y457134D02*
Y461710D01*
X778000Y469500D01*
G01X780718Y452062D02*
X777938D01*
X775000Y455000D01*
G01X779774Y478828D02*
X776000D01*
G01X788774Y475328D02*
X792774D01*
G01X788774D02*
Y471726D01*
X789000Y471500D01*
G01X788774Y478828D02*
Y482774D01*
G01X775524Y475078D02*
Y471976D01*
X778000Y469500D01*
G01X786500Y648000D02*
X784500D01*
X783500Y649000D01*
G01X779250D02*
X783500D01*
G01X792880Y454031D02*
Y456880D01*
X802000Y466000D01*
G01X806524Y469578D02*
X805578D01*
X802000Y466000D01*
G01X797024Y475078D02*
X796750Y474804D01*
Y471000D01*
G01X792774Y475328D02*
X793024Y475078D01*
X797024D01*
G01X792774Y478828D02*
X792946Y479000D01*
X796074D01*
G01X805500Y475078D02*
X800524D01*
G01X805500D02*
X808922D01*
X810000Y474000D01*
G01X800524Y475078D02*
X800250Y474804D01*
Y471000D01*
G01X822500Y407750D02*
X826500D01*
G01X822500D02*
X822250Y407500D01*
X818500D01*
G01X812274Y465078D02*
X817174D01*
G01D02*
Y469826D01*
X814500Y472500D01*
G01X810000Y484078D02*
Y480000D01*
G01Y484078D02*
X819422D01*
X823500Y480000D01*
G01X810024Y469578D02*
Y471328D01*
X810000Y474000D01*
G01X830500Y407250D02*
X831054Y406696D01*
X837031D01*
G01X826500Y407750D02*
X827000Y407250D01*
X830500D01*
G01X854820Y348130D02*
X856570D01*
X857835Y346865D01*
X862220D01*
G01Y344895D02*
X855085D01*
X854820Y344630D01*
G01X841656Y411321D02*
Y421156D01*
X849500Y429000D01*
G01Y432750D02*
Y429000D01*
G01X860400Y231000D02*
X870200Y240800D01*
X877705D01*
X1008375Y371470D01*
Y376981D01*
X1032025Y400631D01*
Y400672D01*
X1032500Y401147D01*
Y478785D01*
X1036425Y482710D01*
Y568742D01*
X1044726Y577043D01*
Y624726D01*
X1068000Y648000D01*
X1077750D01*
G01X871420Y346865D02*
X879555D01*
X880820Y348130D01*
G01X867000Y436250D02*
X871500Y440750D01*
X875000D01*
G01X876500Y475000D02*
X871300D01*
G01X875000Y440750D02*
Y438500D01*
X876000Y437500D01*
Y435500D01*
G01X874500Y449000D02*
Y454250D01*
G01Y449000D02*
Y444750D01*
X875000Y444250D01*
G01D02*
X879500D01*
G01X880500Y475250D02*
X880250Y475000D01*
X876500D01*
G01X1029500Y120750D02*
X1019250D01*
X1014000Y126000D01*
Y172000D01*
X1025250Y183250D01*
X1036250D01*
X1045000Y192000D01*
X1054500D01*
X1056500Y194000D01*
G01X1015500Y876000D02*
Y879934D01*
G01X1025473Y879350D02*
X1022415D01*
X1022160Y879300D01*
X1016134D01*
X1015500Y879934D01*
G01D02*
X1015466Y879968D01*
G01Y902468D02*
Y898468D01*
G01X1025473Y889586D02*
Y893027D01*
X1024000Y894500D01*
X1015500D01*
G01X1015466Y902468D02*
Y906784D01*
X1015250Y907000D01*
G01X1015466Y898468D02*
X1015500Y898434D01*
Y894500D01*
G01X1032200Y921500D02*
X1026668D01*
X1016668Y911500D01*
X1016250D01*
X1011750Y907000D01*
G01X1025500Y129500D02*
Y133250D01*
G01X1029750Y133000D02*
X1025750D01*
X1025500Y133250D01*
G01X1037750Y124000D02*
X1033500D01*
G01X1033250Y137000D02*
X1037085D01*
G01X1033250Y128500D02*
Y133000D01*
G01Y128500D02*
X1029500Y124750D01*
Y124250D01*
G01X1033250Y133000D02*
X1037750D01*
X1039285Y134535D01*
Y139500D01*
G01X1025500Y136750D02*
X1029500D01*
X1029750Y137000D01*
G01D02*
Y139750D01*
X1031000Y141000D01*
G01X1026900Y155000D02*
X1023000D01*
G01X1022000Y147500D02*
X1026500D01*
G01X1031000Y148750D02*
X1027750D01*
X1026500Y147500D01*
G01X1031000Y141000D02*
Y145250D01*
G01D02*
X1033109D01*
X1033500Y145641D01*
X1039125D01*
G01X1030250Y173000D02*
Y168500D01*
G01X1039125Y164927D02*
X1032573D01*
X1032500Y165000D01*
G01X1030250Y168500D02*
Y167250D01*
X1032500Y165000D01*
G01X1035000Y175250D02*
Y172000D01*
X1036000Y171000D01*
G01X1041094Y164927D02*
Y167906D01*
X1039500Y169500D01*
X1037500D01*
X1036000Y171000D01*
G01X1026750Y173000D02*
X1023600D01*
G01X1039500Y178750D02*
X1035000D01*
G01D02*
X1027250D01*
X1023600Y175100D01*
Y173000D01*
G01X1030000Y403500D02*
X1029225Y404275D01*
Y479046D01*
X1033925Y483746D01*
Y569778D01*
X1042226Y578079D01*
Y626098D01*
X1072078Y655950D01*
X1077518D01*
X1077748Y656000D01*
X1077750D01*
G01X1028716Y862218D02*
X1024716D01*
G01X1028466Y866968D02*
X1030098Y868600D01*
Y874725D01*
G01X1028716Y862218D02*
X1028466Y862468D01*
Y866968D01*
G01X1024716Y862218D02*
X1020500D01*
G01X1032657Y894211D02*
Y901500D01*
G01X1032216Y907718D02*
X1032657Y907277D01*
Y901500D01*
G01X1041250Y124000D02*
Y119500D01*
G01Y128500D02*
Y124000D01*
G01X1046999Y145641D02*
Y141010D01*
X1047500Y140509D01*
Y131000D01*
X1045000Y128500D01*
G01X1041250D02*
X1045000D01*
G01X1037750D02*
Y124000D01*
G01X1043062Y145641D02*
Y141062D01*
X1042000Y140000D01*
Y137924D01*
X1041485Y137409D01*
G01X1041094Y145641D02*
Y142594D01*
X1039285Y140785D01*
Y139500D01*
G01X1039500Y175250D02*
Y172702D01*
X1043062Y169140D01*
Y164927D01*
G01X1040000Y182000D02*
X1041600Y180400D01*
Y177350D01*
X1039500Y175250D01*
G01X1066768Y201524D02*
Y198000D01*
X1067268Y197500D01*
X1068828D01*
X1069328Y198000D01*
Y201524D01*
G01X1080468Y211034D02*
X1078034D01*
X1072924Y205924D01*
X1065071D01*
X1064208Y206787D01*
Y208924D01*
G01X1073018Y216349D02*
Y216482D01*
X1067500Y222000D01*
G01X1063718Y219284D02*
X1063750Y219252D01*
Y215000D01*
G01D02*
X1066768Y211982D01*
Y208924D01*
G01X1063718Y219284D02*
Y223284D01*
G01X1060218Y219284D02*
X1055000D01*
G01X1063718Y223284D02*
X1066216D01*
X1067500Y222000D01*
G01X1066218Y227284D02*
X1067934Y229000D01*
X1070500D01*
G01X1069328Y201524D02*
X1074478D01*
X1075218Y200784D01*
G01D02*
X1075800Y201366D01*
Y204900D01*
G01X1088000Y220500D02*
X1087724Y220224D01*
X1080518D01*
G01D02*
X1080468Y220174D01*
Y211034D01*
G01X1073018Y224099D02*
Y226482D01*
X1070500Y229000D01*
G01X1110318Y271719D02*
X1101719D01*
X1083400Y253400D01*
X1079100D01*
X1077000Y255500D01*
Y260000D01*
G01X1092200Y258100D02*
X1085000Y250900D01*
X1079900D01*
X1077000Y248000D01*
G01D02*
Y238000D01*
G01X1079000Y412000D02*
X1081260Y414260D01*
Y418200D01*
G01D02*
X1083700D01*
X1087800Y422300D01*
X1096200D01*
X1097000Y423100D01*
G01X1107160Y843160D02*
X1105910Y841910D01*
X1094550D01*
X1091808Y839168D01*
X1081563D01*
X1079419Y837024D01*
Y765919D01*
X1073098Y759598D01*
Y755304D01*
X1074968Y753434D01*
G01X1088000Y220500D02*
X1106500Y239000D01*
X1139000D01*
X1141468Y241468D01*
Y245784D01*
G01X1110318Y269754D02*
X1103854D01*
X1092200Y258100D01*
G01X1095500Y436750D02*
Y431750D01*
X1099250Y428000D01*
G01D02*
Y425350D01*
X1097000Y423100D01*
G01X1088000Y450000D02*
Y454250D01*
G01X1091625Y444250D02*
X1088000Y447875D01*
Y450000D01*
G01X1098500Y449500D02*
Y451000D01*
X1101500Y454000D01*
Y454250D01*
G01X1099375Y444250D02*
Y448625D01*
X1098500Y449500D01*
G01X1088000Y457750D02*
Y461000D01*
G01X1097000Y454250D02*
X1092500D01*
G01D02*
X1088000D01*
G01X1101700Y854100D02*
Y853600D01*
X1101468Y853368D01*
Y850534D01*
G01X1105968D02*
X1101468D01*
G01X1106725Y867725D02*
X1101021D01*
X1099623Y869123D01*
G01X1096218Y871784D02*
X1096962D01*
X1099623Y869123D01*
G01X1110318Y275600D02*
Y271719D01*
G01X1110500Y280000D02*
X1110318Y279818D01*
Y275600D01*
G01X1106500Y837250D02*
X1109750D01*
X1111000Y836000D01*
G01X1105968Y847034D02*
Y844352D01*
X1107160Y843160D01*
G01X1105968Y850534D02*
X1110468D01*
G01D02*
X1111350Y851416D01*
Y860541D01*
G01X1126000Y850534D02*
X1121968D01*
G01D02*
X1121586Y850916D01*
Y860541D01*
G01X1126211Y865166D02*
X1132336D01*
X1135468Y862034D01*
G01X1139968Y252784D02*
X1141468Y251284D01*
Y245784D01*
G01X1139718Y854218D02*
Y858284D01*
G01X1139750Y862000D02*
Y858316D01*
X1139718Y858284D01*
G01X1135468Y862034D02*
X1135502Y862000D01*
X1139750D01*
G01X1213750Y444000D02*
X1207000D01*
X1203500Y440500D01*
Y431000D01*
X1206500Y428000D01*
X1226500D01*
X1240000Y414500D01*
X1264113D01*
X1274021Y404592D01*
X1280458D01*
X1280500Y404550D01*
G01X1222500Y432250D02*
X1226500D01*
G01X1267499Y434641D02*
Y422749D01*
X1263250Y418500D01*
X1240250D01*
X1234375Y424375D01*
Y427625D01*
X1230500Y431500D01*
G01X1222500Y432250D02*
X1218316D01*
X1218034Y432532D01*
G01X1226500Y432250D02*
X1229750D01*
X1230500Y431500D01*
G01X1234500Y439000D02*
X1231500D01*
G01X1222500Y435750D02*
X1226500D01*
G01Y440250D02*
X1230250D01*
X1231500Y439000D01*
G01X1226500Y435750D02*
Y440250D01*
G01X1222000Y443750D02*
X1226500D01*
G01X1222000D02*
X1217500D01*
X1217250Y444000D01*
G01X1226500Y443750D02*
X1234250D01*
X1237000Y441000D01*
Y432000D01*
G01X1228000Y452500D02*
X1232000D01*
X1235500Y449000D01*
G01X1243000Y431500D02*
X1248250D01*
G01D02*
X1245500Y434250D01*
Y441600D01*
X1248900Y445000D01*
G01X1261594Y434641D02*
Y431594D01*
X1255000Y425000D01*
X1240964D01*
X1237000Y428964D01*
Y432000D01*
G01X1248250Y427500D02*
X1242000D01*
X1239500Y430000D01*
Y445000D01*
X1235500Y449000D01*
G01X1244750Y451500D02*
Y449150D01*
X1248900Y445000D01*
G01X1248250Y435500D02*
Y439250D01*
G01X1237000Y463500D02*
Y459250D01*
X1244750Y451500D01*
G01X1242000Y468750D02*
X1238250D01*
X1237000Y467500D01*
Y463500D01*
G01X1246500Y465250D02*
X1251000D01*
G01X1242000D02*
X1245500Y461750D01*
Y461700D01*
G01D02*
X1245550D01*
X1248250Y459000D01*
X1259500D01*
X1261594Y456906D01*
Y453927D01*
G01X1248250Y451500D02*
Y456000D01*
G01D02*
X1250323Y453927D01*
X1252500D01*
G01X1246500Y468750D02*
X1242000D01*
G01X1251000Y472750D02*
X1247800D01*
G01X1263562Y434641D02*
Y429062D01*
X1256500Y422000D01*
X1250000D01*
G01X1251750Y435500D02*
Y431500D01*
G01D02*
Y427500D01*
G01X1259625Y434641D02*
X1255859D01*
X1255000Y435500D01*
X1251750D01*
G01D02*
X1252000Y435750D01*
Y439500D01*
G01X1263562Y453927D02*
Y458438D01*
X1260500Y461500D01*
X1253500D01*
G01X1251000Y465250D02*
X1253500Y462750D01*
Y461500D01*
G01X1259625Y453927D02*
X1252500D01*
G01X1251000Y468750D02*
Y472750D01*
G01X1271437Y453927D02*
Y458937D01*
G01X1269468Y453927D02*
Y458968D01*
G01X1279311Y453927D02*
Y458311D01*
G01X1277342Y453927D02*
Y458842D01*
G01X1275374Y453927D02*
Y458874D01*
G01X1273405Y453927D02*
Y458405D01*
G01X1318500Y448750D02*
Y456000D01*
X1311000Y463500D01*
G01X1335894Y439453D02*
X1332047D01*
X1330500Y441000D01*
G01X1323500Y445250D02*
X1318500D01*
G01X1323500Y436750D02*
Y441500D01*
G01Y436750D02*
X1327500D01*
G01D02*
X1330750D01*
X1331500Y437500D01*
X1335928D01*
X1335944Y437484D01*
G01X1323500Y441500D02*
Y445250D01*
G01X1348106Y439453D02*
Y441606D01*
X1350000Y443500D01*
X1354000D01*
X1354900Y444400D01*
X1354945D01*
G01X1336750Y452000D02*
Y445000D01*
X1335000Y443250D01*
G01X1339047Y442606D02*
X1335644D01*
X1335000Y443250D01*
G01X1344953Y442606D02*
Y444453D01*
X1348500Y448000D01*
Y448936D01*
X1347468Y449968D01*
Y453034D01*
G01X1341016Y442556D02*
X1341000Y442572D01*
Y445500D01*
X1340000Y446500D01*
Y448000D01*
G01X1340250Y452000D02*
Y448750D01*
X1340000Y448500D01*
Y448000D01*
G01X1338500Y459750D02*
X1332500D01*
X1332000Y459250D01*
G01X1347468Y456534D02*
X1348968Y458034D01*
Y466468D01*
X1351500Y469000D01*
X1359380D01*
X1362500Y465880D01*
Y459000D01*
G01X1354250Y452000D02*
X1348502D01*
X1347468Y453034D01*
G01X1354250Y448000D02*
Y445250D01*
X1354945Y444555D01*
Y444400D01*
G01X1357750Y452000D02*
Y448000D01*
G01X1352500Y460500D02*
X1357500D01*
G01X1357750Y456000D02*
Y452000D01*
G01Y456000D02*
Y460250D01*
X1357500Y460500D01*
G01X1362500Y455000D02*
Y459000D01*
G01X1357500Y466500D02*
X1353500D01*
G01X1354250Y456000D02*
Y452000D01*
G01Y456000D02*
X1351250D01*
X1351000Y455750D01*
G01X1369000Y356500D02*
X1370500D01*
X21220Y373228D03*
X15000Y1008622D03*
X35435Y373228D03*
X82675D03*
X90119Y72219D03*
X96890Y373228D03*
X157480Y283071D03*
X220472D03*
X227041Y1008622D03*
X270078Y92125D03*
Y155117D03*
X332086Y408858D03*
X355708Y96456D03*
X450196Y257874D03*
X490944Y79921D03*
Y255118D03*
X537994Y303150D03*
X572243Y337992D03*
X600925Y44134D03*
X638917D03*
X653974Y1008621D03*
X743897Y353543D03*
Y410629D03*
X825984Y303150D03*
X945197Y380000D03*
X955315Y850829D03*
X968819Y380000D03*
X1008268Y244094D03*
Y411417D03*
X1157095Y128841D03*
X1227166Y155511D03*
X1224016Y180709D03*
Y386221D03*
X1227165Y411417D03*
X1272441Y7087D03*
X1299213D03*
X1305117Y87548D03*
Y262745D03*
X1379862Y108465D03*
Y119095D03*
X1376968Y147243D03*
Y216535D03*
X1385000Y1008622D03*
X1387875Y-15015D03*
G54D31*
X43804Y932420D03*
X100772Y767704D03*
X85304Y884420D03*
X101804Y932420D03*
X216500Y431200D03*
X266500Y211200D03*
X270500D03*
X310429Y264200D03*
X328500Y94200D03*
X315429Y264200D03*
X320429D03*
X321023Y548483D03*
X325023D03*
X337000Y94200D03*
X333500Y946300D03*
X361929Y271200D03*
X352929D03*
X370929D03*
X375000D03*
X378929D03*
X674122Y126632D03*
X675055Y262700D03*
X679055D03*
X706055D03*
X710055D03*
X731468Y779684D03*
X727468D03*
X729468Y811184D03*
X725968D03*
X746716Y122984D03*
X750216D03*
X756000Y579700D03*
X788500Y658200D03*
X787500Y774700D03*
X791500D03*
X826500Y404200D03*
X854820Y344580D03*
X858500Y432700D03*
X880820Y348080D03*
X994500Y536700D03*
X1008500D03*
X1024716Y858668D03*
X1023716Y907668D03*
X1065500Y64200D03*
X1099500Y256200D03*
Y753200D03*
X1096000Y816200D03*
X1099468Y884484D03*
X1103000Y753200D03*
X1134500Y826910D03*
X1121968Y846984D03*
X1137748Y753484D03*
X1135468Y878984D03*
X1179677Y227700D03*
X1183177D03*
X1199677Y230200D03*
X1195677D03*
X1196500Y757700D03*
X1188000Y753700D03*
X1273000Y705700D03*
X1300784Y830732D03*
X1324500Y306200D03*
X1327500Y433200D03*
X1346617Y619612D03*
X1350617Y621112D03*
X1364617Y619612D03*
G54D115*
X672962Y456464D03*
X1048968Y155284D03*
X1269468Y444284D03*
G54D124*
X721716Y121284D03*
G54D160*
X1275984Y17914D03*
X1295670D03*
X1285827D03*
G54D142*
X1017000Y70081D03*
Y58919D03*
G54D151*
X1095006Y745402D03*
Y738906D03*
X1104230Y745402D03*
Y738906D03*
G54D133*
X780718Y450094D03*
Y452062D03*
X792830Y450094D03*
Y452062D03*
X1348056Y437484D03*
Y435516D03*
X1335944D03*
Y437484D03*
G54D22*
X48820Y403503D03*
X45670D03*
X42520D03*
X39370D03*
X50395Y393623D03*
X47245D03*
X44095D03*
X40945D03*
X67715Y403503D03*
X64565D03*
X61415D03*
X58270D03*
X55120D03*
X66140Y393623D03*
X62990D03*
X59840D03*
X56695D03*
X53545D03*
X51970Y403503D03*
X77165D03*
X74015D03*
X70865D03*
X78740Y393623D03*
X75590D03*
X72440D03*
X69290D03*
X166141Y303465D03*
X162992D03*
X164567Y313347D03*
X161417D03*
X181889Y303465D03*
X178740D03*
X175590D03*
X172441D03*
X169291D03*
X180315Y313347D03*
X177165D03*
X174015D03*
X170866D03*
X167716D03*
X197637Y303465D03*
X194488D03*
X191338D03*
X188189D03*
X185039D03*
X196063Y313347D03*
X192913D03*
X189763D03*
X186614D03*
X183464D03*
X213385Y303465D03*
X210236D03*
X207086D03*
X203937D03*
X200787D03*
X214960Y313347D03*
X211811D03*
X208661D03*
X205511D03*
X202362D03*
X199212D03*
X216535Y303465D03*
G54D40*
X106654Y794785D03*
Y796750D03*
Y798720D03*
Y800690D03*
Y802655D03*
X122954Y794785D03*
Y802655D03*
Y800690D03*
Y798720D03*
Y796750D03*
X166700Y467345D03*
Y469315D03*
Y471285D03*
Y473255D03*
X175900Y467345D03*
Y473255D03*
Y471285D03*
Y469315D03*
X222673Y497608D03*
Y499578D03*
Y501543D03*
Y503513D03*
Y505483D03*
Y507453D03*
Y509418D03*
Y511388D03*
Y513358D03*
Y515323D03*
Y517293D03*
Y519263D03*
Y521228D03*
Y523198D03*
Y525168D03*
Y527138D03*
Y529103D03*
Y531073D03*
Y533043D03*
Y535008D03*
Y536978D03*
Y538948D03*
Y540913D03*
Y542883D03*
Y544853D03*
Y546823D03*
Y548788D03*
Y550758D03*
X298373Y499578D03*
Y497608D03*
Y515323D03*
Y513358D03*
Y511388D03*
Y509418D03*
Y507453D03*
Y505483D03*
Y503513D03*
Y501543D03*
Y533043D03*
Y531073D03*
Y529103D03*
Y527138D03*
Y525168D03*
Y523198D03*
Y521228D03*
Y519263D03*
Y517293D03*
Y548788D03*
Y546823D03*
Y544853D03*
Y542883D03*
Y540913D03*
Y538948D03*
Y536978D03*
Y535008D03*
Y550758D03*
X871420Y348835D03*
Y346865D03*
Y344895D03*
Y342925D03*
X862220D03*
Y344895D03*
Y346865D03*
Y348835D03*
X950850Y447745D03*
Y449715D03*
Y451685D03*
Y453655D03*
X960050Y449715D03*
Y447745D03*
Y453655D03*
Y451685D03*
X1110318Y263849D03*
Y265814D03*
Y267784D03*
Y269754D03*
Y271719D03*
X1126618Y269754D03*
Y267784D03*
Y265814D03*
Y263849D03*
Y271719D03*
X1288818Y641849D03*
Y643814D03*
Y645784D03*
Y647754D03*
Y649719D03*
X1288318Y673349D03*
Y675314D03*
Y677284D03*
Y679254D03*
Y681219D03*
X1305118Y647754D03*
Y645784D03*
Y643814D03*
Y641849D03*
Y649719D03*
X1304618Y679254D03*
Y677284D03*
Y675314D03*
Y673349D03*
Y681219D03*
G54D106*
X590315Y9134D03*
Y19134D03*
X649527Y9134D03*
Y19134D03*
Y29134D03*
G54D13*
X8200Y857700D03*
X8000Y853500D03*
X8442Y847311D03*
X35304Y832220D03*
X34304Y897720D03*
X50395Y384679D03*
X40945Y384710D03*
X47483Y387776D03*
X43883Y387769D03*
X48820Y412435D03*
X39370Y412673D03*
X52000Y655500D03*
X40054Y823970D03*
X44804Y837220D03*
X36004Y839500D03*
X44500Y851500D03*
X49000Y861500D03*
X52000Y872720D03*
X37232Y877242D03*
X51896Y878668D03*
X42554Y891720D03*
X37211Y881115D03*
X37758Y884674D03*
X40304Y887220D03*
X51304Y882220D03*
X47804Y906720D03*
X43804Y907720D03*
X38804Y906220D03*
X41304Y927220D03*
X50270Y929186D03*
X41500Y941500D03*
X46500Y944500D03*
X59840Y384679D03*
X62783Y387776D03*
X66483Y387876D03*
X56883D03*
X53183Y387676D03*
X67715Y412518D03*
X58270Y412485D03*
X60304Y663220D03*
X55304Y669720D03*
X58804Y710220D03*
X64304Y698720D03*
X63304Y706720D03*
X68147Y722511D03*
X62704Y739620D03*
X64272Y736004D03*
X55304Y746220D03*
X65272Y758504D03*
X64683Y762056D03*
X59272Y790504D03*
X57772Y801504D03*
X61492Y803004D03*
X55022Y826720D03*
X66022Y827254D03*
X57304Y815720D03*
X61304Y815220D03*
X65804Y835720D03*
X57804Y834720D03*
X61804D03*
X55304Y849720D03*
X52304Y868220D03*
X60804Y907720D03*
X56804Y907220D03*
X52304Y906720D03*
X64804Y907720D03*
X52804Y943220D03*
X57770Y932686D03*
X55270Y929186D03*
X52770Y932686D03*
X62770D03*
X60270Y929186D03*
X52804Y938795D03*
X78740Y384915D03*
X69290Y384865D03*
X71883Y387976D03*
X76083D03*
X77165Y412590D03*
X76804Y662720D03*
Y710220D03*
X73804Y699720D03*
X81304Y710220D03*
X71846Y722426D03*
X77272Y724004D03*
X75432Y735059D03*
X83849Y735513D03*
X80272Y735103D03*
X68910Y760642D03*
X83112Y760720D03*
X75432Y758844D03*
X76272Y762504D03*
X80624Y764241D03*
X68762Y764239D03*
X77804Y773720D03*
X71804Y789720D03*
X82804Y794920D03*
X84804Y808720D03*
X73772Y822004D03*
X79000Y836500D03*
X69804Y835720D03*
X84221Y836078D03*
X77500Y832000D03*
X83838Y848133D03*
X76804Y847720D03*
X70909Y847325D03*
X72304Y869720D03*
X76304D03*
X81304Y884470D03*
X81804Y888720D03*
X72770Y906488D03*
X95304Y663720D03*
X89804Y669720D03*
X95304Y686220D03*
X97737Y698653D03*
X94804Y708220D03*
X99804Y709220D03*
X87772Y735059D03*
X92365Y735040D03*
X85672Y763504D03*
X96060Y762476D03*
X86404Y774720D03*
X85304Y768720D03*
X100804Y774720D03*
X93347Y765754D03*
X99804Y799720D03*
X85204Y798220D03*
X85804Y816220D03*
X92304Y835720D03*
X87804D03*
X87928Y848107D03*
X98304Y888220D03*
X95700Y926300D03*
X97804Y940720D03*
X112654Y314453D03*
X111304Y663720D03*
X111907Y698617D03*
X115804Y798720D03*
X105000Y834500D03*
X113222Y831222D03*
X112500Y835000D03*
X110500Y848500D03*
X115500D03*
X109054Y892720D03*
X102304Y895220D03*
X114054Y892720D03*
X106554Y895720D03*
X116554D03*
X111554Y896220D03*
X105804Y943220D03*
X109054Y932720D03*
X116600Y929924D03*
X114054Y932470D03*
X111554Y929720D03*
X101804Y940720D03*
X108804Y938795D03*
X115500Y983500D03*
X127654Y293453D03*
X132500Y312500D03*
X124500Y316000D03*
X132123Y318877D03*
X123654Y320953D03*
X131500Y324000D03*
X122906Y331953D03*
X122874Y354709D03*
X127301D03*
X131147D03*
X132500Y547000D03*
Y559600D03*
Y556000D03*
Y551500D03*
X133500Y582500D03*
X125050Y583000D03*
X126500Y587500D03*
X121685Y587919D03*
X134000Y587000D03*
X130000Y666500D03*
X129304Y798720D03*
X122500Y845500D03*
X128000Y870500D03*
X129100Y892924D03*
X124054Y892220D03*
X121600Y895266D03*
X119054Y892720D03*
X132804Y894220D03*
X126554Y895470D03*
X121598Y929924D03*
X131554Y929470D03*
X129054Y932720D03*
X126554Y929882D03*
X124098Y932515D03*
X119099Y932516D03*
X118000Y991500D03*
X145500Y283500D03*
X134874Y354709D03*
X147374D03*
X143147D03*
X139301D03*
X147500Y472100D03*
X135500Y511000D03*
X136000Y566000D03*
X136500Y576900D03*
Y573300D03*
Y580500D03*
Y569700D03*
X140500Y568000D03*
X144000Y572500D03*
X149100Y661100D03*
X143010Y676400D03*
X143500Y710500D03*
X141054Y795820D03*
X150225Y790412D03*
X146304Y804220D03*
X146500Y808220D03*
X162595Y296709D03*
X165793Y294309D03*
X153437Y320458D03*
X155874Y310209D03*
Y313961D03*
Y317807D03*
X152995Y329119D03*
X159674Y328609D03*
X159774Y320709D03*
X164147Y328699D03*
X155874Y326957D03*
Y323111D03*
X158874Y354709D03*
X155147D03*
X162801D03*
X166647D03*
X151301D03*
X160000Y465500D03*
X158500Y461500D03*
X153050Y486500D03*
X163225Y522080D03*
X154625Y550290D03*
X154755Y539310D03*
X163305Y554750D03*
X160500Y586500D03*
X156900D03*
X152948Y587000D03*
X166000Y662500D03*
X157750Y662250D03*
X166500Y650500D03*
X166875Y678285D03*
X162500Y670000D03*
X153500Y690275D03*
X163000Y710500D03*
X150900Y812500D03*
X154500D03*
X152500Y840000D03*
X157500Y867500D03*
X163000Y901000D03*
X158000D03*
X172285Y296964D03*
X181889Y297303D03*
X169639Y294309D03*
X179088Y294909D03*
X175242D03*
X183374Y328709D03*
X171874D03*
X171295Y320709D03*
X180315Y321209D03*
X167993Y328699D03*
X179622Y328749D03*
X175776D03*
X170374Y354709D03*
X182800Y465800D03*
Y471300D03*
X171500Y478699D03*
X177493Y533493D03*
X170339Y537396D03*
X180555Y560500D03*
X175993Y559938D03*
X175055Y569500D03*
X167469Y588969D03*
X172040Y688960D03*
X174000Y830500D03*
X170500Y835500D03*
X179500Y847000D03*
X172000Y868000D03*
X168400D03*
X183000Y865750D03*
X181000Y901000D03*
X174500Y901500D03*
X168500Y901000D03*
X197245Y296571D03*
X188295Y297209D03*
X193841Y297755D03*
X185039Y295209D03*
X191295D03*
X196063Y319209D03*
X186614Y319028D03*
X190295Y318709D03*
X192874Y326209D03*
X198864Y323297D03*
X192874Y334307D03*
Y330461D03*
X184295Y322209D03*
X192795Y321709D03*
X192874Y337907D03*
X189000Y347600D03*
X192874Y341611D03*
Y345457D03*
X192500Y431500D03*
X187300Y457300D03*
X191800D03*
X190800Y462800D03*
X189355Y526470D03*
X185000Y533562D03*
X185305Y521100D03*
X195725Y540750D03*
X195865Y552940D03*
X198500Y563000D03*
X189500Y573500D03*
X194500Y724000D03*
X198000Y785000D03*
X191875Y803125D03*
X186000Y841500D03*
X185000Y856000D03*
X185500Y848260D03*
X187000Y878000D03*
X199000Y891500D03*
X190500Y894000D03*
X195000Y891500D03*
X188000Y901000D03*
X197000D03*
Y897000D03*
X207086Y297418D03*
X204285Y294909D03*
X213733D03*
X200439D03*
X209887D03*
X205511Y320709D03*
X214960Y321044D03*
X208338Y323297D03*
X202710D03*
X212134D03*
X212500Y435000D03*
X204500Y470000D03*
X207773Y516562D03*
X208305Y548670D03*
Y536320D03*
Y562640D03*
X203000Y564500D03*
X201000Y625500D03*
X212500Y716500D03*
X204500Y721000D03*
X212500Y786000D03*
X204500Y817500D03*
X215250Y833750D03*
X205500Y830000D03*
X204000Y862000D03*
X212000Y891500D03*
X203500Y894000D03*
X208000Y892000D03*
X205500Y901000D03*
Y897000D03*
X217295Y296709D03*
X232500Y419000D03*
Y431000D03*
Y425000D03*
X229055Y497000D03*
X216500Y516000D03*
X228319Y524798D03*
X230000Y680500D03*
X221000Y723000D03*
X218000Y801500D03*
X223500Y825500D03*
X228000Y825000D03*
X232000D03*
X227000Y858000D03*
X217000Y858500D03*
X222000Y853500D03*
Y858500D03*
Y863500D03*
Y893600D03*
X231500Y898500D03*
X243755Y490890D03*
X242003Y506327D03*
X234755Y509700D03*
X245205Y504679D03*
X246613Y501365D03*
X237055Y513500D03*
X234185Y527138D03*
X248855Y532300D03*
X239555Y519500D03*
X240000Y829250D03*
X247500Y829500D03*
X237953Y861453D03*
X236500Y866000D03*
X259055Y500500D03*
X260288Y514589D03*
X264655Y511100D03*
X250055Y510800D03*
X256055Y531016D03*
X260555Y525500D03*
X253679Y523137D03*
X260605Y519245D03*
X263555Y534500D03*
X261255Y549000D03*
X265455Y544853D03*
X252055Y548760D03*
X257555Y549000D03*
X258500Y608500D03*
Y613500D03*
X253500Y608500D03*
X253555Y613500D03*
X251000Y835500D03*
X251500Y855500D03*
X261500Y857500D03*
X252000Y846500D03*
X252500Y851500D03*
X250362Y865000D03*
X253610Y863447D03*
X268300Y219800D03*
X279997Y514179D03*
X275555Y531500D03*
X275055Y521825D03*
X266055Y531725D03*
X272571Y541150D03*
X278367Y535140D03*
X269555Y536000D03*
X271451Y544616D03*
X278676Y539500D03*
X273000Y674000D03*
X270000Y870000D03*
Y865500D03*
X276500Y888500D03*
X269000Y921500D03*
X274000D03*
X280500Y955000D03*
X278050Y958500D03*
X273678Y958000D03*
X268178Y955500D03*
X296200Y94400D03*
X294500Y98500D03*
X297929Y332000D03*
Y336000D03*
X293929Y342000D03*
X292525Y498780D03*
X292045Y504897D03*
X293273Y509500D03*
X282626Y516639D03*
X291530Y525407D03*
X283103Y520208D03*
X286588Y519305D03*
X292555Y533043D03*
X291755Y529000D03*
X286555Y524524D03*
X282555Y540700D03*
X283038Y536850D03*
X299300Y84200D03*
X309500Y78500D03*
X313250Y85250D03*
X311500Y81500D03*
X314000Y102500D03*
X302000Y94300D03*
X299831Y144328D03*
X303677D03*
X313402Y156000D03*
X305852Y163800D03*
X309698D03*
X305429Y219400D03*
Y223000D03*
X307500Y299000D03*
X299395Y449160D03*
X303545Y445840D03*
X312925Y462560D03*
X300112Y483783D03*
X298662Y479783D03*
X305055Y472500D03*
X302555Y476000D03*
X312773Y529878D03*
X305255Y542600D03*
X313000Y582000D03*
X324500Y6000D03*
Y10500D03*
X316900Y65900D03*
X320500Y66000D03*
X327000Y89500D03*
X323000D03*
X319309Y89503D03*
X317500Y101000D03*
X317660Y96400D03*
X324200Y101900D03*
X330000Y118500D03*
X325929D03*
X321500D03*
X329929Y128500D03*
X325929Y127700D03*
X327100Y136294D03*
Y139857D03*
X326422Y152507D03*
Y148944D03*
X317248Y156000D03*
X319800Y146898D03*
Y143052D03*
X322229Y218800D03*
X316129Y213000D03*
X329929Y241500D03*
X328000Y285000D03*
X326000Y292500D03*
X327000Y308000D03*
X331000Y308018D03*
X330555Y467500D03*
X325873Y477006D03*
X325854Y480606D03*
X317195Y493280D03*
X317255Y514170D03*
X330491Y525490D03*
X315725Y549790D03*
X321555Y534500D03*
X329695Y534650D03*
X315135Y554980D03*
X317758Y581297D03*
X329055Y569500D03*
X321780Y575000D03*
X314930Y585500D03*
X321500Y688000D03*
X336700Y4300D03*
X341200D03*
X346000Y4400D03*
X333000Y90500D03*
X343000Y89000D03*
X339500Y75500D03*
X337500Y84250D03*
X342000Y102000D03*
X346000D03*
X334500Y118500D03*
X334600Y129468D03*
Y133031D03*
X345929Y183000D03*
X340679Y204900D03*
X332429Y210000D03*
X346404Y260000D03*
X344429Y312000D03*
X341500Y309500D03*
X343929Y320700D03*
X345929Y336500D03*
X341351Y336434D03*
X344929Y325500D03*
X342500Y340000D03*
X338500Y397500D03*
X343095Y446200D03*
X336375Y452870D03*
X338985Y467405D03*
X338595Y482590D03*
X339140Y512500D03*
X336445Y509330D03*
X343555Y517000D03*
X343688Y509533D03*
X334055Y526000D03*
X347213Y546700D03*
X340715Y545840D03*
X334555Y548500D03*
X341055Y534500D03*
X344655D03*
X345500Y556500D03*
X339888Y586388D03*
X346402Y653004D03*
X342500Y653000D03*
X335500Y868000D03*
X332129Y889371D03*
X331829Y885500D03*
X338000Y942000D03*
X339500Y936500D03*
Y960000D03*
X333500Y954000D03*
X355000Y4400D03*
X350500D03*
X360400D03*
X352000Y66000D03*
X357500Y79500D03*
Y75500D03*
X352500Y113000D03*
X348429Y130000D03*
X353929Y128500D03*
X351429Y126500D03*
X353300Y218400D03*
X362500Y286000D03*
X348000Y292500D03*
X351929Y332500D03*
X357055Y385000D03*
Y380500D03*
Y376500D03*
X355055Y394000D03*
Y389500D03*
X364015Y468450D03*
X349575Y479503D03*
X349815Y475550D03*
X364055Y512000D03*
X358797Y532258D03*
X354055Y534000D03*
X352095Y524040D03*
X362555Y534500D03*
X351815Y546880D03*
X348255Y534500D03*
X360500Y588500D03*
X350000Y652878D03*
X362210Y876200D03*
X364000Y869500D03*
X363480Y907783D03*
X362000Y904500D03*
X363000Y931500D03*
X359000D03*
X354000Y960000D03*
X363614Y971524D03*
X361000Y974000D03*
X360024Y979100D03*
X364900Y4400D03*
X369400D03*
X366600Y285800D03*
X377855Y300110D03*
X374000Y293500D03*
X372055Y319500D03*
X369555Y322500D03*
X371555Y347500D03*
X372055Y364000D03*
X375805Y380250D03*
X370275Y413540D03*
X371710Y406535D03*
X369555Y417500D03*
X370575Y409952D03*
X375055Y444500D03*
X367022Y482783D03*
X373555Y482500D03*
X378255Y471840D03*
X379000Y531000D03*
X367555Y545500D03*
X380000Y872000D03*
X371000Y866500D03*
X376041Y866041D03*
X375500Y906000D03*
Y901500D03*
X365500Y916000D03*
X369341Y916117D03*
X371100Y926000D03*
X377000Y927500D03*
X372300Y918749D03*
X371938Y922438D03*
X369500Y936500D03*
X368000Y932000D03*
X371000Y930000D03*
X376000Y960000D03*
X364396Y980109D03*
X366878Y977500D03*
X369200Y980252D03*
X372500Y977918D03*
X377464Y987493D03*
X377250Y982250D03*
X390000Y13500D03*
X385000D03*
X391000Y238500D03*
X395500Y237000D03*
X388000Y233500D03*
X388149Y229780D03*
X393429Y229500D03*
X394929Y247000D03*
X395450Y265400D03*
X390100Y263600D03*
X387500Y261000D03*
X381500Y297000D03*
X395104Y291056D03*
X382455Y331870D03*
X386755Y447300D03*
X393055Y451000D03*
Y447400D03*
X385463Y450948D03*
X396055Y456500D03*
X386055Y454500D03*
X388885Y471100D03*
X381500Y534000D03*
X384046Y536546D03*
X389000Y604000D03*
X396000Y714500D03*
X392500Y718500D03*
X391000Y866500D03*
X395500Y867000D03*
X396500Y888500D03*
X396600Y895855D03*
X396330Y899705D03*
X396500Y904000D03*
X384000Y926500D03*
X389838Y942300D03*
X383500Y938500D03*
X388500Y955250D03*
X390000Y946500D03*
X397900Y231800D03*
X409929Y245400D03*
X399500Y240500D03*
X412513Y294800D03*
X398385Y292540D03*
X401855Y293500D03*
X408656Y291500D03*
X405555Y293500D03*
X401555Y318000D03*
X406555Y320500D03*
X403255Y425950D03*
X404500Y877300D03*
X410500Y885500D03*
X397600Y892000D03*
X399500Y901500D03*
X403250Y949000D03*
X408250Y949500D03*
X410500Y954500D03*
X405704Y952046D03*
X398250Y955000D03*
X400750Y952000D03*
X410000Y983500D03*
X410500Y987500D03*
X401500Y994500D03*
X414000Y8000D03*
X418192Y114237D03*
X421000Y231500D03*
X420429Y246400D03*
X424929Y264700D03*
X428100Y266500D03*
X419600Y282900D03*
X416500Y284800D03*
X422500Y271501D03*
X419455Y293000D03*
X416187Y294711D03*
X429500Y311000D03*
X425178Y798000D03*
X425278Y802000D03*
X418278Y828000D03*
Y840000D03*
X418500Y857500D03*
X418278Y854000D03*
Y846500D03*
X416046Y959546D03*
X414500Y948500D03*
X414215Y952089D03*
X422098Y948630D03*
X418500Y948500D03*
X413500Y957000D03*
X416000Y964000D03*
X420000D03*
X413600Y983500D03*
X425000Y994500D03*
X440000Y5000D03*
X438500Y9000D03*
X433929Y100000D03*
X430540Y108750D03*
X439000Y254500D03*
X440500Y267000D03*
X433929Y264300D03*
X439800Y284100D03*
X444255Y283700D03*
X430900Y294550D03*
X439200D03*
X432500Y301000D03*
X435000Y294000D03*
X436416Y357676D03*
X432178Y798000D03*
X438178Y798500D03*
X444678Y798400D03*
X444778Y802100D03*
X438278D03*
X431778Y802000D03*
X442278Y846000D03*
X431500Y886000D03*
X437678D03*
X443178D03*
X431278Y883000D03*
X444278D03*
X437778D03*
X432000Y933500D03*
X430500Y962000D03*
X460000Y5000D03*
X459429Y106000D03*
X448929Y99500D03*
X457500Y121000D03*
X450929Y118000D03*
X457429Y171500D03*
X462500Y169000D03*
X455054Y179475D03*
X458429Y175590D03*
X456000Y243500D03*
X460000D03*
X461100Y260050D03*
X459055Y263500D03*
X459500Y290100D03*
X458685Y425710D03*
X456178Y798000D03*
X452978Y805400D03*
X456278Y802100D03*
X455278Y846000D03*
X451278D03*
X459278D03*
X451178Y886000D03*
X460678D03*
X457578Y879700D03*
X450778Y883000D03*
X460778D03*
X471290Y118361D03*
X469000Y113000D03*
X472990Y113350D03*
X462700Y120800D03*
X471429Y133500D03*
X477291Y147500D03*
X477900Y153600D03*
X471000Y141000D03*
X477929Y158000D03*
X467600Y158400D03*
X465600Y162000D03*
X475216Y182917D03*
X470000Y188500D03*
X462679Y176900D03*
X466700Y259400D03*
X464055Y256500D03*
X469155Y297800D03*
X463371Y290371D03*
X474755Y308300D03*
X464200Y307838D03*
X463945Y349700D03*
X466655Y425340D03*
X472055Y425000D03*
X475678Y798500D03*
X463178D03*
X469178D03*
X475778Y802100D03*
X462778D03*
X469278D03*
X467278Y846000D03*
X468178Y886000D03*
X472178D03*
X473778Y883000D03*
X467278D03*
X485000Y5000D03*
X488500Y114200D03*
X481929Y126500D03*
X481429Y150000D03*
X490100Y162100D03*
X491257Y315952D03*
X495103D03*
X487612Y318606D03*
X492555Y431250D03*
X482178Y886000D03*
X480278Y883000D03*
X488000Y904500D03*
X483500Y907500D03*
X503929Y127500D03*
X499390Y153500D03*
X503500D03*
X503929Y146500D03*
X506429Y149500D03*
X495929Y164500D03*
X499629Y178400D03*
X498855Y302851D03*
X508500Y320000D03*
X504453Y314200D03*
X500607D03*
X496155Y321700D03*
X495555Y369500D03*
X507355Y390800D03*
X505922Y415371D03*
X506163Y419973D03*
X508100Y605500D03*
X506000Y610000D03*
X497778Y843000D03*
Y838500D03*
Y847000D03*
X498500Y867500D03*
X515000Y5000D03*
X513200Y121450D03*
X521700Y114000D03*
X525679Y136250D03*
X517679Y125750D03*
X513000Y156500D03*
X512000Y320000D03*
X519706Y314000D03*
X515860D03*
X527002Y319359D03*
X523348D03*
X526500Y346532D03*
Y342969D03*
Y352969D03*
X520500Y351500D03*
Y347937D03*
Y358937D03*
X526500Y356532D03*
X520500Y362500D03*
X521500Y632500D03*
X533000Y153800D03*
X528500Y172000D03*
X539714Y179150D03*
X542500Y188500D03*
X537479Y197875D03*
X539073Y237300D03*
X531590Y297620D03*
X534500Y295500D03*
X528500Y310000D03*
X534629Y311171D03*
X534960Y321000D03*
X538614D03*
X529848Y325500D03*
X533502D03*
X545000Y5000D03*
X550500Y188000D03*
X560500Y186000D03*
X555500Y194000D03*
X559500D03*
X545000Y195000D03*
X549926Y204000D03*
X557275Y214918D03*
X553675Y215913D03*
X550075D03*
X559961Y209419D03*
X546916Y217641D03*
X548000Y231000D03*
X547746Y225303D03*
X559971Y237753D03*
X553555Y321000D03*
X560253Y329500D03*
X557061Y334194D03*
X553155Y334300D03*
X548000Y369500D03*
X555935Y363000D03*
X559500Y604500D03*
X575000Y5000D03*
X577000Y58000D03*
X572000Y189000D03*
X571398Y183602D03*
X561429Y174441D03*
X575500Y198400D03*
X576650Y204500D03*
X563100Y194000D03*
X568158Y206455D03*
X571461Y207887D03*
X569000Y217000D03*
X569127Y213100D03*
X564583Y206028D03*
X577119Y233139D03*
X564631Y234356D03*
X569322Y234220D03*
X573179Y233535D03*
X575425Y228505D03*
X574000Y269000D03*
X563704Y272000D03*
X563555Y333000D03*
X571555Y326000D03*
X562055Y347500D03*
X564215Y369339D03*
X566430Y366500D03*
X569555Y364000D03*
X562555Y364500D03*
X587175Y202525D03*
X591413Y199087D03*
X583500Y204500D03*
X585325Y198000D03*
X583325Y208500D03*
X583204Y236805D03*
X580709Y232091D03*
X619876Y195000D03*
X617828Y303250D03*
X613962D03*
X623500Y576500D03*
X622500Y608500D03*
X633578Y303250D03*
X629712D03*
X642800Y433587D03*
X641500Y449500D03*
X636500Y444800D03*
X640500Y444500D03*
X641625Y465375D03*
X635325Y457500D03*
X628250Y570200D03*
X628524Y591976D03*
X646500Y101000D03*
X650500D03*
X649323Y303250D03*
X645457D03*
X647125Y429375D03*
X652714Y428214D03*
X647500Y425500D03*
X645500Y459500D03*
X656162Y472338D03*
X654500Y494000D03*
X654300Y490300D03*
X647252Y576500D03*
X674469Y99380D03*
X674358Y103170D03*
X662248Y101000D03*
X667748Y104000D03*
X665073Y303250D03*
X661207D03*
X663500Y452000D03*
X672500D03*
X660000Y443500D03*
X669025Y441725D03*
X660500Y436538D03*
X663500Y456000D03*
Y460500D03*
X667500Y454000D03*
Y458500D03*
X672500Y456000D03*
Y460500D03*
X669462Y472500D03*
X667056Y475500D03*
X673010Y474436D03*
X673300Y579000D03*
X669000D03*
X663500Y610500D03*
X674688Y696751D03*
X670474Y808700D03*
X671500Y861000D03*
X673500Y864000D03*
X672000Y967750D03*
X667000Y969700D03*
X666750Y961550D03*
X685000Y5000D03*
X685519Y55019D03*
X676748Y52000D03*
X684861Y58584D03*
X686000Y62000D03*
X684197Y74703D03*
X687055Y258500D03*
X683055D03*
X678055D03*
X681000Y452000D03*
X687500Y440500D03*
X681000Y456000D03*
Y460500D03*
X676500Y454000D03*
Y458500D03*
X690000Y460500D03*
X677500Y472500D03*
X688500Y606000D03*
X683000Y603950D03*
X677500Y612000D03*
X680000Y640000D03*
X691000Y704500D03*
X677500Y699000D03*
X682968Y758284D03*
X687968Y755284D03*
X677500Y773500D03*
X687968Y781784D03*
X678468Y805284D03*
X691300Y807300D03*
X679000Y865050D03*
X676500Y967750D03*
X695000Y20000D03*
X700000Y60500D03*
X706716Y82448D03*
X706055Y258500D03*
X705500Y575600D03*
X705900Y569200D03*
X698818Y759350D03*
X702918Y782734D03*
X703328Y800144D03*
X697250Y876750D03*
X704000Y892500D03*
X715000Y5000D03*
X725000Y20000D03*
X716034Y53966D03*
X716466Y65466D03*
X711216Y82402D03*
X720216Y82138D03*
X715716Y82652D03*
X713716Y121284D03*
X721716Y112784D03*
Y116784D03*
X717716Y121284D03*
X721716D03*
Y129284D03*
Y125284D03*
X711500Y179400D03*
X721200Y205800D03*
X710055Y258500D03*
X714055D03*
X725000Y452300D03*
X720700Y564200D03*
X717036Y563783D03*
X709750Y585200D03*
X719918Y754734D03*
X715118Y776134D03*
X723168Y774984D03*
X717468Y810784D03*
X722000Y808500D03*
X720500Y860000D03*
X712500Y859750D03*
X716250Y860250D03*
X710750Y863250D03*
X714000Y867500D03*
X714500Y891000D03*
X728966Y53966D03*
Y65466D03*
X740500Y75000D03*
X729716Y121284D03*
X725716D03*
X733498Y180750D03*
X733000Y193000D03*
X728100Y213800D03*
X732500Y455500D03*
X736000Y464500D03*
X728500Y482500D03*
X732500Y485500D03*
X734500Y547500D03*
X730000Y536500D03*
X734462Y553538D03*
X733500Y568500D03*
X729900D03*
X741500Y582450D03*
X737000Y583640D03*
X733268Y757984D03*
X740768Y763984D03*
X735500Y771984D03*
X735000Y780500D03*
X736000Y810500D03*
X733768Y800734D03*
X727468Y819284D03*
X733440Y875560D03*
X741050Y869500D03*
X740000Y886000D03*
X737290Y903000D03*
X733000Y969700D03*
X745000Y5000D03*
X755000Y20000D03*
X747800Y50200D03*
X754500Y67500D03*
X757200Y103100D03*
X745500Y145000D03*
X747000Y210000D03*
X755697Y303250D03*
X749750Y454000D03*
X755300Y489300D03*
X751484Y540600D03*
X746750Y571750D03*
X748000Y579500D03*
X755000Y727500D03*
X757500Y743500D03*
X745400Y877600D03*
X757000Y896400D03*
X749500Y974300D03*
X762250Y71000D03*
X761000Y88500D03*
Y82500D03*
X760600Y94500D03*
X770500Y136000D03*
X770900Y144300D03*
X765116Y187659D03*
X759563Y303250D03*
X771447D03*
X773500Y326000D03*
X758500Y457000D03*
X771000Y464000D03*
X772024Y478976D03*
X774500Y489500D03*
X760500D03*
X765009Y563491D03*
X766000Y635000D03*
X763000Y648000D03*
X767000Y648500D03*
X760125Y666875D03*
X771000Y689500D03*
X770646Y685354D03*
X760500Y707950D03*
X768000Y728000D03*
X763500Y839500D03*
X768000Y833000D03*
X766750Y849250D03*
X774500Y890500D03*
X775000Y5000D03*
X785000Y20000D03*
X775748Y188500D03*
X789500Y235837D03*
X787192Y303250D03*
X775313D03*
X788600Y449300D03*
X784800D03*
X784900Y453000D03*
X788800D03*
X779000Y458000D03*
X776000Y478828D03*
X788774Y482774D03*
X784274Y486274D03*
X790600Y547600D03*
X790000Y554500D03*
X786500Y575688D03*
X786032Y570468D03*
X783500Y649000D03*
X784804Y673304D03*
X785500Y666500D03*
X783746Y692754D03*
X779500Y705000D03*
X787500Y783500D03*
X782750Y845750D03*
X781000Y877000D03*
X785000Y892000D03*
X776750Y964750D03*
X785500Y969700D03*
X805000Y5000D03*
X796000Y167600D03*
X795500Y163408D03*
X802942Y303250D03*
X791058D03*
X806808D03*
X798000Y400500D03*
X806274Y434726D03*
X796074Y479000D03*
X791000Y562000D03*
X802500Y579500D03*
X803500Y655000D03*
X798000Y706000D03*
X802000Y724000D03*
X794000Y723500D03*
X791500Y783500D03*
X801750Y867500D03*
X805250Y865750D03*
X794500Y897000D03*
X815000Y20000D03*
X818000Y240900D03*
X821100Y348480D03*
Y352480D03*
X808500Y363500D03*
X811000Y430500D03*
X823500Y480000D03*
X814500Y472500D03*
X823500Y556500D03*
X815900Y564000D03*
X819500D03*
X810000Y735500D03*
X821250Y845750D03*
X810500Y851000D03*
X814000Y849500D03*
X819000Y868500D03*
X810000Y980000D03*
X835000Y5000D03*
X832000Y137500D03*
X826198Y239950D03*
X833555Y262000D03*
X838055Y262500D03*
X825500Y411100D03*
X832500Y404000D03*
X826500Y436000D03*
X826000Y465078D03*
X831000Y598500D03*
X833500Y613000D03*
X835000Y719000D03*
X826500Y743000D03*
X839250Y854500D03*
X826060Y863440D03*
X824560Y868560D03*
X840000Y980000D03*
X850000Y20000D03*
X856055Y262500D03*
X842555Y262000D03*
X847055Y262500D03*
X851555D03*
X854820Y352380D03*
X850540Y346070D03*
X844410Y346360D03*
X847500Y352000D03*
X852000Y401500D03*
X842000D03*
X847000Y396500D03*
Y401500D03*
Y406500D03*
X854000Y436500D03*
X849500Y622000D03*
X846250Y642250D03*
X854000Y640500D03*
X846500Y710000D03*
X852500Y710500D03*
X842500Y719500D03*
X845500Y865000D03*
X852600Y868500D03*
X865000Y5000D03*
X873000Y68500D03*
X872000Y75500D03*
X870100Y237500D03*
X869544Y226000D03*
X860400Y231000D03*
X860555Y262500D03*
X865055D03*
X863820Y363880D03*
X868820D03*
X870500Y444000D03*
Y448000D03*
X871500Y484000D03*
X857500Y485500D03*
X862500Y621250D03*
X859500Y629500D03*
X872000Y636000D03*
X871000Y639500D03*
X870500Y665060D03*
X861250Y649250D03*
X867500Y655200D03*
X865500Y690500D03*
X860718Y683684D03*
X860500Y734000D03*
X870000Y980000D03*
X880000Y20000D03*
X877860Y316330D03*
X888750Y324660D03*
X884120Y351630D03*
X887950Y359730D03*
X874910Y360160D03*
X879510Y355410D03*
X887940Y380200D03*
X878000Y404500D03*
X877000Y409500D03*
X876000Y435500D03*
X886300Y443100D03*
X882700D03*
X885000Y438700D03*
X874450Y463500D03*
X877000Y479500D03*
X877500Y612500D03*
X876000Y631700D03*
X884200Y636500D03*
X878500Y695500D03*
X881000Y710000D03*
X895000Y5000D03*
X899000Y312500D03*
X898000Y316000D03*
X903480Y324230D03*
X904600Y406600D03*
X893500Y427000D03*
X893600Y443100D03*
X889900D03*
X903075Y472000D03*
X900000Y980000D03*
X910000Y20000D03*
X918420Y449130D03*
X907000Y465050D03*
X917000Y752500D03*
X925000Y5000D03*
X923000Y51500D03*
X936000Y373500D03*
X924465Y388465D03*
X934000Y448700D03*
X936030Y457540D03*
X937000Y489000D03*
X935400Y597300D03*
X955000Y5000D03*
X940000Y20000D03*
X939500Y352000D03*
X953500Y348927D03*
X944000Y434000D03*
X970000Y20000D03*
X958500Y187500D03*
X957990Y191064D03*
X962000Y251500D03*
X965500Y260500D03*
X963500Y256000D03*
X959500Y351688D03*
X965000Y364500D03*
X964000Y354000D03*
X968085Y452065D03*
X970382Y455872D03*
X961700Y477500D03*
X957500Y585500D03*
X961500D03*
X970750Y703000D03*
X985000Y5000D03*
X980078Y204578D03*
X980960Y195257D03*
X980490Y198827D03*
X982075Y439500D03*
X973015Y453416D03*
X977000Y547500D03*
X982500Y549500D03*
X978000Y554000D03*
X975000Y701000D03*
X1000000Y20000D03*
X989000Y66500D03*
X1003000Y59500D03*
X996500Y167000D03*
X988660Y190500D03*
X988900Y434800D03*
X992690Y466750D03*
X996910Y466560D03*
X998000Y461500D03*
X994500Y491000D03*
X1003422Y490578D03*
X992000Y505500D03*
X1002500Y520000D03*
X990500Y536500D03*
X994500Y543800D03*
X998500Y591500D03*
X989000Y659500D03*
Y757150D03*
X1001000Y771500D03*
X1015000Y5000D03*
X1012000Y43000D03*
X1016500Y87500D03*
X1020500Y124500D03*
Y142000D03*
X1017274Y219274D03*
X1014000Y487000D03*
X1007500Y487500D03*
Y507000D03*
X1008500Y533400D03*
X1016500Y519500D03*
X1008500Y543700D03*
X1013500Y559000D03*
X1016900Y561000D03*
X1017982Y585018D03*
X1007032Y879968D03*
X1011966Y893534D03*
X1007532Y902468D03*
X1020282Y911218D03*
X1010000Y980000D03*
X1033500Y118000D03*
X1025500Y129500D03*
X1033500Y124000D03*
X1037085Y137000D03*
X1023000Y155000D03*
X1034000D03*
X1028000Y164500D03*
X1023600Y173000D03*
X1036019Y203177D03*
X1036000Y199500D03*
X1035922Y209578D03*
X1031524Y218476D03*
X1033900Y225500D03*
X1027426Y346500D03*
X1023000Y347000D03*
X1031000Y348500D03*
Y355950D03*
X1030000Y403500D03*
X1036500Y581500D03*
X1035000Y594500D03*
X1021000Y588500D03*
X1025500Y657000D03*
X1023500Y727000D03*
X1037000Y734000D03*
X1024387Y738230D03*
X1035000Y800000D03*
Y804500D03*
X1021468Y866968D03*
X1032600Y867657D03*
X1031500Y884500D03*
X1035216Y884468D03*
X1035000Y888500D03*
Y880500D03*
X1032657Y901500D03*
X1027716Y914784D03*
X1032200Y921500D03*
X1045000Y5000D03*
X1045031Y138031D03*
X1041485Y137409D03*
X1039468Y155284D03*
X1048968D03*
X1053500Y153000D03*
X1044000D03*
X1048968Y150784D03*
X1039500Y151000D03*
X1048968Y159284D03*
X1039500Y159500D03*
X1053500Y157500D03*
X1044000D03*
X1040000Y182000D03*
X1052500Y187500D03*
X1045968Y185500D03*
X1037500Y225500D03*
X1040000Y579000D03*
X1038000Y604000D03*
X1053500Y620500D03*
X1046000Y644000D03*
X1038000Y635000D03*
X1042450Y648500D03*
X1045500Y639500D03*
X1050092Y655052D03*
X1042400Y684500D03*
X1052500Y693000D03*
X1052678Y704084D03*
X1038500Y706500D03*
X1052500Y709000D03*
Y700000D03*
X1041410Y708804D03*
Y704224D03*
X1052648Y712724D03*
X1040208Y745020D03*
X1052500Y773350D03*
X1044000Y763940D03*
X1039000Y884500D03*
X1042500Y930000D03*
X1040000Y980000D03*
X1060000Y20000D03*
X1064000Y80000D03*
X1055500D03*
X1059500D03*
X1068000D03*
Y76000D03*
X1064000D03*
X1059500D03*
X1055500D03*
X1068500Y118500D03*
X1069000Y124500D03*
X1057968Y155284D03*
X1058000Y150500D03*
Y159500D03*
X1060900Y173534D03*
X1060509Y177126D03*
X1066500Y185500D03*
X1056500Y194000D03*
X1060000Y207500D03*
X1061000Y211500D03*
X1055000Y219284D03*
X1060766Y395426D03*
X1061200Y399000D03*
X1068300Y488700D03*
X1059000Y558190D03*
X1058000Y599500D03*
X1056000Y604000D03*
X1058500Y660900D03*
X1054900D03*
X1070000Y650725D03*
X1058350Y681450D03*
X1068500Y677000D03*
X1054500Y697000D03*
X1068500Y687000D03*
X1066000Y717000D03*
X1059800Y719740D03*
X1054000Y735000D03*
X1056350Y748000D03*
X1063000Y780000D03*
X1075000Y5000D03*
X1071000Y71000D03*
X1077250Y102000D03*
X1077500Y97000D03*
Y107500D03*
X1072000Y136000D03*
X1086000Y126500D03*
X1074500Y185500D03*
X1080300Y191000D03*
X1084500Y202500D03*
X1072500Y208924D03*
X1078500Y464000D03*
X1080000Y520000D03*
X1081000Y548000D03*
Y544400D03*
X1084599Y544520D03*
X1086000Y556000D03*
X1071500Y589000D03*
X1074500Y627500D03*
X1073000Y637500D03*
X1085000Y661000D03*
X1074000Y677000D03*
X1073500Y672000D03*
X1074000Y683000D03*
X1074500Y694754D03*
X1074426Y687255D03*
X1074389Y691155D03*
X1074000Y699500D03*
X1074148Y711624D03*
X1074600Y707724D03*
X1074000Y703500D03*
X1073384Y722384D03*
X1073000Y730834D03*
Y726444D03*
X1074288Y715534D03*
X1084300Y741874D03*
X1077500Y745374D03*
X1072000Y743500D03*
X1071500Y739000D03*
X1077500Y759000D03*
X1084000Y748099D03*
X1070098Y764500D03*
X1083700Y835725D03*
X1085468Y895968D03*
X1077000Y943075D03*
X1083200Y956500D03*
X1070000Y980000D03*
X1090000Y20000D03*
X1088000Y85500D03*
X1098000Y126500D03*
X1093894D03*
X1090028D03*
X1092500Y461500D03*
X1098500Y465000D03*
X1089000Y508500D03*
X1100575Y559075D03*
X1098000Y562000D03*
X1091425Y551425D03*
X1093500Y640000D03*
X1094500Y657500D03*
X1091000Y692519D03*
X1090257Y724253D03*
X1087600Y727029D03*
X1094853Y726853D03*
X1098000Y775000D03*
X1093000Y791000D03*
X1097500Y784500D03*
X1095500Y812000D03*
X1098500Y823344D03*
X1097500Y849000D03*
X1092718Y859984D03*
X1089000Y867284D03*
X1099623Y869123D03*
X1093468Y896968D03*
X1097423Y906546D03*
X1093500Y905500D03*
X1100000Y980000D03*
X1105000Y5000D03*
Y15000D03*
Y75000D03*
Y105000D03*
Y135000D03*
X1110318Y275600D03*
X1111500Y517500D03*
X1107500Y580000D03*
X1114883Y591925D03*
X1106000Y609500D03*
Y605500D03*
X1111500Y718500D03*
X1107000Y763000D03*
Y757500D03*
X1110300Y790000D03*
X1111834Y813334D03*
X1113500Y824500D03*
X1111000Y836000D03*
X1107160Y843160D03*
X1118034Y847034D03*
X1113768D03*
X1116468Y870284D03*
Y874284D03*
Y865784D03*
X1112468Y870284D03*
X1114500Y886000D03*
X1103000Y888300D03*
X1118500Y886000D03*
X1123000Y250500D03*
X1120600Y282300D03*
X1128000Y288500D03*
X1132300Y288800D03*
X1130000Y361500D03*
X1124327Y465391D03*
X1123500Y521500D03*
X1128149Y525261D03*
X1130928Y527550D03*
X1132000Y562000D03*
X1125600Y570600D03*
X1135000Y597000D03*
X1132222Y593278D03*
X1119487Y588088D03*
X1122353Y590268D03*
X1125000Y603050D03*
X1134000Y613500D03*
X1126000Y618000D03*
Y627329D03*
X1131000Y631000D03*
X1121500Y621600D03*
X1130490Y627436D03*
X1125041Y631000D03*
X1120500Y729500D03*
X1124000Y729000D03*
X1128430Y749640D03*
X1132960Y752950D03*
X1126210Y752810D03*
X1126642Y785505D03*
X1123200Y783900D03*
X1130030Y820000D03*
X1121000Y823500D03*
X1135468Y854032D03*
X1120468Y870284D03*
X1131275Y867725D03*
X1130000Y980000D03*
X1146500Y267000D03*
X1146000Y258500D03*
X1151000Y264500D03*
X1146500Y275500D03*
X1145800Y282284D03*
X1136100Y288900D03*
X1136450Y294650D03*
X1150640Y359860D03*
X1146640D03*
X1142640D03*
X1151500Y449000D03*
Y522000D03*
X1143500Y542000D03*
X1147500D03*
X1136075Y559075D03*
X1145900Y579800D03*
X1136500Y592500D03*
X1139632Y594441D03*
X1140500Y589000D03*
X1141100Y585400D03*
X1147000Y619000D03*
X1147400Y729900D03*
X1166000Y232000D03*
X1162468Y257968D03*
X1153700Y267700D03*
X1168000Y302500D03*
X1166000Y290000D03*
X1156100Y316405D03*
X1168076Y310046D03*
X1152500Y311000D03*
X1158000Y309500D03*
X1152500Y318500D03*
X1160000D03*
X1156100Y312795D03*
X1165000Y308175D03*
Y304565D03*
X1167000Y321000D03*
Y326450D03*
X1161530Y360430D03*
X1157480Y361620D03*
X1157700Y368500D03*
X1160058Y364558D03*
X1155400Y371500D03*
X1164000Y397000D03*
X1168000Y390250D03*
X1166500Y415500D03*
X1155500Y450758D03*
Y446892D03*
X1161000Y541500D03*
X1154000Y589000D03*
X1155000Y594500D03*
X1165476Y613393D03*
X1152500Y608500D03*
X1165672Y609672D03*
X1164500Y628723D03*
X1159075Y630600D03*
X1154847Y630908D03*
X1156377Y627623D03*
X1160333Y753600D03*
X1153500Y784190D03*
X1164500Y857500D03*
X1162000Y960625D03*
X1155000Y980000D03*
X1171000Y232000D03*
X1181427Y251500D03*
X1180677Y256500D03*
X1173777Y290125D03*
X1169777D03*
X1177500Y290000D03*
X1174752Y320504D03*
X1173125Y323716D03*
X1169515D03*
X1175000Y327000D03*
X1184000Y351500D03*
X1174500Y366000D03*
X1182000Y357000D03*
X1174400Y356500D03*
X1178000D03*
X1175125Y370000D03*
X1176500Y383500D03*
X1174500Y404000D03*
X1182500Y407000D03*
X1173500Y422500D03*
Y554000D03*
X1179934Y567000D03*
X1181350Y595450D03*
X1169075Y613500D03*
X1183000Y628000D03*
X1177100Y624750D03*
X1178500Y653100D03*
X1184500Y749500D03*
Y772782D03*
X1173200Y789500D03*
X1184750Y781000D03*
X1177000Y860000D03*
X1169000Y856000D03*
X1181500Y949000D03*
X1186500Y232000D03*
X1188000Y248500D03*
X1196334Y290561D03*
X1185283Y290513D03*
X1192743Y289800D03*
X1188877D03*
X1199685Y344588D03*
X1196075D03*
X1198000Y348000D03*
X1192000Y344500D03*
X1197000Y372500D03*
X1187500Y411000D03*
X1197000Y409500D03*
X1189000Y421500D03*
X1195000Y428000D03*
X1197675Y533125D03*
X1191000Y528000D03*
X1189000Y533825D03*
X1194564Y530936D03*
X1185500Y548075D03*
X1200500Y547925D03*
X1186000Y615500D03*
X1196000Y605800D03*
X1184956Y619272D03*
X1191000Y663000D03*
X1193804Y657175D03*
X1191000Y667000D03*
X1197500Y665500D03*
X1199551Y683968D03*
X1195937Y683849D03*
X1189890Y684053D03*
X1192937Y683911D03*
X1196500Y745500D03*
Y736687D03*
X1192500Y745500D03*
X1199500Y743500D03*
X1192038Y761481D03*
X1188000Y762500D03*
X1188500Y773000D03*
X1184975Y767500D03*
X1194000Y764500D03*
X1190000Y767500D03*
X1198718Y800782D03*
X1196000Y847500D03*
X1188875Y856625D03*
X1196000Y874500D03*
X1185000Y980000D03*
X1211500Y5500D03*
Y35500D03*
Y65500D03*
Y85500D03*
Y107500D03*
Y137500D03*
X1208500Y202000D03*
X1209000Y212500D03*
X1208000Y231000D03*
X1207500Y239500D03*
X1201922Y248500D03*
X1202177Y260000D03*
X1208500Y283500D03*
X1208000Y271499D03*
Y297638D03*
Y309000D03*
X1206500Y330000D03*
X1208500Y321500D03*
X1203500Y345000D03*
X1208500Y346400D03*
Y359000D03*
X1210800Y379700D03*
X1208000Y371000D03*
X1216000Y390000D03*
X1209500Y404500D03*
X1216500Y439500D03*
X1212500Y436000D03*
X1209000Y438500D03*
X1217000Y452500D03*
X1210000Y507500D03*
X1209500Y514000D03*
X1213100D03*
X1214450Y509000D03*
X1206400Y536800D03*
X1210000D03*
X1201500Y535000D03*
X1209500Y561910D03*
X1205240Y568760D03*
X1215500Y605300D03*
X1207700Y605500D03*
X1208500Y623000D03*
X1204500Y659500D03*
X1203181Y683968D03*
X1206781Y684003D03*
X1213598Y699164D03*
X1216000Y702500D03*
X1210500Y733500D03*
X1206500Y757000D03*
X1213500Y756000D03*
X1201968Y757500D03*
X1212840Y781000D03*
X1202218Y811282D03*
X1211000Y847500D03*
X1204000Y862000D03*
X1217250Y862250D03*
X1208940Y874560D03*
X1211500Y882500D03*
X1215000Y980000D03*
X1227500Y500500D03*
Y504246D03*
X1220500Y513000D03*
X1229500Y533000D03*
X1231632Y537000D03*
X1221500Y539500D03*
X1233000Y554502D03*
X1219200Y564600D03*
X1221500Y633000D03*
X1231450Y677500D03*
X1225500Y714500D03*
X1229000Y716000D03*
Y726500D03*
Y719600D03*
Y740000D03*
X1230219Y747469D03*
X1232000Y738000D03*
X1234000Y747500D03*
X1224500Y757500D03*
X1228547Y772547D03*
Y778453D03*
X1231000Y768500D03*
X1221000Y764750D03*
X1233000Y782500D03*
X1223500Y798500D03*
X1223000Y826500D03*
X1230500Y841000D03*
X1218500Y834500D03*
X1229807Y847000D03*
X1235500Y5000D03*
X1239000Y190500D03*
X1239500Y204000D03*
X1240000Y209449D03*
X1239500Y214000D03*
X1239000Y251500D03*
X1241777Y265700D03*
X1241377Y274900D03*
X1238500Y290000D03*
X1239000Y302437D03*
X1238500Y316500D03*
X1250158Y326463D03*
X1238500Y325985D03*
X1239000Y338900D03*
Y352800D03*
X1239500Y366000D03*
X1234177Y379500D03*
X1243000Y431500D03*
X1250000Y422000D03*
X1234500Y439000D03*
X1248250Y439250D03*
X1243000Y446650D03*
X1250450Y462000D03*
X1242000Y459000D03*
X1247800Y472750D03*
X1246750Y476250D03*
X1249000Y509500D03*
X1249251Y528688D03*
X1235482Y546982D03*
X1240000Y546500D03*
Y542900D03*
X1240173Y550327D03*
X1250500Y567000D03*
X1241000Y631500D03*
X1237500Y675500D03*
X1235000Y682000D03*
X1244371Y733129D03*
X1236500Y737925D03*
X1243000Y743000D03*
X1241000Y734500D03*
X1240016Y761500D03*
X1238000Y764500D03*
X1249500Y765500D03*
X1248950Y769500D03*
X1248500Y775500D03*
X1248950Y782450D03*
X1238047Y791953D03*
X1240045Y788957D03*
X1241984Y796000D03*
X1243953Y789000D03*
X1240660Y829000D03*
X1245650Y821850D03*
X1235258Y820758D03*
X1245000Y980000D03*
X1257000Y33000D03*
X1256500Y166500D03*
X1261000D03*
X1265000Y169000D03*
Y174000D03*
X1258000Y205000D03*
X1265000Y211500D03*
X1261000Y207500D03*
Y211500D03*
X1260677Y237000D03*
X1264177Y233500D03*
X1256000Y252000D03*
X1262558Y254942D03*
X1261677Y241500D03*
Y245500D03*
X1251500Y266500D03*
X1264500Y260000D03*
X1254944Y268567D03*
X1263000Y278500D03*
X1250677Y287500D03*
Y283500D03*
X1251700Y274000D03*
X1254203Y282770D03*
X1254944Y272433D03*
X1260577Y299968D03*
Y296102D03*
X1261000Y292500D03*
X1261006Y303543D03*
X1252564Y290566D03*
X1253477Y312800D03*
X1253577Y308800D03*
X1253500Y316500D03*
Y305000D03*
X1257000Y311000D03*
X1253177Y320500D03*
Y324500D03*
X1265000Y426500D03*
X1259968Y444284D03*
X1260000Y448500D03*
X1264500Y446500D03*
X1260000Y440000D03*
X1264500Y442000D03*
X1257468Y478500D03*
X1253000Y511000D03*
X1251500Y531500D03*
X1260500Y546400D03*
X1263500Y550000D03*
X1258000Y555400D03*
X1255000Y609300D03*
X1266500Y617500D03*
X1265000Y647500D03*
X1257500Y635500D03*
X1265000Y661000D03*
Y657000D03*
X1265500Y652500D03*
X1257100Y664300D03*
X1263121Y678621D03*
X1259000Y678950D03*
X1262300Y670700D03*
X1266000Y665600D03*
X1262500Y699825D03*
X1253500Y778465D03*
X1257950Y809250D03*
X1264000Y853000D03*
X1268000Y5000D03*
X1279500Y150500D03*
X1276500Y234000D03*
X1267677Y232500D03*
X1280500Y338000D03*
Y404550D03*
X1280000Y420500D03*
X1278500Y448500D03*
Y444000D03*
X1274000Y447000D03*
X1269468Y444284D03*
Y448284D03*
X1278500Y439500D03*
X1269468Y439784D03*
X1274000Y442000D03*
X1272500Y466600D03*
X1270000Y477000D03*
X1271000Y573500D03*
Y568500D03*
X1282500Y598000D03*
X1274500Y606000D03*
X1278500Y603500D03*
X1271000Y617500D03*
X1279340Y618660D03*
X1282500Y645000D03*
X1272451Y642500D03*
X1272502Y638900D03*
X1281268Y661780D03*
X1268805Y655405D03*
X1282300Y678000D03*
X1282500Y669561D03*
X1273702Y667662D03*
X1275885Y670525D03*
X1267500Y675000D03*
Y684878D03*
X1281500Y713000D03*
X1279000Y746575D03*
X1267500Y779000D03*
Y783000D03*
X1269500Y835000D03*
X1275000Y980000D03*
X1290874Y34376D03*
X1299500Y236000D03*
X1295500Y291500D03*
X1292500Y402000D03*
X1289000Y415500D03*
X1285700Y529700D03*
X1293960Y528740D03*
X1294600Y524200D03*
X1291300Y540900D03*
X1297500Y562000D03*
X1286500Y569000D03*
X1294000Y587500D03*
X1288335Y594048D03*
X1287482Y590500D03*
X1293500Y593000D03*
X1285557Y585000D03*
X1289570Y597430D03*
X1284825Y621500D03*
X1294000Y628000D03*
X1299000Y641500D03*
X1296000Y638500D03*
X1290500Y635500D03*
X1286500Y652500D03*
X1297500Y665000D03*
X1291500Y666000D03*
X1289500Y669000D03*
X1284490Y710936D03*
X1296500Y830782D03*
X1298034Y907034D03*
X1307500Y5000D03*
X1306000Y43000D03*
X1309500Y51000D03*
X1304050Y296500D03*
X1307500Y320500D03*
X1308000Y311000D03*
X1312750Y314000D03*
X1306000Y329000D03*
Y334500D03*
Y338500D03*
X1311000Y435000D03*
Y463500D03*
X1302000Y475000D03*
X1304700Y536000D03*
X1302500Y559500D03*
X1307000Y573412D03*
X1307900Y577412D03*
X1306817Y592412D03*
X1306617Y587512D03*
X1308817Y595412D03*
X1310500Y625000D03*
X1312000Y645784D03*
X1311000Y651900D03*
X1310425Y660062D03*
X1311100Y656400D03*
X1304400Y661400D03*
X1311700Y681500D03*
X1312115Y672000D03*
X1311000Y677284D03*
X1311300Y687500D03*
X1313500Y710000D03*
X1305000Y739750D03*
X1308100Y748200D03*
X1306000Y782500D03*
X1314284D03*
X1304500Y838000D03*
X1300784Y838716D03*
X1312500Y838000D03*
X1305000Y850500D03*
X1303750Y862250D03*
X1312000Y850500D03*
X1307468Y884532D03*
X1314500Y921500D03*
X1300000Y980000D03*
X1331000Y120000D03*
X1322500Y299000D03*
X1324000Y290500D03*
X1322000Y318500D03*
X1322500Y337000D03*
X1317000Y336000D03*
X1330500Y441000D03*
X1332000Y459250D03*
X1323500Y452500D03*
X1326617Y594412D03*
X1325950Y599000D03*
X1329317Y626512D03*
X1323117Y626412D03*
X1328000Y649000D03*
X1328968Y679684D03*
X1329468Y666468D03*
X1323500Y702000D03*
X1322000Y705500D03*
X1318784Y793716D03*
X1325250Y834250D03*
X1316500Y839000D03*
X1317000Y850500D03*
X1318113Y846371D03*
X1321466Y907034D03*
X1330000Y980000D03*
X1337500Y5000D03*
X1339000Y54000D03*
X1347000Y48000D03*
X1342500Y51000D03*
X1333100Y58600D03*
X1347000Y88000D03*
X1347500Y116000D03*
X1343500Y112000D03*
X1336500Y270874D03*
X1339000Y274000D03*
X1339500Y305500D03*
X1341873Y344873D03*
X1344000Y434500D03*
X1340200D03*
X1335000Y443250D03*
X1340200Y438300D03*
X1343900Y438500D03*
X1343000Y466500D03*
X1334500Y557000D03*
X1335317Y575412D03*
X1344617Y588712D03*
Y593412D03*
X1342648Y612412D03*
X1347617Y610412D03*
X1346617Y626912D03*
X1342367Y627662D03*
X1334500Y636000D03*
X1333468Y680000D03*
X1334500Y669000D03*
X1352000Y85500D03*
X1349500Y112000D03*
X1350000Y276500D03*
X1354500Y276000D03*
X1350084Y296500D03*
X1358500Y288916D03*
X1353000Y390000D03*
Y402000D03*
X1362500Y459000D03*
X1353500Y466500D03*
X1351000Y455750D03*
X1355500Y556500D03*
X1360817Y557812D03*
X1356817Y579012D03*
X1364617Y592912D03*
X1349317Y593412D03*
X1360200Y614800D03*
X1353117Y610412D03*
X1353517Y627512D03*
X1363100Y627000D03*
X1349817Y628612D03*
X1357300Y617700D03*
X1360000Y980000D03*
X1369720Y106365D03*
X1379500Y274500D03*
X1381500Y292000D03*
X1376000D03*
X1379500Y314000D03*
X1375500Y328000D03*
X1370500Y356500D03*
X1368000Y450500D03*
X1374500Y462800D03*
X1369617Y557012D03*
X1367617Y570012D03*
X1394122Y5878D03*
X1390004Y106000D03*
Y122600D03*
X1384500Y274500D03*
Y331500D03*
G54D50*
X155600Y465300D03*
X177543Y537396D03*
X193800Y848000D03*
X200800Y431500D03*
X320793Y450373D03*
X321823Y483783D03*
X336729Y241500D03*
X386300Y947000D03*
X472855Y301500D03*
Y305500D03*
X580300Y66000D03*
Y62000D03*
X631800Y575000D03*
X677386Y107874D03*
X690548Y122500D03*
X694762Y455464D03*
X713300Y568000D03*
X719800Y864000D03*
X785300Y355500D03*
X775574Y475078D03*
X800574D03*
X822800Y368500D03*
X821300Y849500D03*
X852800Y385000D03*
X849800Y638500D03*
X941250Y448700D03*
X1020300Y277500D03*
Y281500D03*
X1011300Y480500D03*
X1015516Y898468D03*
X1033300Y137000D03*
X1050800Y930000D03*
X1077229Y73758D03*
X1096268Y863284D03*
X1105300Y776500D03*
Y772500D03*
X1143300Y862000D03*
X1210300Y432500D03*
X1205800Y753000D03*
X1202268Y807784D03*
Y804284D03*
X1253800Y699500D03*
X1275800Y564500D03*
X1308300Y855000D03*
Y858500D03*
X1316417Y603912D03*
X1340300Y452000D03*
X1357800D03*
G54D32*
X43804Y936020D03*
X100772Y771304D03*
X85304Y888020D03*
X101804Y936020D03*
X216500Y434800D03*
X266500Y214800D03*
X270500D03*
X310429Y267800D03*
X328500Y97800D03*
X315429Y267800D03*
X320429D03*
X321023Y552083D03*
X325023D03*
X337000Y97800D03*
X333500Y949900D03*
X361929Y274800D03*
X352929D03*
X370929D03*
X375000D03*
X378929D03*
X674122Y130232D03*
X675055Y266300D03*
X679055D03*
X706055D03*
X710055D03*
X731468Y783284D03*
X727468D03*
X729468Y814784D03*
X725968D03*
X746716Y126584D03*
X750216D03*
X756000Y583300D03*
X788500Y661800D03*
X787500Y778300D03*
X791500D03*
X826500Y407800D03*
X854820Y348180D03*
X858500Y436300D03*
X880820Y351680D03*
X994500Y540300D03*
X1008500D03*
X1024716Y862268D03*
X1023716Y911268D03*
X1065500Y67800D03*
X1099500Y259800D03*
Y756800D03*
X1096000Y819800D03*
X1099468Y888084D03*
X1103000Y756800D03*
X1134500Y830510D03*
X1121968Y850584D03*
X1137748Y757084D03*
X1135468Y882584D03*
X1179677Y231300D03*
X1183177D03*
X1199677Y233800D03*
X1195677D03*
X1196500Y761300D03*
X1188000Y757300D03*
X1273000Y709300D03*
X1300784Y834332D03*
X1324500Y309800D03*
X1327500Y436800D03*
X1346617Y623212D03*
X1350617Y624712D03*
X1364617Y623212D03*
G54D161*
X1279401Y38583D03*
X1268631D03*
G54D152*
X1159934Y573276D03*
Y589068D03*
X1179934Y573276D03*
Y589068D03*
G54D23*
X48820Y422933D03*
X67717D03*
X58268D03*
G54D170*
X1348595Y545800D03*
X1342639D03*
X1348595Y555024D03*
X1342639D03*
G54D134*
X787758Y445022D03*
X785790D03*
Y457134D03*
X787758D03*
X1342984Y430444D03*
X1341016D03*
Y442556D03*
X1342984D03*
G54D116*
X674931Y446821D03*
X672962D03*
X670993D03*
X669025D03*
X667056D03*
X665088D03*
X663119D03*
Y466107D03*
X665088D03*
X667056D03*
X669025D03*
X670993D03*
X672962D03*
X674931D03*
X682805Y446821D03*
X680836D03*
X678868D03*
X676899D03*
Y466107D03*
X678868D03*
X680836D03*
X682805D03*
X1050937Y145641D03*
X1048968D03*
X1046999D03*
X1045031D03*
X1043062D03*
X1041094D03*
X1039125D03*
Y164927D03*
X1041094D03*
X1043062D03*
X1045031D03*
X1046999D03*
X1048968D03*
X1050937D03*
X1058811Y145641D03*
X1056842D03*
X1054874D03*
X1052905D03*
Y164927D03*
X1054874D03*
X1056842D03*
X1058811D03*
X1265531Y434641D03*
X1263562D03*
X1261594D03*
X1259625D03*
Y453927D03*
X1261594D03*
X1263562D03*
X1265531D03*
X1279311Y434641D03*
X1277342D03*
X1275374D03*
X1273405D03*
X1271437D03*
X1269468D03*
X1267499D03*
Y453927D03*
X1269468D03*
X1271437D03*
X1273405D03*
X1275374D03*
X1277342D03*
X1279311D03*
G54D143*
X1035216Y874725D03*
X1032657D03*
X1030098D03*
Y894211D03*
X1032657D03*
X1035216D03*
X1040334Y874725D03*
X1037775D03*
Y894211D03*
X1040334D03*
G54D125*
X737200Y56165D03*
Y63840D03*
Y61280D03*
Y58720D03*
X747800Y56165D03*
Y58720D03*
Y61280D03*
Y63840D03*
G54D107*
X585315Y44134D03*
X654527D03*
G54D41*
X114174Y1007910D03*
X271653D03*
X723623D03*
G54D14*
G01X146364Y290190D02*
Y296000D01*
G01X516500Y556000D02*
X516682Y556182D01*
X587818D01*
X601000Y543000D01*
G01X961700Y477500D02*
X965600Y473600D01*
Y455790D01*
G01X963500Y536500D02*
Y488000D01*
G01X1195000Y422500D02*
X1190500Y427000D01*
Y456732D01*
X1173100Y474132D01*
Y499200D01*
X34500Y692000D03*
X56000Y7500D03*
X56804Y768220D03*
X57500Y993500D03*
X125000Y827500D03*
X314429Y294500D03*
X366555Y455500D03*
X462500Y86000D03*
X526055Y295500D03*
X1086000Y592000D03*
X1184000Y793500D03*
X1341800Y788600D03*
X1367500Y995000D03*
G54D180*
G01X47245Y393623D02*
Y388351D01*
G03X47483Y387776I813J0D01*
G01X44095Y393623D02*
Y388281D01*
G02X43883Y387769I-724J0D01*
G01X45670Y403503D02*
Y409059D01*
G03X45083Y410476I-2004J0D01*
G02X44620Y411594I1118J1118D01*
G01Y436049D01*
G02X69453Y460882I24833J0D01*
G01X110095D01*
G02X120701Y456489I0J-15000D01*
G01X298115Y279075D01*
G02X299579Y275540I-3536J-3535D01*
G01Y214131D01*
G03X300979Y210751I4781J0D01*
G01X334246Y177484D01*
G03X337829Y176000I3583J3583D01*
G01X338233D01*
G02X339440Y175500I0J-1707D01*
G01X42520Y403503D02*
Y409758D01*
G02X42983Y410876I1581J0D01*
G03X43270Y411569I-693J693D01*
G01Y436049D01*
G02X69453Y462232I26183J0D01*
G01X110096D01*
G02X121657Y457443I0J-16350D01*
G01X299069Y280031D01*
G02X300929Y275541I-4490J-4490D01*
G01Y214132D01*
G03X301934Y211706I3431J0D01*
G01X306650Y206990D01*
G03X307647Y206658I818J794D01*
G02X308644Y206326I179J-1126D01*
G01X309492Y205477D01*
G02X309825Y204480I-793J-819D01*
G03X310157Y203483I1126J-179D01*
G01X311005Y202635D01*
G03X312002Y202302I819J793D01*
G02X312999Y201970I179J-1126D01*
G01X313848Y201121D01*
G02X314180Y200124I-794J-818D01*
G03X314513Y199127I1126J-178D01*
G01X315361Y198279D01*
G03X316358Y197946I819J793D01*
G02X317355Y197614I179J-1126D01*
G01X318204Y196766D01*
G02X318536Y195769I-794J-818D01*
G03X318868Y194772I1126J-179D01*
G01X335201Y178439D01*
G03X337829Y177350I2629J2628D01*
G01X337871D01*
G03X339440Y178000I0J2219D01*
G01X62990Y393623D02*
Y388276D01*
G02X62783Y387776I-707J0D01*
G01X66140Y393623D02*
Y388704D01*
G03X66483Y387876I1171J0D01*
G01X56695Y393623D02*
Y388330D01*
G03X56883Y387876I642J0D01*
G01X53545Y393623D02*
Y388550D01*
G02X53183Y387676I-1236J0D01*
G01X51970Y403503D02*
Y409238D01*
G02X52483Y410476I1751J0D01*
G03X52865Y411398I-922J922D01*
G01Y413083D01*
G03X52870Y413204I-1511J123D01*
G01Y436093D01*
G02X72009Y455232I19139J0D01*
G01X106496D01*
G02X118057Y450443I0J-16350D01*
G01X291269Y277231D01*
G02X293129Y272741I-4490J-4490D01*
G01Y232473D01*
G03X293599Y231533I1140J-18D01*
G02X294069Y230593I-670J-922D01*
G01Y229393D01*
G02X293599Y228453I-1140J-18D01*
G03X293129Y227513I670J-922D01*
G01Y226313D01*
G03Y226251I1140J-31D01*
G03X293599Y225373I1139J45D01*
G02X294069Y224433I-670J-922D01*
G01Y223233D01*
G02X293599Y222293I-1140J-18D01*
G03X293129Y221353I670J-922D01*
G01Y211800D01*
G03X293832Y210103I2400J0D01*
G01X332175Y171760D01*
G03X334129Y170950I1955J1954D01*
G01X338112D01*
G03X339440Y171500I0J1878D01*
G01X61415Y403503D02*
Y408763D01*
G02X62069Y410342I2233J0D01*
G03X62315Y411254I-1564J911D01*
G01Y429930D01*
G02X80617Y448232I18302J0D01*
G01X103496D01*
G02X115057Y443443I0J-16350D01*
G01X283209Y275291D01*
G02X285069Y270801I-4490J-4490D01*
G01Y220023D01*
G03X285539Y219083I1140J-18D01*
G02X286009Y218143I-670J-922D01*
G01Y216943D01*
G02X285539Y216003I-1140J-18D01*
G03X285069Y215063I670J-922D01*
G01Y210859D01*
G03X286158Y208230I3718J0D01*
G01X329458Y164930D01*
G03X331220Y164200I1762J1762D01*
G03X332242Y164624I-1J1446D01*
G01X332289Y164670D01*
G02X333229Y165140I922J-670D01*
G01X334429D01*
G02X335369Y164670I18J-1140D01*
G03X336309Y164200I922J670D01*
G01X337509D01*
G03X339440Y165000I0J2731D01*
G01X64565Y403503D02*
Y408929D01*
G03X64088Y410081I-1629J0D01*
G02X63665Y411102I1021J1021D01*
G01Y429930D01*
G02X80617Y446882I16952J0D01*
G01X103495D01*
G02X114101Y442489I0J-15000D01*
G01X282255Y274335D01*
G02X283719Y270800I-3536J-3535D01*
G01Y210858D01*
G03X285203Y207275I5068J0D01*
G01X328503Y163975D01*
G03X331219Y162850I2716J2717D01*
G01X338595D01*
G02X339440Y162500I0J-1195D01*
G01X55120Y403503D02*
Y409121D01*
G03X54723Y410079I-1355J0D01*
G02X54220Y411618I2102J1539D01*
G01Y436093D01*
G02X72009Y453882I17789J0D01*
G01X106495D01*
G02X117101Y449489I0J-15000D01*
G01X290315Y276275D01*
G02X291779Y272740I-3536J-3535D01*
G01Y211799D01*
G03X292877Y209148I3750J0D01*
G01X331220Y170805D01*
G03X334129Y169600I2909J2909D01*
G01X337991D01*
G02X339440Y169000I0J-2049D01*
G01X72440Y393623D02*
Y389321D01*
G02X71883Y387976I-1902J0D01*
G01X75590Y393623D02*
Y389166D01*
G03X76083Y387976I1683J0D01*
G01X70865Y403503D02*
Y410025D01*
G02X71383Y411276I1769J0D01*
G03X71765Y412198I-922J922D01*
G01Y428497D01*
G02X84500Y441232I12735J0D01*
G01X99996D01*
G02X111557Y436443I0J-16350D01*
G01X276459Y271541D01*
G02X278319Y267051I-4490J-4490D01*
G01Y205385D01*
G03X278510Y204925I651J1D01*
G01X308858Y174577D01*
G03X309855Y174245I818J794D01*
G02X310852Y173913I179J-1126D01*
G01X311700Y173064D01*
G02X312033Y172067I-793J-819D01*
G03X312365Y171070I1126J-179D01*
G01X325132Y158303D01*
G03X325864Y158000I732J732D01*
G01X328158D01*
G03X329098Y158470I18J1140D01*
G02X330038Y158940I922J-670D01*
G01X331238D01*
G02X332178Y158470I18J-1140D01*
G03X333118Y158000I922J670D01*
G01X338233D01*
G03X339440Y158500I0J1707D01*
G01X74015Y403503D02*
Y409074D01*
G03X73683Y409876I-1134J0D01*
G02X73115Y411247I1371J1371D01*
G01Y428497D01*
G02X84500Y439882I11385J0D01*
G01X99995D01*
G02X110601Y435489I0J-15000D01*
G01X275505Y270585D01*
G02X276969Y267050I-3536J-3535D01*
G01Y205385D01*
G03X277555Y203970I2001J0D01*
G01X324177Y157348D01*
G03X325864Y156650I1686J1687D01*
G01X337871D01*
G02X339440Y156000I0J-2219D01*
G01X127301Y354709D02*
X128572Y353438D01*
G02X128874Y352709I-729J-729D01*
G01Y348209D01*
G03X138002Y326171I31166J-1D01*
G01X141419Y322754D01*
X146297Y317875D01*
G03X152375Y315359I6076J6077D01*
G01X154476D01*
X155874Y313961D01*
G01X131147Y354709D02*
X130986Y354547D01*
G03X130224Y352709I1838J-1839D01*
G01Y348209D01*
G03X138957Y327126I29816J0D01*
G01X142374Y323709D01*
X147252Y318830D01*
G03X152374Y316709I5121J5122D01*
G01X154374D01*
G03X155061Y316993I1J971D01*
G01X155874Y317807D01*
G01X143147Y354709D02*
X142529Y354092D01*
G03X141874Y352509I1583J-1582D01*
G01Y342280D01*
G03X146874Y330209I17071J0D01*
G01X149960Y327123D01*
G03X153374Y325709I3414J3414D01*
G01X154626D01*
X155874Y326957D01*
G01X139301Y354709D02*
X139833Y354177D01*
G02X140524Y352509I-1668J-1668D01*
G01Y342279D01*
G03X145919Y329254I18421J0D01*
G01X149005Y326168D01*
G03X153375Y324359I4368J4369D01*
G01X154626D01*
X155874Y323111D01*
G01X166141Y303465D02*
Y299415D01*
G03X166541Y299015I400J0D01*
G01X166641D01*
G02X167041Y298615I0J-400D01*
G01Y295723D01*
G02X166924Y295440I-401J0D01*
G01X165793Y294309D01*
G01X164567Y313347D02*
Y317397D01*
G02X164967Y317797I400J0D01*
G01X165066D01*
G03X165466Y318197I0J400D01*
G01Y326709D01*
G03X164992Y327855I-1620J1D01*
G01X164147Y328699D01*
G01X155147Y354709D02*
X154663D01*
G03X153999Y354434I0J-939D01*
G01X153882Y354317D01*
G03X153724Y353936I380J-381D01*
G01Y346709D01*
G03X167374Y333059I13650J0D01*
G01X189874D01*
G03X192865Y334298I0J4230D01*
G01X192874Y334307D01*
G01Y330461D02*
X192865Y330470D01*
G03X189874Y331709I-2991J-2991D01*
G01X167374D01*
G02X152374Y346709I0J15000D01*
G01Y352809D01*
G03X151789Y354221I-1997J0D01*
G01X151301Y354709D01*
G01X162801D02*
X163749Y353761D01*
G02X164049Y353037I-724J-724D01*
G01Y351709D01*
G03X172899Y342859I8850J0D01*
G01X189874D01*
G02X192865Y341620I0J-4230D01*
G01X192874Y341611D01*
G01X166647Y354709D02*
X166423D01*
G03X165699Y354409I0J-1024D01*
G03X165399Y353685I724J-724D01*
G01Y351709D01*
G03X172899Y344209I7500J0D01*
G01X189874D01*
G03X192865Y345448I0J4230D01*
G01X192874Y345457D01*
G01X169291Y303465D02*
Y299415D01*
G02X168891Y299015I-400J0D01*
G01X168791D01*
G03X168391Y298615I0J-400D01*
G01Y295723D01*
G03X168508Y295440I401J0D01*
G01X169639Y294309D01*
G01X178740Y303465D02*
Y299415D01*
G02X178340Y299015I-400J0D01*
G01X178240D01*
G03X177840Y298615I0J-400D01*
G01Y296323D01*
G03X177957Y296040I401J0D01*
G01X179088Y294909D01*
G01X175590Y303465D02*
Y299415D01*
G03X175990Y299015I400J0D01*
G01X176090D01*
G02X176490Y298615I0J-400D01*
G01Y296323D01*
G02X176373Y296040I-401J0D01*
G01X175242Y294909D01*
G01X167716Y313347D02*
Y317397D01*
G03X167316Y317797I-400J0D01*
G01X167216D01*
G02X166816Y318197I0J400D01*
G01Y326709D01*
G02X167391Y328097I1963J0D01*
G01X167993Y328699D01*
G01X177165Y313347D02*
Y317397D01*
G03X176765Y317797I-400J0D01*
G01X176665D01*
G02X176265Y318197I0J400D01*
G01Y320209D01*
G02X177249Y322583I3358J-1D01*
G03X178374Y325299I-2716J2716D01*
G01Y326709D01*
G02X178934Y328061I1912J0D01*
G01X179622Y328749D01*
G01X174015Y313347D02*
Y317397D01*
G02X174415Y317797I400J0D01*
G01X174515D01*
G03X174915Y318197I0J400D01*
G01Y320210D01*
G02X176294Y323538I4708J-1D01*
G03X177024Y325298I-1761J1762D01*
G01Y326709D01*
G03X176464Y328061I-1912J0D01*
G01X175776Y328749D01*
G01X203937Y303465D02*
Y299415D01*
G02X203537Y299015I-400J0D01*
G01X203437D01*
G03X203037Y298615I0J-400D01*
G01Y296323D01*
G03X203154Y296040I401J0D01*
G01X204285Y294909D01*
G01X213385Y303465D02*
Y299415D01*
G02X212985Y299015I-400J0D01*
G01X212885D01*
G03X212485Y298615I0J-400D01*
G01Y296323D01*
G03X212602Y296040I401J0D01*
G01X213733Y294909D01*
G01X200787Y303465D02*
Y299415D01*
G03X201187Y299015I400J0D01*
G01X201287D01*
G02X201687Y298615I0J-400D01*
G01Y296323D01*
G02X201570Y296040I-401J0D01*
G01X200439Y294909D01*
G01X210236Y303465D02*
Y299415D01*
G03X210636Y299015I400J0D01*
G01X210735D01*
G02X211135Y298615I0J-400D01*
G01Y296323D01*
G02X211018Y296040I-401J0D01*
G01X209887Y294909D01*
G01X208661Y313347D02*
Y317397D01*
G02X209061Y317797I400J0D01*
G01X209161D01*
G03X209561Y318197I0J400D01*
G01Y321908D01*
G03X209444Y322191I-401J0D01*
G01X208338Y323297D01*
G01X202362Y313347D02*
Y317397D01*
G03X201962Y317797I-400J0D01*
G01X201862D01*
G02X201462Y318197I0J400D01*
G01Y321883D01*
G02X201579Y322166I401J0D01*
G01X202710Y323297D01*
G01X211811Y313347D02*
Y317397D01*
G03X211411Y317797I-400J0D01*
G01X211311D01*
G02X210911Y318197I0J400D01*
G01Y321908D01*
G02X211028Y322191I401J0D01*
G01X212134Y323297D01*
G01X199212Y313347D02*
Y317397D01*
G02X199612Y317797I400J0D01*
G01X199712D01*
G03X200112Y318197I0J400D01*
G01Y321883D01*
G03X199995Y322166I-401J0D01*
G01X198864Y323297D01*
G01X279528Y1008860D02*
Y1001110D01*
G03X279928Y1000710I400J0D01*
G01X280421D01*
G02X280821Y1000310I0J-400D01*
G01Y971872D01*
G03X283268Y965963I8356J-1D01*
G01X285435Y963796D01*
G02X289410Y954200I-9595J-9596D01*
G01Y761421D01*
G03X293441Y751689I13764J0D01*
G01X398925Y646205D01*
G02X401130Y640882I-5323J-5323D01*
G01Y452488D01*
G02X400555Y451100I-1963J0D01*
G01X283463Y1008860D02*
Y1001110D01*
G02X283063Y1000710I-400J0D01*
G01X282571D01*
G03X282171Y1000310I0J-400D01*
G01Y971872D01*
G03X284223Y966918I7006J0D01*
G01X286390Y964751D01*
G02X290760Y954201I-10550J-10550D01*
G01Y761422D01*
G03X294396Y752644I12414J0D01*
G01X324516Y722524D01*
G03X325513Y722192I818J794D01*
G02X326510Y721860I179J-1126D01*
G01X327358Y721011D01*
G02X327691Y720014I-793J-819D01*
G03X328023Y719017I1126J-179D01*
G01X328872Y718168D01*
G03X329869Y717836I818J794D01*
G02X330866Y717504I179J-1126D01*
G01X331714Y716655D01*
G02X332046Y715658I-794J-818D01*
G03X332379Y714661I1126J-178D01*
G01X355100Y691940D01*
G03X356097Y691608I818J794D01*
G02X357094Y691275I178J-1126D01*
G01X357942Y690427D01*
G02X358275Y689430I-793J-819D01*
G03X358607Y688433I1126J-179D01*
G01X359456Y687584D01*
G03X360453Y687252I818J794D01*
G02X361450Y686920I179J-1126D01*
G01X362298Y686071D01*
G02X362631Y685074I-793J-819D01*
G03X362963Y684077I1126J-179D01*
G01X379906Y667134D01*
G03X380903Y666802I818J794D01*
G02X381900Y666470I179J-1126D01*
G01X382748Y665621D01*
G02X383081Y664624I-793J-819D01*
G03X383413Y663627I1126J-179D01*
G01X384261Y662779D01*
G03X385259Y662446I819J793D01*
G02X386256Y662114I179J-1126D01*
G01X387104Y661265D01*
G02X387436Y660268I-794J-818D01*
G03X387769Y659271I1126J-178D01*
G01X388617Y658423D01*
G03X389614Y658090I819J793D01*
G02X390611Y657758I179J-1126D01*
G01X391460Y656910D01*
G02X391792Y655913I-794J-818D01*
G03X392125Y654915I1126J-179D01*
G01X399880Y647160D01*
G02X402480Y640883I-6278J-6277D01*
G01Y452870D01*
G03X403055Y451100I3012J0D01*
G01X295273Y1008860D02*
Y1002714D01*
G03X295986Y1000993I2434J0D01*
G02X296728Y999200I-1793J-1792D01*
G01Y763527D01*
G03X299507Y756818I9488J0D01*
G01X406085Y650240D01*
G02X408130Y645303I-4937J-4937D01*
G01Y452307D01*
G02X407843Y451612I-982J-1D01*
G01X407635Y451405D01*
G03X407555Y451212I193J-193D01*
G01Y451100D01*
G01X299213Y1008860D02*
Y1002337D01*
G02X298646Y1000968I-1936J0D01*
G03X298078Y999597I1371J-1371D01*
G01Y763528D01*
G03X300462Y757773I8138J0D01*
G01X310926Y747309D01*
G03X311923Y746976I819J793D01*
G02X312920Y746644I179J-1126D01*
G01X313769Y745795D01*
G02X314101Y744798I-794J-818D01*
G03X314434Y743801I1126J-178D01*
G01X315282Y742953D01*
G03X316279Y742621I818J794D01*
G02X317276Y742288I178J-1126D01*
G01X318125Y741440D01*
G02X318457Y740443I-794J-818D01*
G03X318789Y739446I1126J-179D01*
G01X319638Y738597D01*
G03X320635Y738265I818J794D01*
G02X321632Y737932I178J-1126D01*
G01X322480Y737084D01*
G02X322813Y736087I-793J-819D01*
G03X323145Y735090I1126J-179D01*
G01X352203Y706032D01*
G03X353200Y705699I819J793D01*
G02X354197Y705367I179J-1126D01*
G01X355046Y704518D01*
G02X355378Y703521I-794J-818D01*
G03X355711Y702524I1126J-178D01*
G01X356559Y701676D01*
G03X357556Y701344I818J794D01*
G02X358553Y701011I178J-1126D01*
G01X359402Y700163D01*
G02X359734Y699166I-794J-818D01*
G03X360066Y698169I1126J-179D01*
G01X360915Y697320D01*
G03X361912Y696988I818J794D01*
G02X362909Y696655I178J-1126D01*
G01X363757Y695807D01*
G02X364090Y694810I-793J-819D01*
G03X364422Y693813I1126J-179D01*
G01X378630Y679605D01*
G03X379627Y679273I818J794D01*
G02X380624Y678941I179J-1126D01*
G01X381472Y678092D01*
G02X381805Y677095I-793J-819D01*
G03X382137Y676098I1126J-179D01*
G01X407040Y651195D01*
G02X409480Y645304I-5892J-5891D01*
G01Y452489D01*
G03X409967Y451313I1663J0D01*
G02X410055Y451100I-214J-213D01*
G01X311023Y1008860D02*
Y1003947D01*
G03X311213Y1002990I2500J-1D01*
G01X312138Y1000759D01*
G02X312328Y999803I-2310J-956D01*
G01Y993631D01*
X312329D01*
Y993208D01*
G02X310292Y988291I-6953J0D01*
G01X306002Y984001D01*
G03X304000Y979166I4835J-4834D01*
G01Y766995D01*
G03X306565Y760801I8759J-1D01*
G01X413619Y653747D01*
G02X415130Y650099I-3648J-3648D01*
G01Y452982D01*
G02X414843Y452288I-983J0D01*
G03X414555Y451593I695J-695D01*
G01Y451100D01*
G01X314958Y1008860D02*
Y1002667D01*
G02X314444Y1001426I-1755J0D01*
G03X313678Y999577I1849J-1849D01*
G01Y994500D01*
X313679D01*
Y993207D01*
G02X311247Y987336I-8303J0D01*
G01X306957Y983046D01*
G03X305350Y979166I3880J-3880D01*
G01Y766995D01*
G03X307520Y761756I7409J0D01*
G01X322246Y747030D01*
G03X323243Y746698I818J794D01*
G02X324240Y746366I179J-1126D01*
G01X325088Y745517D01*
G02X325421Y744520I-793J-819D01*
G03X325753Y743523I1126J-179D01*
G01X326602Y742674D01*
G03X327599Y742342I818J794D01*
G02X328596Y742010I179J-1126D01*
G01X329444Y741161D01*
G02X329776Y740164I-794J-818D01*
G03X330109Y739167I1126J-178D01*
G01X330957Y738319D01*
G03X331954Y737986I819J793D01*
G02X332951Y737654I179J-1126D01*
G01X333800Y736806D01*
G02X334132Y735808I-794J-818D01*
G03X334465Y734811I1126J-178D01*
G01X359634Y709642D01*
G03X360631Y709310I818J794D01*
G02X361628Y708978I179J-1126D01*
G01X362476Y708129D01*
G02X362809Y707132I-793J-819D01*
G03X363141Y706135I1126J-179D01*
G01X363990Y705286D01*
G03X364987Y704954I818J794D01*
G02X365984Y704622I179J-1126D01*
G01X366832Y703773D01*
G02X367164Y702776I-794J-818D01*
G03X367497Y701779I1126J-178D01*
G01X368345Y700931D01*
G03X369342Y700598I819J793D01*
G02X370339Y700266I179J-1126D01*
G01X371188Y699417D01*
G02X371520Y698420I-794J-818D01*
G03X371853Y697423I1126J-178D01*
G01X386580Y682696D01*
G03X387577Y682364I818J794D01*
G02X388574Y682031I178J-1126D01*
G01X389423Y681183D01*
G02X389755Y680186I-794J-818D01*
G03X390087Y679189I1126J-179D01*
G01X414574Y654702D01*
G02X416480Y650099I-4603J-4602D01*
G01Y452681D01*
G03X416767Y451988I980J0D01*
G02X417055Y451293I-695J-695D01*
G01Y451100D01*
G01X330708Y1008860D02*
Y1001110D01*
G02X330308Y1000710I-400J0D01*
G01X329816D01*
G03X329416Y1000310I0J-400D01*
G01Y994314D01*
G02X327784Y990374I-5572J0D01*
G01X314660Y977250D01*
G03X312350Y971673I5577J-5577D01*
G01Y770195D01*
G03X313768Y766772I4841J0D01*
G01X318886Y761654D01*
G03X319883Y761322I818J794D01*
G02X320880Y760989I178J-1126D01*
G01X321729Y760141D01*
G02X322061Y759144I-794J-818D01*
G03X322393Y758147I1126J-179D01*
G01X323242Y757298D01*
G03X324239Y756966I818J794D01*
G02X325236Y756633I178J-1126D01*
G01X326084Y755785D01*
G02X326417Y754788I-793J-819D01*
G03X326749Y753791I1126J-179D01*
G01X327598Y752942D01*
G03X328595Y752610I818J794D01*
G02X329592Y752278I179J-1126D01*
G01X330440Y751429D01*
G02X330773Y750432I-793J-819D01*
G03X331105Y749435I1126J-179D01*
G01X365595Y714945D01*
G03X366592Y714613I818J794D01*
G02X367589Y714281I179J-1126D01*
G01X368437Y713432D01*
G02X368770Y712435I-793J-819D01*
G03X369102Y711438I1126J-179D01*
G01X369951Y710589D01*
G03X370948Y710257I818J794D01*
G02X371945Y709925I179J-1126D01*
G01X372793Y709076D01*
G02X373125Y708079I-794J-818D01*
G03X373458Y707082I1126J-178D01*
G01X374306Y706234D01*
G03X375303Y705901I819J793D01*
G02X376300Y705569I179J-1126D01*
G01X377149Y704720D01*
G02X377481Y703723I-794J-818D01*
G03X377814Y702726I1126J-178D01*
G01X388394Y692146D01*
G03X389391Y691813I819J793D01*
G02X390388Y691481I179J-1126D01*
G01X391237Y690633D01*
G02X391569Y689636I-794J-818D01*
G03X391901Y688639I1126J-179D01*
G01X420363Y660177D01*
G02X423480Y652652I-7526J-7526D01*
G01Y452606D01*
G03X423766Y451913I983J0D01*
G01X423767Y451912D01*
G02X424055Y451218I-692J-694D01*
G01Y451100D01*
G01X326773Y1008860D02*
Y1001110D01*
G03X327173Y1000710I400J0D01*
G01X327666D01*
G02X328066Y1000310I0J-400D01*
G01Y994314D01*
G02X326829Y991329I-4222J1D01*
G01X313705Y978205D01*
G03X311000Y971673I6532J-6531D01*
G01Y770194D01*
G03X312813Y765817I6191J0D01*
G01X419408Y659222D01*
G02X422130Y652651I-6571J-6571D01*
G01Y452882D01*
G02X421843Y452188I-983J0D01*
G01X421838Y452183D01*
G03X421555Y451500I683J-683D01*
G01Y451100D01*
G01X339440Y136500D02*
X338524D01*
G02X337897Y136760I0J886D01*
G01X337842Y136815D01*
G03X337215Y137075I-627J-626D01*
G01X328986D01*
G03X327100Y136294I0J-2667D01*
G01X339440Y139000D02*
X338524D01*
G03X337897Y138740I0J-886D01*
G01X337842Y138685D01*
G02X337215Y138425I-627J626D01*
G01X328759D01*
G02X328453Y138486I0J800D01*
G01X327594Y138841D01*
G02X327100Y139581I306J739D01*
G01Y139857D01*
G01X339440Y145500D02*
X338323D01*
G03X338040Y145383I0J-401D01*
G01X337699Y145042D01*
G02X337416Y144925I-283J284D01*
G01X324226D01*
G02X323944Y145042I1J400D01*
G01X323451Y145533D01*
G03X323169Y145650I-283J-283D01*
G01X321214D01*
G02X320931Y145767I0J401D01*
G01X319800Y146898D01*
G01X339440Y143000D02*
X338323D01*
G02X338040Y143117I0J401D01*
G01X337699Y143458D01*
G03X337416Y143575I-283J-284D01*
G01X324013D01*
G02X323138Y143938I0J1237D01*
G01X322775Y144300D01*
X321214D01*
G03X320931Y144183I0J-401D01*
G01X319800Y143052D01*
G01X346458Y1008860D02*
Y1001110D01*
G02X346058Y1000710I-400J0D01*
G01X345563D01*
G03X345163Y1000310I0J-400D01*
G01Y994068D01*
G02X343211Y989355I-6665J0D01*
G01X321963Y968107D01*
G03X319350Y961799I6308J-6308D01*
G01Y777215D01*
G03X322738Y769037I11566J1D01*
G01X322995Y768779D01*
X334589Y757185D01*
G03X335586Y756852I819J793D01*
G02X336583Y756520I179J-1126D01*
G01X337432Y755671D01*
G02X337764Y754674I-794J-818D01*
G03X338097Y753677I1126J-178D01*
G01X338945Y752829D01*
G03X339942Y752496I819J793D01*
G02X340939Y752164I179J-1126D01*
G01X341788Y751316D01*
G02X342120Y750319I-794J-818D01*
G03X342452Y749322I1126J-179D01*
G01X356595Y735179D01*
G03X357592Y734847I818J794D01*
G02X358589Y734515I179J-1126D01*
G01X359437Y733666D01*
G02X359770Y732669I-793J-819D01*
G03X360102Y731672I1126J-179D01*
G01X360950Y730824D01*
G03X361947Y730491I819J793D01*
G02X362944Y730159I179J-1126D01*
G01X363793Y729310D01*
G02X364125Y728313I-794J-818D01*
G03X364458Y727316I1126J-178D01*
G01X365306Y726468D01*
G03X366303Y726136I818J794D01*
G02X367300Y725803I178J-1126D01*
G01X368149Y724955D01*
G02X368481Y723958I-794J-818D01*
G03X368813Y722961I1126J-179D01*
G01X382956Y708818D01*
G03X383953Y708486I818J794D01*
G02X384950Y708154I179J-1126D01*
G01X385798Y707305D01*
G02X386130Y706308I-794J-818D01*
G03X386463Y705311I1126J-178D01*
G01X387311Y704463D01*
G03X388308Y704130I819J793D01*
G02X389305Y703798I179J-1126D01*
G01X390154Y702949D01*
G02X390486Y701952I-794J-818D01*
G03X390819Y700955I1126J-178D01*
G01X391667Y700107D01*
G03X392664Y699775I818J794D01*
G02X393661Y699442I178J-1126D01*
G01X394510Y698594D01*
G02X394842Y697597I-794J-818D01*
G03X395174Y696600I1126J-179D01*
G01X427976Y663798D01*
G02X430480Y657751I-6047J-6046D01*
G01Y452606D01*
G03X430766Y451913I983J0D01*
G01X430767Y451912D01*
G02X431055Y451218I-692J-694D01*
G01Y451100D01*
G01X342518Y1008860D02*
Y1001110D01*
G03X342918Y1000710I400J0D01*
G01X343413D01*
G02X343813Y1000310I0J-400D01*
G01Y994067D01*
X343812Y994068D01*
G02X342256Y990310I-5315J-1D01*
G01X321008Y969062D01*
G03X318000Y961800I7263J-7262D01*
G01Y777214D01*
G03X321782Y768083I12916J1D01*
G01X322038Y767826D01*
X427021Y662843D01*
G02X429130Y657751I-5092J-5092D01*
G01Y452707D01*
G02X428843Y452012I-982J-1D01*
G01X428777Y451946D01*
G03X428555Y451412I531J-534D01*
G01Y451100D01*
G01X393703Y1008860D02*
Y1001110D01*
G03X394103Y1000710I400J0D01*
G01X394596D01*
G02X394996Y1000310I0J-400D01*
G01Y989518D01*
G02X392044Y982392I-10077J0D01*
G01X388142Y978490D01*
G02X385816Y977527I-2325J2326D01*
G03X379993Y975115I0J-8236D01*
G01X373529Y968651D01*
G02X366673Y965811I-6856J6856D01*
G01X330941D01*
G03X327419Y964352I0J-4981D01*
G03X325000Y958512I5840J-5840D01*
G01Y780578D01*
G03X328417Y772327I11668J-1D01*
G01X434717Y666027D01*
G02X436130Y662616I-3411J-3411D01*
G01Y452482D01*
G02X435843Y451788I-983J0D01*
G01X435696Y451641D01*
G03X435555Y451300I342J-341D01*
G01Y451100D01*
G01X397638Y1008860D02*
Y1001110D01*
G02X397238Y1000710I-400J0D01*
G01X396746D01*
G03X396346Y1000310I0J-400D01*
G01Y989517D01*
G02X392999Y981437I-11427J0D01*
G01X389097Y977535D01*
G02X385816Y976176I-3281J3281D01*
G03X380948Y974160I0J-6885D01*
G01X374484Y967696D01*
G02X366674Y964461I-7810J7811D01*
G01X330942D01*
G03X328374Y963397I0J-3631D01*
G03X326350Y958513I4885J-4886D01*
G01Y780578D01*
G03X329372Y773282I10318J0D01*
G01X358005Y744649D01*
G03X359002Y744317I818J794D01*
G02X359999Y743984I178J-1126D01*
G01X360848Y743136D01*
G02X361180Y742139I-794J-818D01*
G03X361512Y741142I1126J-179D01*
G01X362361Y740293D01*
G03X363358Y739961I818J794D01*
G02X364355Y739628I178J-1126D01*
G01X365203Y738780D01*
G02X365536Y737783I-793J-819D01*
G03X365868Y736786I1126J-179D01*
G01X366717Y735937D01*
G03X367714Y735605I818J794D01*
G02X368711Y735273I179J-1126D01*
G01X369559Y734424D01*
G02X369892Y733427I-793J-819D01*
G03X370224Y732430I1126J-179D01*
G01X384366Y718288D01*
G03X385363Y717956I818J794D01*
G02X386360Y717623I178J-1126D01*
G01X387209Y716775D01*
G02X387541Y715778I-794J-818D01*
G03X387873Y714781I1126J-179D01*
G01X388722Y713932D01*
G03X389719Y713600I818J794D01*
G02X390716Y713268I179J-1126D01*
G01X391564Y712419D01*
G02X391897Y711422I-793J-819D01*
G03X392229Y710425I1126J-179D01*
G01X393078Y709576D01*
G03X394075Y709244I818J794D01*
G02X395072Y708912I179J-1126D01*
G01X395920Y708063D01*
G02X396252Y707066I-794J-818D01*
G03X396585Y706069I1126J-178D01*
G01X435672Y666982D01*
G02X437480Y662617I-4366J-4365D01*
G01Y452506D01*
G03X437766Y451813I983J0D01*
G01X437767Y451812D01*
G02X438055Y451118I-692J-694D01*
G01Y451100D01*
G01X339440Y130000D02*
X338323D01*
G02X338040Y130117I0J401D01*
G01X337699Y130458D01*
G03X337416Y130575I-283J-284D01*
G01X337260D01*
X337259Y130574D01*
X335872D01*
G03X335589Y130457I0J-401D01*
G01X334600Y129468D01*
G01X339440Y132500D02*
X338323D01*
G03X338040Y132383I0J-401D01*
G01X337699Y132042D01*
G02X337416Y131925I-283J284D01*
G01X336700D01*
X336699Y131924D01*
X335873D01*
G02X335590Y132041I0J401D01*
G01X334600Y133031D01*
G01X341640Y132500D02*
G03X343209Y131850I1569J1569D01*
G01X344640D01*
G03X345101Y132041I0J652D01*
G01X349444Y136384D01*
G02X352490Y137645I3045J-3046D01*
G01X357134D01*
X357284Y137795D01*
G01X341640Y136500D02*
X342990D01*
G03X344259Y136876I-1J2332D01*
G03X344639Y137183I-1267J1957D01*
G01X344648Y137189D01*
X344654Y137194D01*
X344697Y137226D01*
X344742Y137260D01*
X344951Y137419D01*
G03X345003Y137464I-300J400D01*
G01X346525Y138986D01*
G02X347754Y139495I1229J-1229D01*
G01X357043D01*
G03X357184I71J1691D01*
G03Y139500I-148J2D01*
G01X357189Y139495D01*
G03X358378Y139988I-1J1682D01*
G01X358975Y140585D01*
G02X359844Y140945I869J-869D01*
G01X360433D01*
G01X341640Y139000D02*
G03X343241Y138337I1601J1601D01*
G01X343807D01*
X343985Y138382D01*
X343987Y138383D01*
X344081Y138454D01*
X344083Y138456D01*
G03X344096Y138468I-332J373D01*
G01X344590Y138961D01*
X345570Y139941D01*
G02X347754Y140845I2183J-2184D01*
G01X357043D01*
G03X357284Y140945I0J340D01*
G01X341640Y130000D02*
X341918Y130278D01*
G02X342300Y130483I534J-537D01*
G01X342301Y130484D01*
G02X342315Y130486I114J-748D01*
G02X342451Y130499I140J-744D01*
G02X342454Y130500I241J-718D01*
G01X344640D01*
G03X346056Y131086I1J2002D01*
G01X350399Y135429D01*
G02X352490Y136295I2091J-2091D01*
G01X357148D01*
G03X358563Y136881I0J2001D01*
G01X359167Y137485D01*
G02X359915Y137795I748J-747D01*
G01X360433D01*
G01X339440Y152000D02*
G02X338052Y151425I-1388J1388D01*
G01X332829D01*
G02X331782Y151858I-1J1480D01*
G01X331040Y152601D01*
G01X339440Y149500D02*
G03X338052Y150075I-1388J-1388D01*
G01X333429D01*
G03X331679Y149350I0J-2475D01*
G01X330929Y148600D01*
G01X341640Y145500D02*
G03X342968Y144950I1328J1328D01*
G01X345510D01*
G03X345971Y145141I0J652D01*
G01X347388Y146558D01*
G02X348803Y147144I1415J-1415D01*
G01X357184D01*
X357284Y147244D01*
G01X341640Y143000D02*
G02X343089Y143600I1449J-1449D01*
G01X345510D01*
G03X346926Y144186I1J2002D01*
G01X348343Y145603D01*
G02X348803Y145794I461J-460D01*
G01X357189D01*
G03X358378Y146287I-1J1682D01*
G01X358975Y146884D01*
G02X359844Y147244I869J-869D01*
G01X360433D01*
G01X341640Y149500D02*
G02X342485Y149850I845J-845D01*
G01X348421D01*
G02X348674Y149745I0J-357D01*
G03X350613Y148943I1937J1938D01*
G01X357631D01*
G03X357824Y149023I0J273D01*
G01X357904Y149103D01*
G03X358378Y149436I-715J1522D01*
G01X358975Y150033D01*
G02X359844Y150393I869J-869D01*
G01X360433D01*
G01X341640Y152000D02*
X341953Y151687D01*
G03X343129Y151200I1176J1176D01*
G01X348422D01*
G02X349629Y150700I0J-1707D01*
G03X350612Y150293I983J983D01*
G01X357043D01*
G03X357284Y150393I0J340D01*
G01X341640Y156000D02*
G02X341881Y156100I241J-241D01*
G01X346446D01*
G02X346929Y155900I0J-683D01*
G03X348274Y155343I1345J1345D01*
G01X357838D01*
G03X358579Y155650I0J1048D01*
G01X359379Y156450D01*
G02X359966Y156693I587J-587D01*
G01X360433D01*
G01X341640Y158500D02*
X341898Y158242D01*
G03X343809Y157450I1912J1911D01*
G01X346445D01*
G02X347884Y156855I2J-2033D01*
G03X348274Y156693I391J390D01*
G01X357284D01*
G01X341640Y169000D02*
G02X341881Y169100I241J-241D01*
G01X343229D01*
G02X345107Y168322I0J-2656D01*
G01X348152Y165277D01*
G03X349567Y164691I1415J1415D01*
G01X358391D01*
G03X359400Y165109I0J1427D01*
G01X359872Y165581D01*
X360433Y166141D01*
G01X341640Y171500D02*
X342499Y170641D01*
G03X342960Y170450I461J461D01*
G01X343230D01*
G02X346062Y169277I0J-4006D01*
G01X349107Y166232D01*
G03X349567Y166041I461J460D01*
G01X357184D01*
X357284Y166141D01*
G01X341640Y162500D02*
G02X341881Y162600I241J-241D01*
G01X344572D01*
G02X346380Y161851I0J-2557D01*
G01X348680Y159551D01*
G03X351237Y158492I2557J2558D01*
G01X356654D01*
X356704Y158442D01*
X357864D01*
X357914Y158492D01*
X357985D01*
G03X358248Y158505I1J2651D01*
G03X359860Y159268I-262J2638D01*
G01X360433Y159842D01*
G01X341640Y165000D02*
G03X344175Y163950I2535J2535D01*
G01X344573D01*
G02X347335Y162806I0J-3907D01*
G01X349635Y160506D01*
G03X351238Y159842I1603J1603D01*
G01X357284D01*
G01X341640Y178000D02*
X341717Y177923D01*
G03X342859Y177450I1142J1142D01*
G01X345699D01*
G02X348584Y176255I0J-4081D01*
G01X351392Y173447D01*
G02X352379Y171063I-2384J-2383D01*
G03X354292Y169150I1913J0D01*
G01X356944D01*
G03X357067Y169166I0J481D01*
G03X357171Y169207I-123J465D01*
G03X357284Y169291I-227J424D01*
G01X341640Y175500D02*
G02X343089Y176100I1449J-1449D01*
G01X345698D01*
G02X347629Y175300I0J-2731D01*
G01X350437Y172492D01*
G02X351029Y171063I-1429J-1429D01*
G03X354292Y167800I3263J0D01*
G01X358929D01*
G03X359983Y168236I1J1490D01*
G01X360300Y168554D01*
G03X360433Y169217I-1588J663D01*
G01Y169291D01*
G01X366733Y137795D02*
X366747D01*
X368296Y136246D01*
G01X369882Y137795D02*
X371456Y136221D01*
G01X369882Y156693D02*
Y156656D01*
X368333Y155107D01*
G01X365140Y155100D02*
X365502D01*
G03X366067Y155334I0J799D01*
G01X366499Y155766D01*
G03X366733Y156331I-565J565D01*
G01Y156693D01*
G01X369882Y150393D02*
Y149860D01*
G02X369736Y149507I-500J0D01*
G01X369209Y148980D01*
G02X368856Y148834I-353J354D01*
G01X368340D01*
X368333Y148827D01*
G01X368329Y151956D02*
X368190Y151817D01*
Y151776D01*
X366807Y150393D01*
X366733D01*
G01X369882Y147244D02*
X371459Y145667D01*
X371493D01*
G01X368314Y142505D02*
X368273D01*
X366733Y140965D01*
Y140945D01*
G01Y147244D02*
X366789Y147300D01*
X367235D01*
G02X367311Y147285I-1J-206D01*
G01X367433Y147237D01*
G03X367572Y147212I139J374D01*
G01X367633D01*
X368213Y146632D01*
G03X368220Y146569I278J-1D01*
G01X368299Y146228D01*
G02X368314Y146096I-568J-131D01*
G01Y145680D01*
G01X368305Y139401D02*
Y139505D01*
X369745Y140945D01*
X369882D01*
G01X366733Y169291D02*
X366770D01*
X368309Y170830D01*
G01X369882Y169291D02*
X369820D01*
X368334Y167805D01*
Y167706D01*
G01X366733Y166141D02*
Y165211D01*
G02X366587Y164858I-500J0D01*
G01X366429Y164700D01*
G02X366076Y164554I-353J354D01*
G01X365158D01*
G01X368325Y164585D02*
X369881Y166141D01*
X369882D01*
G01X366733Y159842D02*
X366768D01*
X368326Y161400D01*
G01X368271Y158268D02*
X368403Y158400D01*
X368440D01*
X369882Y159842D01*
G01X403055Y448900D02*
Y448024D01*
G02X402768Y447330I-983J0D01*
G01X402649Y447211D01*
G03X402480Y446803I408J-408D01*
G01Y445600D01*
G03X403912Y442143I4889J0D01*
G01X414654Y431401D01*
X414655D01*
X421602Y424454D01*
G02X422487Y422788I-2116J-2192D01*
G02X422451Y422782I-61J257D01*
G01X422637Y422638D01*
G01X400555Y448900D02*
Y448024D01*
G03X400843Y447330I980J0D01*
G01X400962Y447211D01*
G02X401130Y446804I-409J-407D01*
G01Y445599D01*
G03X402957Y441188I6239J0D01*
G01X404220Y439922D01*
X405466Y438676D01*
X405935Y438208D01*
X409340Y434801D01*
X414128Y430014D01*
X416019Y428124D01*
X416928Y427216D01*
X420534Y423611D01*
G02X420544Y423601I-278J-288D01*
G02X420553Y423591I-292J-272D01*
G02X420574Y423568I-284J-280D01*
G02X420612Y423521I-291J-274D01*
G02X420676Y423425I-294J-265D01*
G02X421137Y422313I-1201J-1150D01*
G03X421628Y421127I1678J0D01*
G01X422136Y420619D01*
G02X422637Y419410I-1209J-1209D01*
G01Y418701D01*
G01X410055Y448900D02*
Y447927D01*
G02X409909Y447574I-500J0D01*
G01X409626Y447291D01*
G03X409480Y446938I354J-353D01*
G01Y445409D01*
G03X410208Y443653I2484J1D01*
G01X418588Y435272D01*
X419187Y434673D01*
G02X420046Y432599I-2074J-2074D01*
G03X420993Y430313I3233J0D01*
G01X423635Y427671D01*
G02X425065Y424470I-2868J-3201D01*
G01Y420163D01*
G03X425109Y419831I1263J-2D01*
G03X425215Y419565I1219J332D01*
G03X425435Y419270I1112J600D01*
G01X425601Y419104D01*
G03X426574Y418701I973J973D01*
G01X407555Y448900D02*
Y447927D01*
G03X407701Y447574I500J0D01*
G01X407984Y447291D01*
G02X408130Y446938I-354J-353D01*
G01Y445408D01*
G03X409253Y442698I3834J1D01*
G01X417633Y434317D01*
X418232Y433718D01*
G02X418695Y432599I-1119J-1118D01*
G03X420038Y429358I4583J1D01*
G01X423466Y425930D01*
G02X424141Y424418I-1641J-1639D01*
G02X424145Y424290I-2316J-136D01*
G01Y419570D01*
G03X425826Y415512I5739J0D01*
G01X426574Y414764D01*
G01X433073Y1008860D02*
Y1001110D01*
G02X432673Y1000710I-400J0D01*
G01X432178D01*
G03X431778Y1000310I0J-400D01*
G01Y990623D01*
G03X434284Y984573I8556J0D01*
G01X436917Y981940D01*
G02X440178Y974067I-7874J-7873D01*
G01Y907457D01*
G02X438782Y904087I-4766J0D01*
G01X410748Y876053D01*
G03X410188Y874701I1352J-1352D01*
G01Y873798D01*
G03X410658Y872858I1140J-18D01*
G02X411128Y871918I-670J-922D01*
G01Y870718D01*
G02X410658Y869778I-1140J-18D01*
G03X410188Y868838I670J-922D01*
G01Y867638D01*
G03X410658Y866698I1140J-18D01*
G02X411128Y865758I-670J-922D01*
G01Y864558D01*
G02X410658Y863618I-1140J-18D01*
G03X410188Y862678I670J-922D01*
G01Y861478D01*
G03X410658Y860538I1140J-18D01*
G02X411128Y859598I-670J-922D01*
G01Y858398D01*
G02X410658Y857458I-1140J-18D01*
G03X410188Y856518I670J-922D01*
G01Y855318D01*
G03X410658Y854378I1140J-18D01*
G02X411128Y853438I-670J-922D01*
G01Y852238D01*
G02X410658Y851298I-1140J-18D01*
G03X410188Y850358I670J-922D01*
G01Y819800D01*
G03X421721Y791957I39376J0D01*
G01X424736Y788942D01*
G03X425733Y788609I819J793D01*
G02X426730Y788277I179J-1126D01*
G01X427579Y787428D01*
G02X427911Y786431I-794J-818D01*
G03X428244Y785434I1126J-178D01*
G01X429092Y784586D01*
G03X430089Y784253I819J793D01*
G02X431086Y783921I179J-1126D01*
G01X431935Y783073D01*
G02X432267Y782076I-794J-818D01*
G03X432599Y781079I1126J-179D01*
G01X433448Y780230D01*
G03X434445Y779898I818J794D01*
G02X435442Y779565I178J-1126D01*
G01X436291Y778717D01*
G02X436623Y777720I-794J-818D01*
G03X436955Y776723I1126J-179D01*
G01X440308Y773370D01*
G02X444480Y763298I-10073J-10073D01*
G01Y452488D01*
G03X444825Y451655I1178J0D01*
G02X445055Y451100I-555J-555D01*
G01X429133Y1008860D02*
Y1001110D01*
G03X429533Y1000710I400J0D01*
G01X430028D01*
G02X430428Y1000310I0J-400D01*
G01Y990623D01*
G03X433329Y983618I9906J-1D01*
G01X435962Y980985D01*
G02X438828Y974066I-6919J-6919D01*
G01Y907458D01*
G02X437827Y905042I-3416J0D01*
G01X409793Y877008D01*
G03X408838Y874701I2307J-2306D01*
G01Y819800D01*
G03X420766Y791002I40726J-1D01*
G01X439353Y772415D01*
G02X443130Y763297I-9118J-9118D01*
G01Y452706D01*
G02X442843Y452013I-980J0D01*
G03X442555Y451318I695J-695D01*
G01Y451100D01*
G01X426574Y402953D02*
X424605Y404922D01*
G01X426574Y406890D02*
X424605Y408859D01*
G01X422637Y402953D02*
X420668Y404922D01*
G01X422637Y406890D02*
X420668Y408859D01*
G01X417055Y448900D02*
Y448097D01*
G02X416909Y447744I-500J0D01*
G01X416626Y447461D01*
G03X416480Y447108I354J-353D01*
G01Y446100D01*
G03X417522Y443584I3559J0D01*
G01X427561Y433545D01*
G02X430023Y427600I-5945J-5944D01*
G01Y423179D01*
G03X430169Y422826I500J0D01*
G01X430357Y422638D01*
X430511D01*
G01X414555Y448900D02*
Y448077D01*
G03X414701Y447724I500J0D01*
G01X414984Y447441D01*
G02X415130Y447088I-354J-353D01*
G01Y446099D01*
G03X416567Y442629I4909J0D01*
G01X426606Y432590D01*
G02X428673Y427600I-4990J-4990D01*
G01Y420979D01*
G03X428819Y420626I500J0D01*
G01X430429Y419016D01*
G02X430511Y418817I-199J-198D01*
G01Y418701D01*
G01X424055Y448900D02*
Y448607D01*
G02X423909Y448254I-500J0D01*
G01X423701Y448046D01*
G03X423555Y447693I354J-353D01*
G01Y445854D01*
G03X424830Y442776I4353J0D01*
G01X428295Y439311D01*
X428296D01*
G02X428591Y439006I-11046J-10979D01*
G01X431324Y436272D01*
G02X432945Y432360I-3912J-3913D01*
G01Y420954D01*
G03X433226Y419923I2032J0D01*
G01X434448Y418701D01*
G01X421555Y448900D02*
Y448770D01*
G03X421647Y448548I314J0D01*
G01X422059Y448136D01*
G02X422205Y447783I-354J-353D01*
G01Y445853D01*
G03X423875Y441821I5703J0D01*
G01X427339Y438357D01*
G02X427464Y438230I-10074J-10041D01*
G02X427607Y438080I-10223J-9889D01*
G01X427616Y438070D01*
G03X427626Y438060I288J278D01*
G01X430369Y435317D01*
G02X431595Y432359I-2957J-2958D01*
G01Y428010D01*
G03X431774Y426434I7027J0D01*
G02X432011Y424696I-6257J-1738D01*
G01Y420902D01*
X432023Y420890D01*
Y418550D01*
G03X432985Y416226I3286J-1D01*
G01X434448Y414764D01*
G01X431278Y883000D02*
X432898Y881380D01*
G02X433650Y879564I-1817J-1816D01*
G01Y861829D01*
G02X432045Y857955I-5478J0D01*
G03X427853Y847833I10122J-10121D01*
G01Y802400D01*
G02X427453Y802000I-400J0D01*
G01X425278D01*
G01X434448Y406890D02*
X432479Y408859D01*
G01X434448Y402953D02*
X432479Y404922D01*
G01X438385Y402953D02*
X436416Y404922D01*
G01X438385Y406890D02*
X436416Y408859D01*
G01X430511Y406890D02*
X428542Y408859D01*
G01X446259Y402953D02*
X444290Y404922D01*
G01X446259Y406890D02*
X444290Y408859D01*
G01X442322Y406890D02*
X440353Y408859D01*
G01X442322Y402953D02*
X440353Y404922D01*
G01X430511Y402953D02*
X428542Y404922D01*
G01X435555Y448900D02*
Y447827D01*
G03X435701Y447474I500J0D01*
G01X436009Y447166D01*
G02X436155Y446813I-354J-353D01*
G01Y445161D01*
G03X437812Y441158I5659J-2D01*
G01X438512Y440458D01*
G02X439885Y437143I-3315J-3315D01*
G01Y419720D01*
G03X441666Y415420I6081J0D01*
G01X442322Y414764D01*
G01X442555Y448900D02*
Y448024D01*
G03X442843Y447330I980J0D01*
G01X442962Y447211D01*
G02X443130Y446804I-409J-407D01*
G01Y443742D01*
G03X444137Y441307I3444J-2D01*
G02X444355Y440784I-522J-525D01*
G01Y423910D01*
G03X444407Y423302I3549J-3D01*
G01Y423172D01*
G03X446259Y418701I6323J0D01*
G01X438055Y448900D02*
Y447867D01*
G02X437909Y447514I-500J0D01*
G01X437651Y447256D01*
G03X437505Y446903I354J-353D01*
G01Y445160D01*
G03X438767Y442113I4309J0D01*
G01X439467Y441413D01*
G02X441235Y437143I-4270J-4269D01*
G01Y429138D01*
G02X441073Y428468I-1468J0D01*
G03X440805Y427821I647J-647D01*
G01Y419774D01*
G03X441148Y418946I1171J0D01*
G03X441898Y418701I750J1025D01*
G01X442322D01*
G01X431055Y448900D02*
Y447987D01*
G02X430909Y447634I-500J0D01*
G01X430594Y447319D01*
G03X430448Y446966I354J-353D01*
G01Y445300D01*
G03X431962Y441644I5171J0D01*
G01X436530Y437076D01*
G02X438385Y432596I-4480J-4479D01*
G01Y424288D01*
X438384D01*
X438385Y422638D01*
G01X428555Y448900D02*
Y448117D01*
G03X428701Y447764I500J0D01*
G01X428952Y447513D01*
G02X429098Y447160I-354J-353D01*
G01Y445301D01*
G03X431007Y440689I6521J-2D01*
G01X435575Y436121D01*
G02X437035Y432596I-3525J-3525D01*
G01Y424362D01*
G02X436765Y423710I-922J0D01*
G03X436495Y423058I652J-652D01*
G01Y421347D01*
G03X437227Y419579I2501J0D01*
G01X438105Y418701D01*
X438385D01*
G01X445055Y448900D02*
Y448024D01*
G02X444768Y447330I-983J0D01*
G01X444649Y447211D01*
G03X444480Y446803I408J-408D01*
G01Y443742D01*
G03X445093Y442262I2093J0D01*
G02X445705Y440784I-1479J-1478D01*
G01Y423910D01*
G03X445737Y423533I2199J-3D01*
G03X445873Y423067I2166J379D01*
G01X445903Y422995D01*
X446259Y422639D01*
Y422638D01*
G01X438278Y808750D02*
X439109D01*
G02X440332Y808382I-1J-2219D01*
G02X440978Y806822I-1560J-1560D01*
G01Y794100D01*
G03X446906Y779787I20242J-1D01*
G02X450130Y772004I-7783J-7783D01*
G01Y452582D01*
G02X449843Y451888I-983J0D01*
G01X449732Y451777D01*
G03X449555Y451350I427J-427D01*
G01Y451100D01*
G01X444778Y808750D02*
X444162D01*
G03X442935Y808362I0J-2134D01*
G03X442328Y806897I1465J-1465D01*
G01Y794100D01*
G03X447861Y780742I18891J0D01*
G02X451480Y772005I-8738J-8738D01*
G01Y452488D01*
G03X451772Y451783I997J0D01*
G02X452055Y451100I-683J-683D01*
G01X444778Y805250D02*
Y802100D01*
G01X438278Y805250D02*
Y802100D01*
G01X437778Y883000D02*
X436218Y881439D01*
G03X435000Y878500I2939J-2940D01*
G01Y861828D01*
G02X433000Y857000I-6828J0D01*
G03X429203Y847833I9167J-9167D01*
G01Y802400D01*
G03X429603Y802000I400J0D01*
G01X431778D01*
G01X444278Y872250D02*
X444697D01*
G02X445262Y872016I0J-799D01*
G01X446551Y870727D01*
G02X446785Y870162I-565J-565D01*
G01Y827072D01*
G02X445875Y824875I-3107J0D01*
G01X443500Y822500D01*
G03X441000Y816464I6036J-6036D01*
G01Y814500D01*
G02X438750Y812250I-2250J0D01*
G01X438278D01*
G01X450778Y872250D02*
X450659D01*
G03X450094Y872016I0J-799D01*
G01X448369Y870291D01*
G03X448135Y869726I565J-565D01*
G01Y827072D01*
G02X446830Y823920I-4457J-1D01*
G01X444455Y821545D01*
G03X442351Y816464I5081J-5080D01*
G01X442350Y816463D01*
Y813331D01*
G03X442584Y812766I799J0D01*
G01X442866Y812484D01*
G03X443431Y812250I565J565D01*
G01X444778D01*
G01X444883Y1008860D02*
Y1001657D01*
G03X445156Y1000687I1861J0D01*
G03X445428Y1000341I1589J969D01*
G03X445493Y1000186I220J1D01*
G01X445778Y999900D01*
X445807Y999870D01*
G02X446168Y999000I-870J-871D01*
G01Y889851D01*
G03X446428Y888537I3433J-3D01*
G01X446739Y887786D01*
X446740Y887785D01*
G02X446828Y887344I-1062J-441D01*
G01Y877262D01*
G02X446767Y876956I-800J0D01*
G01X446632Y876630D01*
G02X446134Y876174I-739J307D01*
G01X444886Y875779D01*
G02X444698Y875750I-188J595D01*
G01X444278D01*
G01Y879250D02*
Y883000D01*
G01X458071Y402953D02*
Y403035D01*
X456223Y404883D01*
G01X458071Y406890D02*
Y406935D01*
X456223Y408783D01*
G01X463555Y448900D02*
Y448500D01*
G03X463838Y447817I966J0D01*
G01X463843Y447812D01*
G02X464130Y447118I-696J-694D01*
G01Y445300D01*
G02X462079Y440350I-7001J1D01*
G01X461592Y439862D01*
X456842Y435112D01*
X456789Y435058D01*
G03X455646Y432300I2758J-2759D01*
G01Y418900D01*
G03X456856Y415979I4131J0D01*
G01X458071Y414764D01*
G01X449555Y448900D02*
G02X450205Y447331I-1569J-1569D01*
G01Y444098D01*
G02X449400Y442155I-2747J0D01*
G03X447771Y438222I3934J-3933D01*
G01Y420618D01*
G03X450196Y414764I8279J0D01*
G01X454134Y402953D02*
Y402972D01*
X452223Y404883D01*
G01X450196Y406890D02*
X448227Y408859D01*
G01X454134Y406890D02*
X454116D01*
X452223Y408783D01*
G01X450196Y402953D02*
X448227Y404922D01*
G01X470555Y448900D02*
G02X471130Y447512I-1388J-1388D01*
G01Y441776D01*
G02X470792Y440963I-1150J2D01*
G01X462991Y433162D01*
X462992D01*
X462609Y432779D01*
G03X460470Y428345I5278J-5279D01*
G03X460423Y427499I7419J-836D01*
G01Y422604D01*
G03X460486Y422292I800J-1D01*
G01X462008Y418701D01*
G01X466055Y448900D02*
Y448407D01*
G02X465767Y447712I-983J0D01*
G03X465480Y447018I696J-694D01*
G01Y445299D01*
G02X463035Y439395I-8351J0D01*
G01X457647Y434007D01*
G03X456630Y432104I2623J-2625D01*
G03X456560Y431383I3641J-717D01*
G01Y421500D01*
G03X457057Y419812I3110J-1D01*
G03X457471Y419301I2610J1691D01*
G01X458071Y418701D01*
G01X459055Y448900D02*
G02X458914Y448559I-483J0D01*
G03X458405Y447330I1229J-1229D01*
G01Y446099D01*
G02X456402Y441262I-6842J0D01*
G01X456145Y441005D01*
G03X453865Y435500I5506J-5505D01*
G01Y423287D01*
G03X454134Y422638I918J0D01*
G01X456555Y448900D02*
G02X457055Y447693I-1207J-1207D01*
G01Y446100D01*
G02X455446Y442217I-5492J1D01*
G01X455447D01*
X455190Y441960D01*
G03X452515Y435501I6461J-6459D01*
G01Y422769D01*
G03X452576Y422463I800J0D01*
G01X454134Y418701D01*
G01X452055Y448900D02*
G03X451555Y447693I1207J-1207D01*
G01Y444097D01*
G02X450355Y441200I-4097J0D01*
G03X449121Y438221I2979J-2979D01*
G01Y427591D01*
G02X448905Y427070I-737J0D01*
G03X448685Y426539I531J-531D01*
G01Y421200D01*
G03X449384Y419514I2385J1D01*
G01X450196Y418701D01*
G01X469278Y808750D02*
X469823D01*
G02X471232Y808270I1J-2305D01*
G02X471828Y806831I-1439J-1439D01*
G01Y781423D01*
G02X470700Y778700I-3851J0D01*
G01X460550Y768550D01*
X459342Y767343D01*
G03X457129Y762000I5343J-5343D01*
G01X457130D01*
Y452582D01*
G02X456843Y451887I-982J-1D01*
G01X456733Y451777D01*
G03X456555Y451349I426J-428D01*
G01Y451100D01*
G01X475778Y808750D02*
X475077D01*
G03X473797Y808301I0J-2049D01*
G03X473178Y806807I1494J-1494D01*
G01Y781422D01*
G02X471655Y777745I-5201J0D01*
G01X461505Y767595D01*
X460297Y766388D01*
G03X458480Y762000I4388J-4387D01*
G01Y452488D01*
G03X458896Y451484I1420J0D01*
G02X459055Y451100I-384J-384D01*
G01X460778Y883000D02*
X462596Y881181D01*
G02X463500Y879000I-2181J-2182D01*
G01Y841536D01*
G02X461000Y835500I-8536J0D01*
G03X458853Y830317I5183J-5183D01*
G01Y802500D01*
G02X458453Y802100I-400J0D01*
G01X456278D01*
G01X467278Y883000D02*
X465406Y881128D01*
G03X464850Y879786I1342J-1342D01*
G01Y841537D01*
G02X461955Y834545I-9886J-2D01*
G03X460203Y830316I4228J-4229D01*
G01Y802500D01*
G03X460603Y802100I400J0D01*
G01X462778D01*
G01X448818Y1008860D02*
Y1001545D01*
G02X448178Y1000000I-2185J0D01*
G03X447750Y999404I1592J-1595D01*
G03X447743Y999389I2038J-960D01*
G03X447708Y999314I2024J-990D01*
G03X447558Y998833I2063J-907D01*
G03X447547Y998774I2210J-442D01*
G03X447518Y998407I2225J-360D01*
G01Y986038D01*
G03X447988Y985098I1140J-18D01*
G02X448458Y984158I-670J-923D01*
G01Y982958D01*
G02X447988Y982018I-1140J-18D01*
G03X447518Y981078I670J-923D01*
G01Y979878D01*
G03X447988Y978938I1140J-18D01*
G02X448458Y977998I-670J-923D01*
G01Y976798D01*
G02X447988Y975858I-1140J-18D01*
G03X447518Y974918I670J-923D01*
G01Y969278D01*
G03X447988Y968338I1140J-18D01*
G02X448458Y967398I-670J-923D01*
G01Y966198D01*
G02X447988Y965258I-1140J-18D01*
G03X447518Y964318I670J-923D01*
G01Y963118D01*
G03X447988Y962178I1140J-18D01*
G02X448458Y961238I-670J-923D01*
G01Y960038D01*
G02X447988Y959098I-1140J-18D01*
G03X447518Y958158I670J-923D01*
G01Y956958D01*
G03X447988Y956018I1140J-18D01*
G02X448458Y955078I-670J-923D01*
G01Y953878D01*
G02X447988Y952938I-1140J-18D01*
G03X447518Y951998I670J-923D01*
G01Y940007D01*
G03X447988Y939067I1140J-18D01*
G02X448458Y938127I-670J-922D01*
G01Y936927D01*
G02X447988Y935987I-1140J-18D01*
G03X447518Y935047I670J-922D01*
G01Y933847D01*
G03X447988Y932907I1140J-18D01*
G02X448458Y931967I-670J-922D01*
G01Y930767D01*
G02X447988Y929827I-1140J-18D01*
G03X447518Y928887I670J-922D01*
G01Y889851D01*
G03X447676Y889054I2083J-1D01*
G01X447987Y888303D01*
G02X448178Y887345I-2309J-958D01*
G01Y877956D01*
G03X448904Y876203I2479J0D01*
G03X450247Y875750I1344J1766D01*
G01X450778D01*
G01Y879250D02*
Y883000D01*
G01X460628Y1008860D02*
Y1001998D01*
G03X461298Y1000380I2289J0D01*
G02X461968Y998762I-1619J-1618D01*
G01Y923974D01*
G03X465273Y915995I11285J0D01*
G01X473642Y907626D01*
G02X476428Y900900I-6726J-6726D01*
G01Y877614D01*
G02X475791Y876076I-2175J0D01*
G02X474497Y875750I-1294J2405D01*
G01X473778D01*
G01X469305Y293800D02*
X467055Y296050D01*
Y306578D01*
X467077Y306600D01*
Y307077D01*
X470482Y310482D01*
Y315327D01*
X474673Y319518D01*
Y323358D01*
X473819Y324212D01*
G01X472805Y305500D02*
X476105Y302200D01*
X482200D01*
X484600Y304600D01*
X491840D01*
X494123Y306883D01*
G01X473819Y328149D02*
X476055Y325913D01*
Y323391D01*
X476023Y323359D01*
Y318958D01*
X471832Y314767D01*
Y306473D01*
X472805Y305500D01*
G01X462008Y406890D02*
X463977Y408859D01*
G01X462008Y402953D02*
X463977Y404922D01*
G01X465945Y406890D02*
X467914Y408859D01*
G01X465945Y402953D02*
X467914Y404922D01*
G01X477555Y448900D02*
G02X478130Y447512I-1388J-1388D01*
G01Y440592D01*
G02X475855Y435100I-7767J0D01*
G01X473755Y433000D01*
X473017Y432263D01*
G02X467555Y430000I-5463J5462D01*
G01X467072D01*
G03X465149Y429409I-2J-3416D01*
G03X464655Y429000I1922J-2824D01*
G03X463515Y426248I2752J-2752D01*
G01Y420631D01*
G03X465945Y414764I8297J0D01*
G01X473055Y448900D02*
X472990D01*
G03X472618Y448651I0J-402D01*
G01X472538Y448459D01*
G03X472480Y448168I701J-291D01*
G01Y441776D01*
G02X471748Y440008I-2501J0D01*
G01X463564Y431824D01*
G03X461812Y428193I4324J-4324D01*
G01X461773Y427507D01*
Y423166D01*
G03X462008Y422638I801J40D01*
G01X480055Y448900D02*
X479959D01*
G03X479701Y448766I-1J-314D01*
G01X479600Y448621D01*
G03X479480Y448241I542J-380D01*
G01Y440591D01*
G02X476810Y434145I-9117J0D01*
G01X473972Y431307D01*
G02X467556Y428650I-6416J6418D01*
G01X467071D01*
G03X465908Y428292I-1J-2066D01*
G03X465610Y428045I1164J-1707D01*
G01X465310Y427745D01*
G03X464434Y425978I2182J-2182D01*
G01Y420475D01*
G03X465085Y418903I2223J0D01*
G03X465573Y418701I488J488D01*
G01X465945D01*
G01X476378Y1008860D02*
Y1002544D01*
G03X477328Y1000250I3244J0D01*
G02X478138Y998294I-1956J-1956D01*
G01Y931860D01*
G03X484728Y915950I22501J0D01*
G01X495707Y904971D01*
X507986Y892693D01*
G02X517970Y868588I-24105J-24104D01*
G01Y703269D01*
G02X509273Y682274I-29692J1D01*
G01X508510Y681510D01*
X467440Y640440D01*
G03X464130Y632449I7992J-7992D01*
G01Y452488D01*
G02X463785Y451655I-1178J0D01*
G03X463555Y451100I555J-555D01*
G01X492128Y1008860D02*
Y1000769D01*
G03X492778Y999200I2219J0D01*
G02X493328Y997872I-1328J-1328D01*
G01Y935799D01*
G03X506020Y905159I43333J1D01*
G01X507728Y903450D01*
X517135Y894043D01*
G02X526056Y872506I-21537J-21537D01*
G01Y695170D01*
G02X521379Y683879I-15968J0D01*
G01X474098Y636598D01*
X473511Y636013D01*
G03X471129Y630261I5751J-5751D01*
G01X471130D01*
Y452488D01*
G02X470555Y451100I-1963J0D01*
G01X496063Y1008860D02*
Y1001016D01*
G02X495829Y1000451I-799J0D01*
G01X494912Y999534D01*
G03X494678Y998969I565J-565D01*
G01Y993027D01*
G03X495148Y992087I1140J-18D01*
G02X495618Y991147I-670J-922D01*
G01Y989947D01*
G02X495148Y989007I-1140J-18D01*
G03X494678Y988067I670J-922D01*
G01Y986867D01*
G03X495148Y985927I1140J-18D01*
G02X495618Y984987I-670J-922D01*
G01Y983787D01*
G02X495148Y982847I-1140J-18D01*
G03X494678Y981907I670J-922D01*
G01Y980707D01*
G03X495148Y979767I1140J-18D01*
G02X495618Y978827I-670J-922D01*
G01Y977627D01*
G02X495148Y976687I-1140J-18D01*
G03X494678Y975747I670J-922D01*
G01Y968778D01*
G03X495148Y967838I1140J-18D01*
G02X495618Y966898I-670J-922D01*
G01Y965698D01*
G02X495148Y964758I-1140J-18D01*
G03X494678Y963818I670J-922D01*
G01Y962618D01*
G03X495148Y961678I1140J-18D01*
G02X495618Y960738I-670J-922D01*
G01Y959538D01*
G02X495148Y958598I-1140J-18D01*
G03X494678Y957658I670J-922D01*
G01Y956458D01*
G03X495148Y955518I1140J-18D01*
G02X495618Y954578I-670J-922D01*
G01Y953378D01*
G02X495148Y952438I-1140J-18D01*
G03X494678Y951498I670J-922D01*
G01Y935800D01*
G03X506975Y906114I41983J1D01*
G01X507829Y905259D01*
X518090Y894998D01*
G02X527406Y872507I-22492J-22491D01*
G01Y695169D01*
G02X522334Y682924I-17318J0D01*
G01X475052Y635642D01*
X474466Y635057D01*
G03X472480Y630261I4796J-4795D01*
G01Y451859D01*
G03X472541Y451553I800J0D01*
G01X472626Y451347D01*
G03X472995Y451100I370J153D01*
G01X473055D01*
G01X507873Y1008860D02*
Y1001036D01*
G03X508107Y1000471I799J0D01*
G01X508894Y999684D01*
G02X509089Y999362I-566J-563D01*
G02X509092Y999350I-771J-199D01*
G02X509128Y999119I-762J-237D01*
G01Y923226D01*
G03X517351Y903374I28076J1D01*
G01X526109Y894616D01*
G02X532917Y878180I-16436J-16436D01*
G01Y689566D01*
G02X527862Y677362I-17259J0D01*
G01X480267Y629767D01*
G03X478130Y624606I5161J-5160D01*
G01Y452488D01*
G02X477555Y451100I-1963J0D01*
G01X480313Y1008860D02*
Y1001566D01*
G02X480079Y1001001I-799J0D01*
G01X479722Y1000644D01*
G03X479488Y1000079I565J-565D01*
G01Y986618D01*
G03X479958Y985678I1140J-18D01*
G02X480428Y984738I-670J-923D01*
G01Y983538D01*
G02X479958Y982598I-1140J-18D01*
G03X479488Y981658I670J-923D01*
G01Y980458D01*
G03X479958Y979518I1140J-18D01*
G02X480428Y978578I-670J-923D01*
G01Y977378D01*
G02X479958Y976438I-1140J-18D01*
G03X479488Y975498I670J-923D01*
G01Y974298D01*
G03X479958Y973358I1140J-18D01*
G02X480428Y972418I-670J-923D01*
G01Y971218D01*
G02X479958Y970278I-1140J-18D01*
G03X479488Y969338I670J-923D01*
G01Y963819D01*
G03X479958Y962879I1140J-18D01*
G02X480428Y961939I-670J-922D01*
G01Y960739D01*
G02X479958Y959799I-1140J-18D01*
G03X479488Y958859I670J-922D01*
G01Y957659D01*
G03X479958Y956719I1140J-18D01*
G02X480428Y955779I-670J-922D01*
G01Y954579D01*
G02X479958Y953639I-1140J-18D01*
G03X479488Y952699I670J-922D01*
G01Y951499D01*
G03X479958Y950559I1140J-18D01*
G02X480428Y949619I-670J-922D01*
G01Y948419D01*
G02X479958Y947479I-1140J-18D01*
G03X479488Y946539I670J-922D01*
G01Y939571D01*
G03X479958Y938631I1140J-18D01*
G02X480428Y937691I-670J-922D01*
G01Y936491D01*
G02X479958Y935551I-1140J-18D01*
G03X479488Y934611I670J-922D01*
G01Y931861D01*
G03X485683Y916905I21151J0D01*
G01X496662Y905926D01*
X508941Y893648D01*
G02X519321Y868588I-25060J-25060D01*
G01X519320D01*
Y703268D01*
G02X510229Y681319I-31042J0D01*
G01X468395Y639485D01*
G03X465480Y632448I7037J-7037D01*
G01Y452488D01*
G03X465896Y451484I1420J0D01*
G02X466055Y451100I-384J-384D01*
G01X475778Y805250D02*
Y802100D01*
G01X469278Y805250D02*
Y802100D01*
G01X480278Y872250D02*
X479811D01*
G03X478000Y871500I0J-2561D01*
G03X477850Y871138I362J-362D01*
G01Y844327D01*
G02X475455Y838545I-8178J1D01*
G03X473203Y833109I5435J-5436D01*
G01Y814729D01*
G03X473437Y814164I799J0D01*
G01X475115Y812485D01*
G03X475681Y812250I566J564D01*
G01X475778D01*
G01X473778Y872250D02*
G02X476500Y869528I0J-2722D01*
G01Y844328D01*
G02X474500Y839500I-6828J0D01*
G03X471853Y833110I6390J-6390D01*
G01Y814384D01*
G02X471619Y813819I-799J0D01*
G01X470285Y812484D01*
G02X469719Y812250I-565J566D01*
G01X469278D01*
G01X473778Y879250D02*
Y883000D01*
G01X464568Y1008860D02*
Y1002074D01*
G02X463943Y1000565I-2134J0D01*
G03X463318Y999056I1509J-1509D01*
G01Y991518D01*
G03X463788Y990578I1140J-17D01*
G02X464258Y989638I-670J-922D01*
G01Y988438D01*
G02X463788Y987498I-1140J-17D01*
G03X463318Y986558I670J-922D01*
G01Y985358D01*
G03X463788Y984418I1140J-17D01*
G02X464258Y983478I-670J-922D01*
G01Y982278D01*
G02X463788Y981338I-1140J-17D01*
G03X463318Y980398I670J-922D01*
G01Y979198D01*
G03X463788Y978258I1140J-17D01*
G02X464258Y977318I-670J-922D01*
G01Y976118D01*
G02X463788Y975178I-1140J-17D01*
G03X463318Y974238I670J-922D01*
G01Y962198D01*
G03X463788Y961258I1140J-18D01*
G02X464258Y960318I-670J-922D01*
G01Y959118D01*
G02X463788Y958178I-1140J-18D01*
G03X463318Y957238I670J-922D01*
G01Y956038D01*
G03X463788Y955098I1140J-18D01*
G02X464258Y954158I-670J-922D01*
G01Y952958D01*
G02X463788Y952018I-1140J-18D01*
G03X463318Y951078I670J-922D01*
G01Y949878D01*
G03X463788Y948938I1140J-18D01*
G02X464258Y947998I-670J-922D01*
G01Y946798D01*
G02X463788Y945858I-1140J-18D01*
G03X463318Y944918I670J-922D01*
G01Y938265D01*
G03X463788Y937325I1140J-18D01*
G02X464258Y936385I-670J-922D01*
G01Y935185D01*
G02X463788Y934245I-1140J-18D01*
G03X463318Y933305I670J-922D01*
G01Y923975D01*
G03X466228Y916950I9935J0D01*
G01X474597Y908581D01*
G02X477778Y900900I-7681J-7680D01*
G01Y877551D01*
G03X478423Y875994I2202J0D01*
G03X479418Y875750I994J1904D01*
G01X480278D01*
G01X485630Y336023D02*
Y335870D01*
X487500Y334000D01*
Y333833D01*
G01X483662Y334054D02*
X483446D01*
X481693Y335807D01*
Y336023D01*
G01X485630Y332086D02*
X487599Y330117D01*
G01X481693Y328149D02*
X483662Y326180D01*
G01X484000Y322000D02*
X484005D01*
G03X484850Y322350I0J1195D01*
G01X485200Y322700D01*
G03X485630Y323738I-1038J1038D01*
G01Y324212D01*
G01Y328149D02*
X487599Y326180D01*
G01X487155Y321900D02*
X487214Y321959D01*
Y322041D01*
G02X486980Y322606I565J565D01*
G01Y323194D01*
G02X487214Y323759I799J0D01*
G01X487433Y323978D01*
G02X487998Y324212I565J-565D01*
G01X489567D01*
G01X519423Y324783D02*
X518949Y325257D01*
G03X518000Y325650I-949J-949D01*
G01X507954D01*
G02X505617Y326618I0J3306D01*
G01X503895Y328340D01*
G01X481693Y332086D02*
X483662Y330117D01*
G01X485630Y339960D02*
X487599Y337991D01*
G01X481693Y339960D02*
X483662Y337991D01*
G01Y341928D02*
Y342033D01*
G03X483588Y342212I-253J0D01*
G01X482051Y343749D01*
G03X481693Y343897I-358J-359D01*
G01X487599Y341928D02*
X487272D01*
X485630Y343570D01*
Y343897D01*
G01X481693Y347834D02*
X483662Y345865D01*
G01X485630Y351771D02*
X487599Y349802D01*
G01X483662D02*
X483598D01*
X481693Y351707D01*
Y351771D01*
G01X485630Y347834D02*
X487599Y345865D01*
G01X514923Y332283D02*
X514162Y333044D01*
G03X513906Y333150I-256J-256D01*
G01X513756D01*
G02X511603Y334040I-3J3042D01*
G01X509888Y335755D01*
G03X508255Y336433I-1635J-1633D01*
G01X506638D01*
G01X515900Y351000D02*
X515498Y350597D01*
G02X514900Y350350I-597J598D01*
G01X514400D01*
G02X513802Y350597I-1J845D01*
G01X513600Y350800D01*
G03X512205Y351378I-1395J-1395D01*
G01X505328D01*
G03X503155Y350478I0J-3073D01*
G02X502600Y350248I-555J555D01*
G01X497975D01*
G03X496850Y349782I0J-1591D01*
G01X495890Y348823D01*
G02X493504Y347834I-2387J2386D01*
G01X485630Y367519D02*
X485639D01*
X487603Y369483D01*
G01X481693Y359645D02*
X483662Y357676D01*
G01X485630Y359645D02*
X487599Y357676D01*
G01X481693Y363582D02*
X481782D01*
X483663Y365463D01*
G01X485630Y363582D02*
Y363581D01*
X483662Y361613D01*
G01X481693Y355708D02*
X483662Y353739D01*
G01X485630Y355708D02*
X487599Y353739D01*
G01X481693Y367519D02*
X481799D01*
X483683Y369403D01*
G01X529555Y387900D02*
G02X530155Y386451I-1449J-1449D01*
G01Y385786D01*
G02X529850Y385050I-1041J0D01*
G01X519549Y374749D01*
X518799Y373998D01*
G02X518200Y373751I-598J600D01*
G03X516622Y373375I0J-3500D01*
G03X515726Y372727I1577J-3124D01*
G01X515700Y372700D01*
X510300Y367300D01*
G02X508446Y366532I-1854J1854D01*
G01X502930D01*
G03X502218Y366237I0J-1007D01*
G02X501692Y366019I-526J526D01*
G01X498953D01*
G03X497439Y365392I0J-2141D01*
G02X497217Y365300I-222J222D01*
G01X496255D01*
G03X494491Y364570I-1J-2494D01*
G01X493504Y363582D01*
G01X515900Y362000D02*
Y361900D01*
G02X515000Y361000I-900J0D01*
G03X512952Y360152I0J-2897D01*
G01X512900Y360100D01*
X512866Y360067D01*
G02X510900Y359252I-1967J1966D01*
G01X505328D01*
G03X503155Y358352I0J-3073D01*
G02X502600Y358122I-555J555D01*
G01X497975D01*
G03X496850Y357656I0J-1591D01*
G01X495890Y356697D01*
G02X493504Y355708I-2387J2386D01*
G01X515865Y388360D02*
G02X516455Y386936I-1424J-1424D01*
G02X516051Y385961I-1379J0D01*
G01X505595Y375505D01*
X505181Y375090D01*
G02X504600Y374849I-581J581D01*
G03X502701Y374063I-1J-2685D01*
G01X502508Y373870D01*
X497975D01*
G03X496850Y373404I0J-1591D01*
G01X495890Y372445D01*
G02X493504Y371456I-2387J2386D01*
G01X523623Y1008860D02*
Y1001600D01*
G03X524221Y1000158I2040J1D01*
G01X524478Y999900D01*
G02X524692Y999607I-847J-843D01*
G02X524787Y999362I-1059J-552D01*
G02X524828Y999055I-1153J-310D01*
G01Y910594D01*
G03X527622Y903847I9542J-1D01*
G01X537151Y894318D01*
G02X540084Y887237I-7081J-7081D01*
G01Y683759D01*
G02X533950Y668950I-20943J0D01*
G01X488003Y623003D01*
G03X484880Y615462I7541J-7540D01*
G01Y461650D01*
G03X487666Y454924I9513J0D01*
G01X514397Y428193D01*
G02X516355Y423466I-4727J-4727D01*
G01Y391743D01*
G02X515865Y390560I-1673J0D01*
G01X527558Y1008860D02*
Y1000795D01*
G02X527422Y1000229I-1243J-1D01*
G01X527400Y1000206D01*
G02X527137Y1000031I-566J565D01*
G01X526578Y999800D01*
G03X526178Y998834I966J-966D01*
G01Y955663D01*
G03X526648Y954723I1140J-18D01*
G02X527118Y953783I-670J-922D01*
G01Y952583D01*
G02X526648Y951643I-1140J-18D01*
G03X526178Y950703I670J-922D01*
G01Y949503D01*
G03X526648Y948563I1140J-18D01*
G02X527118Y947623I-670J-922D01*
G01Y946423D01*
G02X526648Y945483I-1140J-18D01*
G03X526178Y944543I670J-922D01*
G01Y943343D01*
G03X526648Y942403I1140J-18D01*
G02X527118Y941463I-670J-922D01*
G01Y940263D01*
G02X526648Y939323I-1140J-18D01*
G03X526178Y938383I670J-922D01*
G01Y910594D01*
G03X528577Y904802I8191J0D01*
G01X538106Y895273D01*
G02X541434Y887238I-8036J-8035D01*
G01Y683759D01*
G02X534905Y667995I-22294J-1D01*
G01X488958Y622048D01*
G03X486230Y615462I6586J-6586D01*
G01Y461651D01*
G03X488621Y455879I8163J0D01*
G01X515352Y429148D01*
G02X517705Y423467I-5682J-5681D01*
G01Y392100D01*
G03X518327Y390597I2125J-1D01*
G01X518365Y390560D01*
G01X539368Y1008860D02*
Y1000960D01*
G03X539618Y1000358I852J1D01*
G01X539667Y1000308D01*
X540102Y999873D01*
G02X540244Y999680I-573J-570D01*
G02X540339Y999301I-713J-380D01*
G01Y909062D01*
G03X542679Y903411I7991J-1D01*
G01X549067Y897023D01*
G02X552500Y888735I-8288J-8288D01*
G01Y686259D01*
G02X543124Y663625I-32010J1D01*
G01X542849Y663349D01*
X497405Y617905D01*
G03X494000Y609683I8222J-8221D01*
G01Y461284D01*
G03X495614Y457386I5512J-1D01*
G01X520817Y432183D01*
G02X523129Y426600I-5583J-5582D01*
G01X523130Y426601D01*
Y392124D01*
G02X523013Y391841I-401J0D01*
G01X522672Y391500D01*
G03X522555Y391217I284J-283D01*
G01Y390100D01*
G01X511813Y1008860D02*
Y1000611D01*
G02X511780Y1000447I-429J1D01*
G01X511745Y1000362D01*
G02X511515Y1000131I-394J162D01*
G01X511143Y999978D01*
G03X510884Y999805I306J-739D01*
G01X510712Y999634D01*
G03X510478Y999069I565J-565D01*
G01Y986818D01*
G03X510948Y985878I1140J-17D01*
G02X511418Y984938I-670J-922D01*
G01Y983738D01*
G02X510948Y982798I-1140J-17D01*
G03X510478Y981858I670J-922D01*
G01Y980658D01*
G03X510948Y979718I1140J-17D01*
G02X511418Y978778I-670J-922D01*
G01Y977578D01*
G02X510948Y976638I-1140J-17D01*
G03X510478Y975698I670J-922D01*
G01Y968036D01*
G03X510948Y967096I1140J-18D01*
G02X511418Y966156I-670J-922D01*
G01Y964956D01*
G02X510948Y964016I-1140J-18D01*
G03X510478Y963076I670J-922D01*
G01Y961876D01*
G03X510948Y960936I1140J-18D01*
G02X511418Y959996I-670J-922D01*
G01Y958796D01*
G02X510948Y957856I-1140J-18D01*
G03X510478Y956916I670J-922D01*
G01Y955716D01*
G03X510948Y954776I1140J-18D01*
G02X511418Y953836I-670J-922D01*
G01Y952636D01*
G02X510948Y951696I-1140J-18D01*
G03X510478Y950756I670J-922D01*
G01Y923227D01*
G03X518306Y904329I26726J0D01*
G01X527064Y895571D01*
G02X534267Y878180I-17391J-17390D01*
G01Y689566D01*
G02X528817Y676407I-18609J-1D01*
G01X481222Y628812D01*
G03X479480Y624606I4206J-4206D01*
G01Y451959D01*
G03X479541Y451653I800J0D01*
G01X479668Y451347D01*
G03X480037Y451100I370J153D01*
G01X480055D01*
G01X480278Y879250D02*
Y883000D01*
G01X519283Y320577D02*
G02X518350Y321510I0J933D01*
G03X517538Y323462I-2775J-9D01*
G01X517500Y323500D01*
G03X515105Y324492I-2395J-2396D01*
G01X503092D01*
G02X501308Y325231I0J2523D01*
G01X501044Y325496D01*
X500701Y325839D01*
G02X500555Y326192I354J353D01*
G01Y327293D01*
G02X500701Y327646I500J0D01*
G01X501081Y328026D01*
G02X501378Y328149I297J-297D01*
G01X516283Y320577D02*
X516854Y321149D01*
G03X517000Y321500I-351J352D01*
G03X516583Y322507I-1424J0D01*
G01X516545Y322545D01*
G03X515104Y323142I-1441J-1441D01*
G01X503091D01*
G02X500353Y324276I0J3873D01*
G01X499745Y324884D01*
X499216Y325412D01*
X499158Y325471D01*
X499111Y325516D01*
X498976Y325651D01*
X498928Y325700D01*
X498926Y325701D01*
X498120Y326510D01*
G02X497441Y328149I1639J1639D01*
G01X519423Y327283D02*
G02X518740Y327000I-683J683D01*
G01X507955D01*
G02X506572Y327573I0J1956D01*
G01X504850Y329295D01*
G01X525423Y332783D02*
G02X523533Y332000I-1890J1890D01*
G01X521504D01*
G03X520055Y331400I0J-2049D01*
G02X518384Y330708I-1671J1671D01*
G01X512574D01*
G02X511505Y331151I0J1512D01*
G01X508022Y334634D01*
G03X506455Y335283I-1567J-1567D01*
G01X503155D01*
G02X502769Y335312I-6J2505D01*
G02X501399Y336000I385J2475D01*
G02X501384Y336016I1819J1720D01*
G01X501378Y336023D01*
G01X525423Y330283D02*
G03X524537Y330650I-886J-886D01*
G01X521503D01*
G03X521010Y330445I1J-699D01*
G02X518384Y329358I-2625J2626D01*
G01X512573D01*
G02X510550Y330196I1J2862D01*
G01X507067Y333679D01*
G03X506456Y333933I-613J-612D01*
G01X500753D01*
G02X498665Y334798I0J2953D01*
G01X498509Y334955D01*
X497441Y336023D01*
G01X514923Y334783D02*
G02X514240Y334500I-683J683D01*
G01X513755D01*
G02X512558Y334995I-1J1692D01*
G01X510844Y336710D01*
G03X508255Y337783I-2590J-2589D01*
G01X506638D01*
G01X515900Y346000D02*
G02X514331Y345350I-1569J1569D01*
G01X511633D01*
G02X510655Y345755I0J1383D01*
G03X508756Y346541I-1898J-1899D01*
G01X507169D01*
X506962Y346334D01*
X502890D01*
G03X501376Y345707I0J-2141D01*
G02X501154Y345615I-222J222D01*
G01X500192D01*
G03X498428Y344885I-1J-2494D01*
G01X497441Y343897D01*
G01X515900Y348500D02*
X515753Y348646D01*
G03X514900Y349000I-854J-853D01*
G01X514400D01*
Y348999D01*
G02X512846Y349643I0J2196D01*
G01X512644Y349845D01*
G03X512204Y350028I-441J-439D01*
G01X505046D01*
G03X504310Y349723I0J-1041D01*
G02X503598Y349428I-712J712D01*
G01X500355D01*
G03X498101Y348495I-1J-3187D01*
G01X497441Y347834D01*
G01X515900Y343500D02*
G03X514693Y344000I-1207J-1207D01*
G01X511633D01*
G02X509700Y344800I-1J2733D01*
G03X508756Y345191I-944J-944D01*
G01X507169D01*
X506963Y345397D01*
X504592D01*
G03X504020Y345357I2J-4138D01*
G03X503314Y345194I574J-4098D01*
G03X501666Y344185I1277J-3936D01*
G01X501378Y343897D01*
G01X515900Y353500D02*
X515895Y353505D01*
G03X514700Y354000I-1195J-1195D01*
G01X512500D01*
G03X511647Y353646I1J-1207D01*
G01X511500Y353500D01*
G02X510450Y353065I-1050J1050D01*
G01X507169D01*
X506963Y353271D01*
X504592D01*
G03X503314Y353068I2J-4138D01*
G03X501666Y352059I1277J-3936D01*
G01X501378Y351771D01*
G01X515900Y356000D02*
X515639Y355739D01*
G02X514700Y355350I-939J939D01*
G01X512499D01*
G03X510693Y354603I0J-2557D01*
G01X510546Y354457D01*
X510545Y354455D01*
G02X510449Y354415I-96J95D01*
G01X507169D01*
X506962Y354208D01*
X502890D01*
G03X501376Y353581I0J-2141D01*
G02X501154Y353489I-222J222D01*
G01X500192D01*
G03X498428Y352759I-1J-2494D01*
G01X497441Y351771D01*
G01X539000Y387900D02*
Y386783D01*
G02X538883Y386500I-401J0D01*
G01X538542Y386159D01*
G03X538425Y385876I284J-283D01*
G01Y384418D01*
G02X537592Y382407I-2845J1D01*
G01X523792Y368607D01*
G02X521118Y367500I-2673J2674D01*
G01X518835D01*
G03X517255Y366845I1J-2235D01*
G01X511805Y361395D01*
G02X509039Y360250I-2765J2766D01*
G01X501983D01*
X501378Y359645D01*
G01X536500Y387900D02*
Y386783D01*
G03X536617Y386500I401J0D01*
G01X536958Y386159D01*
G02X537075Y385876I-284J-283D01*
G01Y384419D01*
G02X536637Y383362I-1495J0D01*
G01X522837Y369562D01*
G02X521118Y368850I-1719J1719D01*
G01X518835D01*
G03X516300Y367800I0J-3585D01*
G01X510850Y362350D01*
G02X509039Y361600I-1811J1811D01*
G01X502455D01*
X502405Y361650D01*
G03X501560Y362000I-845J-845D01*
G01X500380D01*
G03X498366Y361166I0J-2849D01*
G01X497862Y360662D01*
G03X497441Y359645I1018J-1017D01*
G01X532055Y387900D02*
G03X531505Y386572I1328J-1328D01*
G01Y385786D01*
G02X530805Y384095I-2391J-1D01*
G01X520505Y373795D01*
X519754Y373043D01*
G02X518200Y372400I-1553J1554D01*
G03X516681Y371771I0J-2149D01*
G01X511255Y366345D01*
G02X508447Y365182I-2808J2809D01*
G01X503073D01*
G03X502832Y365082I0J-341D01*
G01X500655D01*
G03X499377Y364879I2J-4138D01*
G03X497729Y363870I1277J-3936D01*
G01X497441Y363582D01*
G01X525055Y387900D02*
X524847Y387692D01*
G03X524405Y386625I1067J-1067D01*
G01Y386285D01*
G02X523705Y384595I-2391J0D01*
G01X508362Y369252D01*
G02X505700Y368150I-2661J2663D01*
G01X502901D01*
G03X502538Y368119I1J-2154D01*
G03X502124Y368005I362J-2123D01*
G03X501378Y367519I777J-2009D01*
G01X522555Y387900D02*
G02X523055Y386693I-1207J-1207D01*
G01Y386286D01*
G02X522750Y385550I-1041J0D01*
G01X507407Y370207D01*
G02X505700Y369500I-1707J1707D01*
G01X502209D01*
G03X499655Y368442I0J-3612D01*
G01X499645Y368432D01*
G02X497441Y367519I-2204J2204D01*
G01X515900Y359500D02*
G03X515538Y359650I-362J-362D01*
G01X514999D01*
G03X513907Y359196I3J-1546D01*
G01X513848Y359138D01*
X513814Y359104D01*
G02X510901Y357902I-2913J2929D01*
G01X505046D01*
G03X504310Y357597I0J-1041D01*
G02X503598Y357302I-712J712D01*
G01X500355D01*
G03X498101Y356369I-1J-3187D01*
G01X497441Y355708D01*
G01X518365Y388360D02*
G03X517805Y387008I1352J-1352D01*
G01Y386936D01*
G02X517006Y385006I-2729J-1D01*
G01X506551Y374551D01*
X506137Y374135D01*
G02X504600Y373499I-1536J1536D01*
G03X503656Y373108I0J-1335D01*
G01X503548Y373000D01*
X499074D01*
X498594Y372520D01*
G03X498101Y372117I1761J-2657D01*
G01X497441Y371456D01*
G01X543308Y1008860D02*
Y1001309D01*
G02X542957Y1000463I-1197J1D01*
G01X541848Y999354D01*
G03X541689Y998970I384J-384D01*
G01Y967166D01*
G03X542159Y966226I1140J-18D01*
G02X542629Y965286I-670J-922D01*
G01Y964086D01*
G02X542159Y963146I-1140J-18D01*
G03X541689Y962206I670J-922D01*
G01Y961006D01*
G03X542159Y960066I1140J-18D01*
G02X542629Y959126I-670J-922D01*
G01Y957926D01*
G02X542159Y956986I-1140J-18D01*
G03X541689Y956046I670J-922D01*
G01Y954846D01*
G03X542159Y953906I1140J-18D01*
G02X542629Y952966I-670J-922D01*
G01Y951766D01*
G02X542159Y950826I-1140J-18D01*
G03X541689Y949886I670J-922D01*
G01Y909062D01*
G03X543634Y904366I6641J0D01*
G01X550022Y897978D01*
G02X553850Y888735I-9243J-9242D01*
G01Y686258D01*
G02X544080Y662671I-33360J1D01*
G01X543806Y662396D01*
X498360Y616950D01*
G03X495350Y609683I7267J-7267D01*
G01Y461284D01*
G03X496569Y458341I4162J0D01*
G01X521772Y433138D01*
G02X524480Y426600I-6538J-6538D01*
G01Y392124D01*
G03X524597Y391841I401J0D01*
G01X524938Y391500D01*
G02X525055Y391217I-284J-283D01*
G01Y390100D01*
G01X582678Y1008860D02*
Y1001490D01*
G02X581978Y999800I-2390J0D01*
G03X581428Y998472I1328J-1328D01*
G01Y985383D01*
G03X581898Y984443I1140J-18D01*
G02X582368Y983503I-670J-922D01*
G01Y982303D01*
G02X581898Y981363I-1140J-18D01*
G03X581428Y980423I670J-922D01*
G01Y979223D01*
G03X581898Y978283I1140J-18D01*
G02X582368Y977343I-670J-922D01*
G01Y976143D01*
G02X581898Y975203I-1140J-18D01*
G03X581428Y974263I670J-922D01*
G01Y964207D01*
G03X581898Y963267I1140J-18D01*
G02X582368Y962327I-670J-922D01*
G01Y961127D01*
G02X581898Y960187I-1140J-18D01*
G03X581428Y959247I670J-922D01*
G01Y958047D01*
G03X581898Y957107I1140J-18D01*
G02X582368Y956167I-670J-922D01*
G01Y954967D01*
G02X581898Y954027I-1140J-18D01*
G03X581428Y953087I670J-922D01*
G01Y951887D01*
G03X581898Y950947I1140J-18D01*
G02X582368Y950007I-670J-922D01*
G01Y948807D01*
G02X581898Y947867I-1140J-18D01*
G03X581428Y946927I670J-922D01*
G01Y671265D01*
G02X575558Y657092I-20043J-1D01*
G01X550460Y631994D01*
X548510Y630045D01*
X511785Y593320D01*
G03X508850Y586234I7086J-7086D01*
G01Y469481D01*
G03X510562Y465348I5845J0D01*
G01X535455Y440455D01*
G02X538425Y433285I-7170J-7170D01*
G01Y392124D01*
G03X538542Y391841I401J0D01*
G01X538883Y391500D01*
G02X539000Y391217I-284J-283D01*
G01Y390100D01*
G01X578738Y1008860D02*
Y1000671D01*
G03X578972Y1000106I799J0D01*
G01X579844Y999234D01*
G02X580078Y998669I-565J-565D01*
G01Y671265D01*
G02X574603Y658047I-18693J0D01*
G01X549505Y632949D01*
X547555Y631000D01*
X510830Y594275D01*
G03X507500Y586234I8041J-8040D01*
G01Y469480D01*
G03X509607Y464393I7195J0D01*
G01X534500Y439500D01*
G02X537075Y433284I-6215J-6216D01*
G01Y392124D01*
G02X536958Y391841I-401J0D01*
G01X536617Y391500D01*
G03X536500Y391217I284J-283D01*
G01Y390100D01*
G01X562993Y1008860D02*
Y1000247D01*
G03X563178Y999800I632J0D01*
G03X563419Y999700I241J241D01*
G01X563845D01*
G02X564291Y999499I-1J-597D01*
G01X564442Y999330D01*
G02X564628Y998819I-613J-512D01*
G01Y921936D01*
G03X566493Y917433I6368J0D01*
G01X566678Y917248D01*
G02X568814Y912091I-5157J-5157D01*
G01Y666818D01*
G02X565527Y658881I-11224J-1D01*
G01X564580Y657935D01*
X502724Y596079D01*
G03X500750Y591309I4769J-4767D01*
G01Y465298D01*
G03X500937Y463819I5935J-1D01*
G03X502488Y461102I5748J1480D01*
G01X528021Y435569D01*
G02X530155Y430417I-5152J-5152D01*
G01Y391549D01*
G02X529555Y390100I-2049J0D01*
G01X566928Y1008860D02*
Y1001057D01*
G02X566428Y999850I-1707J0D01*
G03X566151Y999472I1086J-1086D01*
G03X566016Y999106I1362J-710D01*
G03X565978Y998764I1498J-340D01*
G01Y990189D01*
G03X566448Y989249I1140J-18D01*
G02X566918Y988309I-670J-923D01*
G01Y987109D01*
G02X566448Y986169I-1140J-18D01*
G03X565978Y985229I670J-923D01*
G01Y984029D01*
G03X566448Y983089I1140J-18D01*
G02X566918Y982149I-670J-923D01*
G01Y980949D01*
G02X566448Y980009I-1140J-18D01*
G03X565978Y979069I670J-923D01*
G01Y966152D01*
G03X566448Y965212I1140J-18D01*
G02X566918Y964272I-670J-923D01*
G01Y963072D01*
G02X566448Y962132I-1140J-18D01*
G03X565978Y961192I670J-923D01*
G01Y959992D01*
G03X566448Y959052I1140J-18D01*
G02X566918Y958112I-670J-923D01*
G01Y956912D01*
G02X566448Y955972I-1140J-18D01*
G03X565978Y955032I670J-923D01*
G01Y953832D01*
G03X566448Y952892I1140J-18D01*
G02X566918Y951952I-670J-923D01*
G01Y950752D01*
G02X566448Y949812I-1140J-18D01*
G03X565978Y948872I670J-923D01*
G01Y921935D01*
X565979Y921936D01*
G03X567448Y918388I5018J-1D01*
G01X567633Y918203D01*
G02X570156Y912478I-6112J-6112D01*
G02X570164Y912121I-7970J-357D01*
G01Y666818D01*
G02X568761Y661044I-12575J-2D01*
G02X566482Y657926I-11171J5773D01*
G01X503679Y595124D01*
G03X502100Y591310I3814J-3813D01*
G01Y465299D01*
G03X502245Y464156I4585J1D01*
G03X503443Y462057I4440J1143D01*
G01X528976Y436524D01*
G02X531505Y430417I-6107J-6106D01*
G01Y391428D01*
G03X532055Y390100I1878J0D01*
G01X519283Y318377D02*
Y317177D01*
G02X518883Y316777I-400J0D01*
G01X518858D01*
G03X518458Y316377I0J-400D01*
G01Y315000D01*
G03X519458Y314000I1000J0D01*
G01X519706D01*
G01X516283Y318377D02*
Y317177D01*
G03X516683Y316777I400J0D01*
G01X516708D01*
G02X517108Y316377I0J-400D01*
G01Y315000D01*
X516283Y314175D01*
G02X515860Y314000I-423J424D01*
G01X521623Y324783D02*
X522740D01*
G03X523023Y324900I0J401D01*
G01X523364Y325241D01*
G02X523647Y325358I283J-284D01*
G01X524120D01*
G02X524500Y324978I0J-380D01*
G01Y320677D01*
G02X524383Y320394I-401J0D01*
G01X523348Y319359D01*
G01X517123Y332283D02*
X518240D01*
G03X518523Y332400I0J401D01*
G01X518864Y332741D01*
G02X519147Y332858I283J-284D01*
G01X519620D01*
G03X522185Y333920I1J3627D01*
G01X522510Y334245D01*
G02X523004Y334450I494J-494D01*
G01X532238D01*
G02X533802Y333802I0J-2212D01*
G01X535422Y332182D01*
G02X536112Y330516I-1666J-1666D01*
G01Y323000D01*
G02X535512Y321553I-2047J1D01*
G01X534960Y321000D01*
G01X517123Y334783D02*
X518240D01*
G02X518523Y334666I0J-401D01*
G01X518864Y334325D01*
G03X519147Y334208I283J284D01*
G01X519620D01*
G03X521230Y334875I0J2277D01*
G01X521555Y335200D01*
G02X523004Y335800I1449J-1449D01*
G01X532239D01*
G02X534757Y334757I0J-3562D01*
G01X536377Y333137D01*
G02X537462Y330516I-2621J-2620D01*
G01Y323000D01*
G03X538062Y321553I2047J1D01*
G01X538614Y321000D01*
G01X521623Y327283D02*
X522740D01*
G02X523023Y327166I0J-401D01*
G01X523364Y326825D01*
G03X523647Y326708I283J284D01*
G01X524120D01*
G02X525850Y324978I0J-1730D01*
G01Y320677D01*
G03X525967Y320394I401J0D01*
G01X527002Y319359D01*
G01X518100Y346000D02*
X519217D01*
G02X519500Y345883I0J-401D01*
G01X519841Y345542D01*
G03X520124Y345425I283J284D01*
G01X525000D01*
G03X525671Y345703I0J949D01*
G01X526500Y346532D01*
G01X518100Y343500D02*
X519217D01*
G03X519500Y343617I0J401D01*
G01X519841Y343958D01*
G02X520124Y344075I283J-284D01*
G01X525197D01*
G02X525533Y343936I0J-476D01*
G01X526500Y342969D01*
G01X518100Y351000D02*
X519293D01*
G03X520500Y351500I0J1707D01*
G01X518100Y348500D02*
X519141D01*
G02X520500Y347937I0J-1922D01*
G01X518100Y359500D02*
X519141D01*
G02X520500Y358937I0J-1922D01*
G01X518100Y356000D02*
X519217D01*
G02X519500Y355883I0J-401D01*
G01X519841Y355542D01*
G03X520124Y355425I283J284D01*
G01X525227D01*
G03X525510Y355542I0J401D01*
G01X526500Y356532D01*
G01X518100Y362000D02*
X519293D01*
G03X520500Y362500I0J1707D01*
G01X518100Y353500D02*
X519217D01*
G03X519500Y353617I0J401D01*
G01X519841Y353958D01*
G02X520124Y354075I283J-284D01*
G01X525228D01*
G02X525511Y353958I0J-401D01*
G01X526500Y352969D01*
G01X527623Y330283D02*
X528740D01*
G03X529023Y330400I0J401D01*
G01X529364Y330741D01*
G02X529647Y330858I283J-284D01*
G01X530120D01*
G02X531000Y329978I0J-880D01*
G01Y326818D01*
G02X530883Y326535I-401J0D01*
G01X529848Y325500D01*
G01X527623Y332783D02*
X528740D01*
G02X529023Y332666I0J-401D01*
G01X529364Y332325D01*
G03X529647Y332208I283J284D01*
G01X530120D01*
G02X532350Y329978I0J-2230D01*
G01Y326818D01*
G03X532467Y326535I401J0D01*
G01X533502Y325500D01*
G01X1091750Y93250D02*
X1092400Y92600D01*
Y87700D01*
G01X1133996Y709607D02*
X1136516D01*
X1137657Y708466D01*
X1138034D01*
X1138500Y708000D01*
X1140460D01*
X1140710Y707750D01*
G01X1140544Y778485D02*
X1140558D01*
X1142323Y780250D01*
G01X1143693Y778485D02*
Y779215D01*
X1144023Y779545D01*
Y780955D01*
X1143470Y781508D01*
Y782805D01*
G01X1149992Y791083D02*
X1151392Y789683D01*
X1153417D01*
X1154200Y788900D01*
G01X1165492Y722205D02*
X1167000Y723713D01*
Y727500D01*
G01X1159192Y725355D02*
X1159692Y725855D01*
Y729669D01*
X1157659Y731702D01*
X1157112D01*
G01X1165492Y725355D02*
Y726008D01*
X1165400Y726100D01*
Y728163D01*
X1166337Y729100D01*
X1168674D01*
X1169282Y729708D01*
G01X1159192Y722205D02*
X1161042Y724055D01*
Y730229D01*
X1157000Y734271D01*
Y734500D01*
G01X1152893Y722205D02*
Y723445D01*
X1154300Y724852D01*
Y728352D01*
X1152248Y730404D01*
G01X1152893Y725355D02*
X1152950Y725412D01*
Y726850D01*
X1152400Y727400D01*
Y727600D01*
G01X1162591Y778485D02*
Y780763D01*
X1162693Y780865D01*
G01X1165740Y778485D02*
Y778552D01*
X1165400Y778892D01*
Y780865D01*
X1165492Y780957D01*
G01X1153142Y791083D02*
X1154283D01*
X1154700Y791500D01*
Y792678D01*
X1154712Y792690D01*
G54D60*
X184200Y861000D03*
X187700Y852000D03*
X188200Y874000D03*
X209700Y816500D03*
X452629Y101500D03*
X596598Y426116D03*
Y431116D03*
Y441116D03*
Y436116D03*
Y451116D03*
Y446116D03*
X670948Y56500D03*
Y63500D03*
X719400Y202000D03*
X763974Y441078D03*
X846700Y720000D03*
X870168Y709784D03*
X1038700Y105500D03*
Y111000D03*
X1100700Y780500D03*
X1147100Y604700D03*
X1249200Y716000D03*
X1287700Y363000D03*
X1302700Y564500D03*
X1311817Y577412D03*
X1325200Y420000D03*
X1336817Y562412D03*
G54D51*
X152000Y465300D03*
X173943Y537396D03*
X197200Y431500D03*
X190200Y848000D03*
X317193Y450373D03*
X318223Y483783D03*
X333129Y241500D03*
X382700Y947000D03*
X469255Y301500D03*
Y305500D03*
X576700Y66000D03*
Y62000D03*
X628200Y575000D03*
X673786Y107874D03*
X686948Y122500D03*
X691162Y455464D03*
X709700Y568000D03*
X716200Y864000D03*
X771974Y475078D03*
X781700Y355500D03*
X796974Y475078D03*
X819200Y368500D03*
X817700Y849500D03*
X849200Y385000D03*
X846200Y638500D03*
X937650Y448700D03*
X1016700Y277500D03*
Y281500D03*
X1007700Y480500D03*
X1011916Y898468D03*
X1029700Y137000D03*
X1047200Y930000D03*
X1073629Y73758D03*
X1101700Y776500D03*
Y772500D03*
X1092668Y863284D03*
X1139700Y862000D03*
X1198668Y807784D03*
Y804284D03*
X1206700Y432500D03*
X1202200Y753000D03*
X1250200Y699500D03*
X1272200Y564500D03*
X1312817Y603912D03*
X1304700Y855000D03*
Y858500D03*
X1336700Y452000D03*
X1354200D03*
G54D162*
X1283596Y557000D03*
X1273404D03*
G54D117*
X671500Y516250D03*
Y531750D03*
G54D15*
X33554Y844660D03*
Y849780D03*
Y847220D03*
X40054Y844660D03*
Y849780D03*
X201805Y532560D03*
Y530000D03*
Y527440D03*
X208305D03*
Y532560D03*
X201805Y545060D03*
Y542500D03*
Y539940D03*
X208305D03*
Y545060D03*
Y552940D03*
Y555500D03*
Y558060D03*
X201805D03*
Y552940D03*
X721250Y875560D03*
Y870440D03*
X727750D03*
Y873000D03*
Y875560D03*
X782750Y856060D03*
Y853500D03*
Y850940D03*
X789250D03*
Y856060D03*
X839250Y846440D03*
Y849000D03*
Y851560D03*
X832750D03*
Y846440D03*
X832250Y868560D03*
Y866000D03*
Y863440D03*
X838750D03*
Y868560D03*
X865250Y659940D03*
Y662500D03*
X858750Y659940D03*
X865250Y665060D03*
X858750D03*
X932250Y56940D03*
X925750D03*
X932250Y59500D03*
Y62060D03*
X925750D03*
X1003750Y467000D03*
Y464440D03*
Y469560D03*
X1010250Y464440D03*
Y469560D03*
G54D126*
X730940Y205035D03*
X733500D03*
X736060D03*
Y196965D03*
X733500D03*
X730940D03*
G54D135*
X774938Y685354D03*
X777498D03*
X780058D03*
Y692754D03*
X777498D03*
X774938D03*
X868936Y687711D03*
X871496D03*
Y695111D03*
X868936D03*
X874056Y687711D03*
Y695111D03*
X1064208Y201524D03*
X1066768D03*
Y208924D03*
X1064208D03*
X1069328Y201524D03*
Y208924D03*
G54D144*
X1025473Y879350D03*
Y881909D03*
Y884468D03*
Y887027D03*
Y889586D03*
X1044959D03*
Y887027D03*
Y884468D03*
Y881909D03*
Y879350D03*
G54D153*
X1215256Y203150D03*
Y200000D03*
Y196851D03*
Y193701D03*
Y190552D03*
Y218898D03*
Y215748D03*
Y212599D03*
Y209449D03*
Y206300D03*
Y237796D03*
Y234646D03*
Y231496D03*
Y228347D03*
Y225197D03*
Y222048D03*
Y253544D03*
Y250394D03*
Y247245D03*
Y244095D03*
Y240945D03*
Y269292D03*
Y266142D03*
Y262993D03*
Y259843D03*
Y256693D03*
Y285040D03*
Y281890D03*
Y278741D03*
Y275591D03*
Y272441D03*
Y300788D03*
Y297638D03*
Y294489D03*
Y291339D03*
Y288189D03*
Y319685D03*
Y316536D03*
Y313386D03*
Y310237D03*
Y307087D03*
Y303937D03*
Y335434D03*
Y332284D03*
Y329134D03*
Y325985D03*
Y322835D03*
Y351182D03*
Y348032D03*
Y344882D03*
Y341733D03*
Y338583D03*
Y366930D03*
Y363780D03*
Y360630D03*
Y357481D03*
Y354331D03*
Y376378D03*
Y373229D03*
Y370079D03*
X1232776Y203150D03*
Y200000D03*
Y196851D03*
Y193701D03*
Y190552D03*
Y218898D03*
Y215748D03*
Y212599D03*
Y209449D03*
Y206300D03*
Y237796D03*
Y234646D03*
Y231496D03*
Y228347D03*
Y225197D03*
Y222048D03*
Y253544D03*
Y250394D03*
Y247245D03*
Y244095D03*
Y240945D03*
Y269292D03*
Y266142D03*
Y262993D03*
Y259843D03*
Y256693D03*
Y285040D03*
Y281890D03*
Y278741D03*
Y275591D03*
Y272441D03*
Y300788D03*
Y297638D03*
Y294489D03*
Y291339D03*
Y288189D03*
Y319685D03*
Y316536D03*
Y313386D03*
Y310237D03*
Y307087D03*
Y303937D03*
Y335434D03*
Y332284D03*
Y329134D03*
Y325985D03*
Y322835D03*
Y351182D03*
Y348032D03*
Y344882D03*
Y341733D03*
Y338583D03*
Y366930D03*
Y363780D03*
Y360630D03*
Y357481D03*
Y354331D03*
Y376378D03*
Y373229D03*
Y370079D03*
G54D171*
X1336743Y581762D03*
Y605062D03*
X1352491Y581762D03*
Y605062D03*
G54D42*
X110234Y1009860D03*
X133859D03*
X129919D03*
X125984D03*
X122049D03*
X118109D03*
X145669D03*
X149604D03*
X165354D03*
X161419D03*
X157479D03*
X153544D03*
X181104D03*
X177164D03*
X173229D03*
X169289D03*
X185039D03*
X279528D03*
X275588D03*
X267718D03*
X295273D03*
X291338D03*
X287403D03*
X283463D03*
X311023D03*
X307088D03*
X303148D03*
X299213D03*
X330708D03*
X326773D03*
X322833D03*
X318898D03*
X314958D03*
X346458D03*
X342518D03*
X338583D03*
X334643D03*
X362203D03*
X358268D03*
X354333D03*
X350393D03*
X377953D03*
X374018D03*
X370078D03*
X366143D03*
X393703D03*
X389763D03*
X385828D03*
X381888D03*
X409448D03*
X405513D03*
X401573D03*
X397638D03*
X429133D03*
X425198D03*
X421258D03*
X417323D03*
X413388D03*
X444883D03*
X440943D03*
X437008D03*
X433073D03*
X460628D03*
X456693D03*
X452758D03*
X448818D03*
X476378D03*
X472443D03*
X468503D03*
X464568D03*
X492128D03*
X488188D03*
X484253D03*
X480313D03*
X507873D03*
X503938D03*
X499998D03*
X496063D03*
X527558D03*
X523623D03*
X519683D03*
X515748D03*
X511813D03*
X543308D03*
X539368D03*
X535433D03*
X531498D03*
X559053D03*
X555118D03*
X574803D03*
X570868D03*
X566928D03*
X562993D03*
X590553D03*
X586613D03*
X582678D03*
X578738D03*
X594488D03*
X719683D03*
X739368D03*
X735433D03*
X731498D03*
X727558D03*
X755118D03*
X743308D03*
X770868D03*
X766928D03*
X762993D03*
X759053D03*
X790553D03*
X786613D03*
X782678D03*
X778738D03*
X774803D03*
X794488D03*
G54D108*
X599941Y70118D03*
X607933D03*
X595905Y80118D03*
X603897D03*
X611889D03*
X615925Y70118D03*
X623917D03*
X627953Y80118D03*
X631909Y70118D03*
X639901D03*
X635945Y80118D03*
X643937D03*
G54D33*
X59787Y669714D03*
X61362D03*
X62937D03*
X64512D03*
X66087D03*
Y691914D03*
X64512D03*
X62937D03*
X61362D03*
X59787D03*
X67662Y669714D03*
X69232D03*
X70807D03*
X72382D03*
X73957D03*
X75532D03*
X77107D03*
Y691914D03*
X75532D03*
X73957D03*
X72382D03*
X70807D03*
X69232D03*
X67662D03*
X94587Y669714D03*
X96162D03*
X97737D03*
X99312D03*
Y691914D03*
X97737D03*
X96162D03*
X94587D03*
X100887Y669714D03*
X102462D03*
X104032D03*
X105607D03*
X107182D03*
X108757D03*
X110332D03*
X111907D03*
Y691914D03*
X110332D03*
X108757D03*
X107182D03*
X105607D03*
X104032D03*
X102462D03*
X100887D03*
X323395Y517900D03*
X324970D03*
X326545D03*
X328120D03*
X329695D03*
Y540100D03*
X328120D03*
X326545D03*
X324970D03*
X323395D03*
X331270Y517900D03*
X332840D03*
X334415D03*
X335990D03*
X337565D03*
X339140D03*
X340715D03*
Y540100D03*
X339140D03*
X337565D03*
X335990D03*
X334415D03*
X332840D03*
X331270D03*
X347738Y517994D03*
X349313D03*
X350888D03*
X352463D03*
X354038D03*
X355613D03*
X357183D03*
X358758D03*
X360333D03*
X361908D03*
Y540194D03*
X360333D03*
X358758D03*
X357183D03*
X355613D03*
X354038D03*
X352463D03*
X350888D03*
X349313D03*
X347738D03*
X363483Y517994D03*
X365058D03*
Y540194D03*
X363483D03*
G54D24*
G01X-245081Y-422119D02*
G02I-12000J0D01*
G01X-250231D02*
G02I-6850J0D01*
G01X-241081D02*
X-273081D01*
G01X-257081Y-438119D02*
Y-406119D01*
G01X-241081Y-438119D02*
Y-518119D01*
G01D02*
X1034819D01*
G01X-241081Y-473619D02*
X1034819D01*
G01X-241081Y-438119D02*
X1034819D01*
G01X23054Y845220D02*
X10533D01*
X8442Y847311D01*
G01X23054Y849720D02*
X15944D01*
X15523Y849778D01*
X15522Y849779D01*
X11800Y853500D01*
X8000D01*
G01X48820Y422933D02*
Y412435D01*
G01X55304Y753970D02*
X50304Y758970D01*
Y771220D01*
X51804Y772720D01*
Y823502D01*
X55022Y826720D01*
G01X40054Y829345D02*
Y823970D01*
G01X65804Y839970D02*
X65554Y840220D01*
X59304D01*
X56804Y842720D01*
X51554D01*
G01X48054Y849720D02*
Y847470D01*
X51554Y843970D01*
Y842720D01*
G01Y849720D02*
X55304D01*
G01X38804Y890470D02*
X42054D01*
X42554Y890970D01*
Y891720D01*
G01X38804Y901970D02*
Y906220D01*
G01X39804Y931220D02*
X41054Y932470D01*
X43804D01*
G01X39804Y937220D02*
Y938304D01*
X41500Y940000D01*
Y941500D01*
G01X43804Y935970D02*
X45000Y937166D01*
Y943000D01*
X46500Y944500D01*
G01X58268Y422933D02*
X57877Y422542D01*
Y412878D01*
X58270Y412485D01*
G01X67717Y422933D02*
Y412520D01*
X67715Y412518D01*
G01X58804Y710220D02*
Y714470D01*
G01X63304D02*
Y706720D01*
G01X62304Y783720D02*
X68304Y777720D01*
Y770720D01*
X72554Y766470D01*
X73804D01*
G01X66804Y785220D02*
X71804Y780220D01*
X102804D01*
X106404Y776620D01*
Y765570D01*
X103804Y762970D01*
G01X55054Y830720D02*
X55022Y830688D01*
Y826720D01*
G01X66054Y830720D02*
X66022Y830688D01*
Y827254D01*
G01X65804Y835720D02*
Y839970D01*
G01X76804Y714470D02*
Y710220D01*
G01X81304Y714470D02*
Y710220D01*
G01X77804Y769970D02*
Y773720D01*
G01X71804Y793970D02*
Y789720D01*
G01X89054Y806720D02*
X86804D01*
X84804Y808720D01*
G01X89054Y811220D02*
X87304D01*
X84804Y808720D01*
G01X78804Y839970D02*
Y836696D01*
X79000Y836500D01*
G01X69804Y839970D02*
Y835720D01*
G01X104554Y844220D02*
Y842970D01*
X93584Y832000D01*
X77500D01*
G01X81304Y884470D02*
X85304D01*
G01X78054Y885720D02*
X80054D01*
X81304Y884470D01*
G01X85304Y887970D02*
X82754D01*
X81804Y888920D01*
G01Y888720D02*
Y888920D01*
G01X78054Y889720D02*
X80304D01*
X80804Y889220D01*
X81504D01*
X81804Y888920D01*
G01X99536Y762976D02*
X96560D01*
X96060Y762476D01*
G01X100772Y771254D02*
X100804Y771286D01*
Y774720D01*
G01X96772Y767754D02*
X100772D01*
G01X89054Y815220D02*
X86804D01*
X85804Y816220D01*
G01X92304Y839970D02*
Y835720D01*
G01X87804Y839970D02*
Y835720D01*
G01X98304Y888220D02*
X99054Y887470D01*
Y882720D01*
G01X97500Y931000D02*
X98970Y932470D01*
X101804D01*
G01X97500Y937000D02*
Y940416D01*
X97804Y940720D01*
G01X113779Y309203D02*
Y313328D01*
X112654Y314453D01*
G01X116404Y316453D02*
X114654D01*
X112654Y314453D01*
G01X102304Y890470D02*
Y895220D01*
G01X101804Y932470D02*
Y929720D01*
X103304Y928220D01*
G01X101804Y935970D02*
Y940720D01*
G01X127654Y297953D02*
Y293453D01*
G01X136250Y312000D02*
X135750Y312500D01*
X132500D01*
G01X127654Y312203D02*
Y312846D01*
X124500Y316000D01*
G01X130000Y666500D02*
X135250D01*
G01D02*
X134000Y667750D01*
Y671250D01*
G01X141750Y283500D02*
X145500D01*
G01X135316Y306093D02*
Y309066D01*
X136250Y310000D01*
Y312000D01*
G01X152050Y469800D02*
X149300D01*
X147500Y471600D01*
Y472100D01*
G01X153200Y660400D02*
X149800D01*
X149100Y661100D01*
G01X147375Y673250D02*
X145520D01*
X143010Y675760D01*
Y676400D01*
G01X147375Y688460D02*
X151460D01*
X153275Y690275D01*
X153500D01*
G01X143500Y706250D02*
Y710500D01*
G01X160000Y465500D02*
X159800Y465300D01*
X155550D01*
G01X158500Y461500D02*
X154399D01*
X152050Y463849D01*
Y465300D01*
G01X153805Y530000D02*
Y535309D01*
X151255Y537859D01*
Y547255D01*
X154290Y550290D01*
X154625D01*
G01X168495Y516875D02*
X163290Y522080D01*
X163225D01*
G01X159805Y550500D02*
X154835D01*
X154625Y550290D01*
G01X155680Y543750D02*
Y540395D01*
X154755Y539470D01*
Y539310D01*
G01X157750Y662250D02*
Y666500D01*
G01D02*
X157650Y666400D01*
X153200D01*
G01D02*
Y670450D01*
X153500Y670750D01*
G01X172000Y666500D02*
Y668125D01*
X166875Y673250D01*
G01X163000Y706250D02*
Y710500D01*
G01X152750Y844000D02*
Y840250D01*
X152500Y840000D01*
G01X186800Y467050D02*
X184050D01*
X182800Y465800D01*
G01Y471300D02*
X183550Y470550D01*
X186800D01*
G01X177493Y537396D02*
Y533493D01*
G01X179743Y544096D02*
Y539646D01*
X177493Y537396D01*
G01X173993D02*
X170339D01*
G01X185000Y533562D02*
X181993Y536569D01*
Y537396D01*
G01X179743Y554696D02*
Y559688D01*
X180555Y560500D01*
G01X181055Y569500D02*
X175055D01*
G01X166875Y678285D02*
Y673250D01*
G01Y688960D02*
X172040D01*
G01X179500Y843500D02*
Y847000D01*
G01X184000Y861000D02*
X180750D01*
X179500Y862250D01*
G01X179000Y851500D02*
X179500Y851000D01*
Y847000D01*
G01X197250Y431500D02*
X192500D01*
G01X190800Y467050D02*
Y462800D01*
G01X186800Y470550D02*
X190800D01*
G01X185305Y525500D02*
Y521100D01*
G01X189555Y570250D02*
Y573445D01*
X189500Y573500D01*
G01X190118Y734957D02*
Y739409D01*
G01D02*
Y743861D01*
G01X185666Y739409D02*
X190118D01*
G01D02*
X194570D01*
G01X195666D02*
X200118D01*
G01X198250Y789125D02*
Y785250D01*
X198000Y785000D01*
G01X198250Y803125D02*
X191875D01*
G01X190250Y844000D02*
X188500D01*
X186000Y841500D01*
G01X190250Y840000D02*
X187500D01*
X186000Y841500D01*
G01X185000Y856000D02*
X184000Y857000D01*
Y861000D01*
G01X190250Y856500D02*
X185500D01*
X185000Y856000D01*
G01X190250Y848000D02*
X185760D01*
X185500Y848260D01*
G01X187500Y852000D02*
X185500Y850000D01*
Y848260D01*
G01X190250Y865500D02*
Y861250D01*
X190000Y861000D01*
G01X190750Y878500D02*
X187500D01*
X187000Y878000D01*
G01X188000Y874000D02*
X187000Y875000D01*
Y878000D01*
G01X190250Y865500D02*
X190750Y865000D01*
X194250D01*
X194500Y864750D01*
G01D02*
X199750D01*
G01X190750Y869500D02*
X190000Y868750D01*
Y865750D01*
X190250Y865500D01*
G01X199000Y887250D02*
Y891500D01*
G01X190500Y890000D02*
Y894000D01*
G01X195000Y887250D02*
Y891500D01*
G01X200750Y431500D02*
Y422250D01*
X200000Y421500D01*
G01X216500Y434750D02*
X212750D01*
X212500Y435000D01*
G01X207773Y521183D02*
Y516562D01*
G01X215666Y739409D02*
X220118D01*
G01X210118Y734957D02*
Y739409D01*
G01D02*
Y743861D01*
G01X205666Y739409D02*
X210118D01*
G01D02*
X214570D01*
G01X200118Y734957D02*
Y739409D01*
G01D02*
Y743861D01*
G01Y739409D02*
X204570D01*
G01X212500Y790500D02*
Y786000D01*
G01Y801500D02*
X218000D01*
G01X212500Y796500D02*
Y801500D01*
G01X209500Y816500D02*
X205500D01*
X204500Y817500D01*
G01X207200Y823000D02*
Y820200D01*
X204500Y817500D01*
G01X210000Y829250D02*
X206250D01*
X205500Y830000D01*
G01X199750Y864750D02*
X205250D01*
G01X218500Y874547D02*
X216000Y877047D01*
Y879500D01*
G01Y887250D02*
Y887500D01*
X212000Y891500D01*
G01Y887250D02*
Y891500D01*
G01X219114Y911564D02*
Y896002D01*
X216562Y893450D01*
X216500D01*
X214550Y891500D01*
X212000D01*
G01X203500Y890000D02*
Y894000D01*
G01X208000Y887250D02*
Y892000D01*
G01X216500Y431250D02*
Y421500D01*
G01X237250Y423000D02*
X234500D01*
X232500Y425000D01*
G01X237250Y427000D02*
X234500D01*
X232500Y425000D01*
G01X230118Y724957D02*
Y729409D01*
G01D02*
Y733861D01*
G01X225666Y729409D02*
X230118D01*
G01D02*
X234570D01*
G01X220118Y734957D02*
Y739409D01*
G01D02*
Y743861D01*
G01Y739409D02*
X224570D01*
G01X230118Y734957D02*
Y739409D01*
G01D02*
Y743861D01*
G01X225666Y739409D02*
X230118D01*
G01D02*
X234570D01*
G01X220500Y890000D02*
Y892000D01*
X222000Y893500D01*
Y893600D01*
G01X216000Y879500D02*
Y883750D01*
G01X220500Y884000D02*
X220250Y883750D01*
X216000D01*
G01X247319Y-438119D02*
Y-518119D01*
G01X237250Y431000D02*
X232500D01*
G01X237250Y419000D02*
X232500D01*
G01X238455Y565850D02*
X242150D01*
X242500Y565500D01*
G01X240118Y734957D02*
Y739409D01*
G01D02*
Y743861D01*
G01X235666Y739409D02*
X240118D01*
G01D02*
X244570D01*
G01X245666D02*
X250118D01*
G01X246750Y835500D02*
X251000D01*
G01X236500Y829250D02*
X240000D01*
G01X247250Y855500D02*
X251500D01*
G01X247250Y847500D02*
X251000D01*
X252000Y846500D01*
G01Y859500D02*
X247250D01*
G01Y851500D02*
X252500D01*
G01X243750Y855500D02*
Y851500D01*
G01X250362Y865000D02*
X248750D01*
X247250Y863500D01*
G01X233000Y867500D02*
X238500Y873000D01*
X277000D01*
X281000Y877000D01*
Y882500D01*
G01X260909Y430178D02*
Y434678D01*
G01X250000Y707250D02*
X253500D01*
G01X260118Y724957D02*
Y729409D01*
G01D02*
Y733861D01*
G01X255666Y729409D02*
X260118D01*
G01D02*
X264570D01*
G01X260118Y734957D02*
Y739409D01*
G01D02*
Y743861D01*
G01X255666Y739409D02*
X260118D01*
G01D02*
X264570D01*
G01X250118Y734957D02*
Y739409D01*
G01D02*
Y743861D01*
G01Y739409D02*
X254570D01*
G01X252300Y841500D02*
Y846200D01*
X252000Y846500D01*
G01X258000Y859500D02*
X259500D01*
X261500Y857500D01*
G01X252000Y859500D02*
Y861500D01*
X253500Y863000D01*
Y863337D01*
X253610Y863447D01*
G01X259000Y894000D02*
X264000D01*
X265000Y893000D01*
G01X265500Y897750D02*
Y893500D01*
X265000Y893000D01*
G01X271653Y985475D02*
X262178Y976000D01*
G01X267718Y987398D02*
X261360Y981040D01*
X261178D01*
G01X270500Y214750D02*
Y217600D01*
X268300Y219800D01*
G01X266500Y214750D02*
Y218000D01*
X268300Y219800D01*
G01X270118Y724957D02*
Y729409D01*
G01D02*
Y733861D01*
G01X265666Y729409D02*
X270118D01*
G01D02*
X274570D01*
G01X270118Y734957D02*
Y739409D01*
G01D02*
Y743861D01*
G01X265666Y739409D02*
X270118D01*
G01D02*
X274570D01*
G01X271500Y893500D02*
Y888500D01*
G01D02*
X272750Y887250D01*
Y884500D01*
G01X281000Y882500D02*
Y892250D01*
X277500Y895750D01*
G01Y899250D02*
Y902800D01*
G01X269000Y910000D02*
X274000D01*
G01X265500Y901250D02*
X270250D01*
X271500Y902500D01*
G01D02*
Y905500D01*
X269000Y908000D01*
Y910000D01*
G01X277500Y902800D02*
X277200Y902500D01*
X271500D01*
G01X269000Y916000D02*
Y921500D01*
G01X274000Y916000D02*
Y921500D01*
G01X271653Y1007910D02*
Y985475D01*
G01X267718Y1008860D02*
Y987398D01*
G01X275588Y1008860D02*
Y992912D01*
G01X299129Y342000D02*
X293929D01*
G01X287403Y1008860D02*
Y997225D01*
X285678Y995500D01*
G01X291338Y1008860D02*
Y997340D01*
X293178Y995500D01*
G01X311500Y81500D02*
X306600D01*
G01X305000Y91250D02*
Y93000D01*
X314000Y102000D01*
Y102500D01*
G01X309500Y91750D02*
X312550Y94800D01*
X314119D01*
X315619Y96300D01*
X316119D01*
X316219Y96400D01*
X317660D01*
G01X317243Y454373D02*
X317041D01*
X317001Y454333D01*
X313444D01*
X313404Y454373D01*
X304608D01*
X299395Y449160D01*
G01X317243Y450373D02*
X308078D01*
X303545Y445840D01*
G01X312555Y442750D02*
X306635D01*
X303545Y445840D01*
G01X318555Y443800D02*
X317505Y442750D01*
X312555D01*
G01X317273Y464283D02*
X314648D01*
X312925Y462560D01*
G01X317273Y459783D02*
X315702D01*
X312925Y462560D01*
G01X318273Y483783D02*
X300112D01*
G01X318273Y479783D02*
X298662D01*
G01X312773Y497183D02*
X306672D01*
X306155Y497700D01*
G01X312773Y529878D02*
Y524683D01*
G01D02*
X306072D01*
X305555Y525200D01*
G01X303148Y1008860D02*
Y997470D01*
X301178Y995500D01*
G01X307088Y1008860D02*
Y998090D01*
X309678Y995500D01*
G01X333179Y241500D02*
X329929D01*
G01X332829Y248400D02*
Y247900D01*
X329929Y245000D01*
Y241500D01*
G01X336429Y349300D02*
X328429D01*
G01D02*
X322429D01*
G01X317195Y493280D02*
X321773Y488702D01*
Y483783D01*
G01X318273Y475283D02*
Y479783D01*
G01X316273Y497183D02*
X320238D01*
G01X324555Y506750D02*
X328555D01*
G01D02*
X333865D01*
X336445Y509330D01*
G01X324555Y510250D02*
X328555D01*
G01X317255Y514170D02*
X318865D01*
X322785Y510250D01*
X324555D01*
G01X316273Y507683D02*
X320338D01*
G01X316273Y524683D02*
Y520282D01*
G01X321023Y548533D02*
X325023D01*
G01X315725Y549790D02*
X316982Y548533D01*
X321023D01*
G01X325023Y552033D02*
X321023D01*
G01D02*
X318432D01*
X317174Y553291D01*
X316824D01*
X315135Y554980D01*
G01X322833Y1008860D02*
Y997345D01*
X324678Y995500D01*
G01X318898Y1008860D02*
Y997220D01*
X317178Y995500D01*
G01X343000Y77500D02*
Y73500D01*
G01X337900Y73100D02*
X338500Y72500D01*
X342000D01*
X343000Y73500D01*
G01X344679Y241500D02*
X346404Y243225D01*
Y260000D01*
G01X341029Y262600D02*
X343804D01*
X346404Y260000D01*
G01X336375Y452870D02*
X339405Y449840D01*
X339505D01*
G01X347023Y506033D02*
X339742D01*
X336445Y509330D01*
G01X343688Y509533D02*
X347023D01*
G01X332500Y935600D02*
X334100D01*
X335000Y936500D01*
X339500D01*
G01X333500Y949850D02*
Y954000D01*
G01X338583Y1008860D02*
Y998595D01*
X341178Y996000D01*
G01X334643Y1008860D02*
Y997465D01*
X332678Y995500D01*
G01X359773Y463783D02*
X362668D01*
X364185Y465300D01*
Y468280D01*
X364015Y468450D01*
G01X358773Y473783D02*
Y478283D01*
G01X367022Y482783D02*
X358773D01*
G01D02*
Y478283D01*
G01X364015Y468450D02*
X359685D01*
G01X358773Y486783D02*
X369272D01*
X373555Y482500D01*
G01X362210Y876200D02*
X363500Y874910D01*
X363750D01*
X365410Y873250D01*
X367500D01*
G01X350393Y1008860D02*
Y997715D01*
X348678Y996000D01*
G01X391055Y299250D02*
Y296760D01*
X388295Y294000D01*
X378526D01*
X375255Y297271D01*
Y297412D01*
X374345Y298322D01*
Y311040D01*
X375805Y312500D01*
G01Y321500D02*
X374055D01*
X372055Y319500D01*
G01X375805Y317000D02*
X374555D01*
X372055Y319500D01*
G01X375805Y330500D02*
X370555D01*
X366055Y326000D01*
Y317000D01*
X370555Y312500D01*
X375805D01*
G01Y326000D02*
X373055D01*
X369555Y322500D01*
G01X375805Y335000D02*
Y339500D01*
G01Y330500D02*
Y335000D01*
G01Y348500D02*
X373055D01*
X372055Y347500D01*
X371555D01*
G01X375805Y353000D02*
X371555D01*
X370555Y352000D01*
Y348500D01*
X371555Y347500D01*
G01X375805Y344000D02*
X368555D01*
X367055Y345500D01*
Y359000D01*
X372055Y364000D01*
G01X375805Y339500D02*
Y344000D01*
G01Y362000D02*
Y357500D01*
G01Y366500D02*
X374555D01*
X372055Y364000D01*
G01D02*
X374055Y362000D01*
X375805D01*
G01Y380250D02*
Y375500D01*
G01D02*
Y371000D01*
G01X376773Y387783D02*
X372055D01*
X371914Y387924D01*
X371781D01*
G01X375055Y435500D02*
Y444500D01*
G01Y467500D02*
Y468640D01*
X378255Y471840D01*
G01X380555Y467500D02*
Y469540D01*
X378255Y471840D01*
G01X384500Y870250D02*
X381750D01*
X380000Y872000D01*
G01X367500Y869750D02*
X364250D01*
X364000Y869500D01*
G01X375500Y918750D02*
X372301D01*
X372300Y918749D01*
G01X383500Y938500D02*
Y939500D01*
X380000Y943000D01*
G01X382750Y947000D02*
Y945750D01*
X380000Y943000D01*
G01X384819Y-438119D02*
Y-518119D01*
G01X388429Y252000D02*
X390960D01*
X393929Y249031D01*
Y248757D01*
X394500Y248186D01*
Y247757D01*
X394929Y247328D01*
Y247000D01*
G01X398750Y265400D02*
Y266482D01*
X398729Y266551D01*
Y267771D01*
X396700Y269800D01*
Y271400D01*
G01X395555Y299250D02*
Y295500D01*
X398385Y292670D01*
Y292540D01*
G01X391555Y467500D02*
Y468430D01*
X388885Y471100D01*
G01X386055Y467500D02*
Y468640D01*
X388515Y471100D01*
X388885D01*
G01X389000Y870250D02*
Y868500D01*
X391000Y866500D01*
G01X393500Y870250D02*
X391000Y867750D01*
Y866500D01*
G01X398000Y870250D02*
Y869000D01*
X396000Y867000D01*
X395500D01*
G01X389763Y1008860D02*
Y996085D01*
G01X412729Y251400D02*
Y259400D01*
G01X409929Y245400D02*
Y247329D01*
X412729Y250129D01*
Y251400D01*
G01X405129Y259400D02*
Y251400D01*
G01X414055Y299250D02*
X412753Y296448D01*
Y295198D01*
X412513Y294958D01*
Y294800D01*
G01X410826Y351771D02*
X412737Y349860D01*
X412815D01*
G01X410826Y414764D02*
X408857Y416733D01*
G01X405750Y880500D02*
Y878750D01*
X404500Y877500D01*
Y877300D01*
G01X405750Y885000D02*
X406000D01*
X406500Y885500D01*
X410500D01*
G01X401573Y1008860D02*
Y994573D01*
X401500Y994500D01*
G01X425750Y236500D02*
X425500D01*
X423500Y234500D01*
X420500D01*
G01X420429Y249650D02*
Y246400D01*
G01X424929Y249650D02*
X424650D01*
X421400Y246400D01*
X420429D01*
G01X424929Y264700D02*
Y261150D01*
G01X423005Y279200D02*
Y283200D01*
G01D02*
X419900D01*
X419600Y282900D01*
G01X423005Y275200D02*
Y272006D01*
X422500Y271501D01*
G01X423005Y287200D02*
X422505Y286700D01*
X418400D01*
X416500Y284800D01*
G01X423055Y297250D02*
X422105D01*
X419455Y294600D01*
Y293000D01*
G01X427555Y295250D02*
X430050D01*
X430750Y294550D01*
X430900D01*
G01X414763Y351771D02*
X414784D01*
X416615Y349940D01*
Y349930D01*
G01X425198Y1008860D02*
Y994698D01*
X425000Y994500D01*
G01X438790Y106000D02*
Y110000D01*
G01Y106000D02*
X434790D01*
X434540Y106250D01*
G01D02*
X433765D01*
X431265Y108750D01*
X430540D01*
G01X437250Y268500D02*
X439000D01*
X440500Y267000D01*
G01X433929Y261150D02*
Y264300D01*
G01X444177Y291000D02*
Y283778D01*
X444255Y283700D01*
G01X438385Y332086D02*
X436416Y330117D01*
G01X446259Y332086D02*
X444290Y330117D01*
G01X430750Y941500D02*
Y945500D01*
G01D02*
Y961750D01*
X430500Y962000D01*
G01X437008Y1008860D02*
Y997330D01*
X435678Y996000D01*
G01X440943Y1008860D02*
Y998235D01*
X443178Y996000D01*
G01X449750Y110000D02*
Y106000D01*
G01X458250Y117500D02*
X457500Y118250D01*
Y121000D01*
G01X449750Y114500D02*
X450750Y115500D01*
Y117750D01*
X450929Y117929D01*
Y118000D01*
G01X455000Y109750D02*
X450000D01*
X449750Y110000D01*
G01D02*
Y114500D01*
G01X459500Y109750D02*
X455000D01*
G01X458555Y293250D02*
X459500Y292305D01*
Y290100D01*
G01X462008Y332086D02*
X463977Y330117D01*
G01X454134Y332086D02*
X456103Y330117D01*
G01X450196Y351771D02*
X448227Y349802D01*
G01X454134Y359645D02*
X456103Y357676D01*
G01X450196Y355708D02*
X448227Y353739D01*
G01X462008Y410827D02*
X461967D01*
X460023Y408883D01*
G01X452758Y1008860D02*
Y998580D01*
X450178Y996000D01*
G01X456693Y1008860D02*
Y996985D01*
X457678Y996000D01*
X458678D01*
G01X466179Y165500D02*
X469339D01*
X469429Y165590D01*
G01X466179Y172500D02*
X469429D01*
G01X466179Y180500D02*
X467179Y179500D01*
X469429D01*
G01X465679Y189500D02*
Y192600D01*
G01X465750Y197000D02*
X474500D01*
X480500Y191000D01*
Y181800D01*
G01X469305Y305500D02*
Y301500D01*
G01D02*
Y297950D01*
X469155Y297800D01*
G01X479923Y306883D02*
X478506Y308300D01*
X474755D01*
G01X479725Y330117D02*
X477756Y332086D01*
G01Y324212D02*
X479468Y322500D01*
X479655D01*
G01X469882Y324212D02*
X471851Y322243D01*
G01X477756Y328149D02*
X477757D01*
X479725Y330117D01*
G01X477756Y336023D02*
X477757D01*
X479725Y337991D01*
G01X469882Y328149D02*
X471851Y326180D01*
G01X475788Y341928D02*
X473819Y343897D01*
G01X465945Y351771D02*
X467914Y349802D01*
G01X477756Y339960D02*
X479725Y337991D01*
G01X473819Y351771D02*
X475788Y349802D01*
G01X473819Y347834D02*
X473820D01*
X475788Y349802D01*
G01X477756Y347834D02*
X475788Y349802D01*
G01X467914D02*
X469882Y347834D01*
G01X473819Y355708D02*
X473820D01*
X475788Y357676D01*
G01X477756Y355708D02*
X475788Y357676D01*
G01X472443Y1008860D02*
Y997235D01*
X474178Y995500D01*
G01X468503Y1008860D02*
Y998325D01*
X466178Y996000D01*
G01X494123Y298683D02*
X497338D01*
X498855Y300200D01*
Y302851D01*
G01X498955Y316900D02*
X496855Y319000D01*
X495155D01*
X493555Y320600D01*
Y324161D01*
X493504Y324212D01*
G01X481693D02*
Y324211D01*
X479982Y322500D01*
X479655D01*
G01X489567Y359645D02*
X489521D01*
X487643Y361523D01*
G01X488188Y1008860D02*
Y996990D01*
X489678Y995500D01*
G01X484253Y1008860D02*
Y997575D01*
X482178Y995500D01*
G01X499819Y-438119D02*
Y-518119D01*
G01X497441Y324212D02*
X499410Y322243D01*
G01X503938Y1008860D02*
Y997240D01*
X505678Y995500D01*
G01X499998Y1008860D02*
Y997320D01*
X498178Y995500D01*
G01X519683Y1008860D02*
Y996995D01*
X521178Y995500D01*
G01X515748Y1008860D02*
Y997570D01*
X513678Y995500D01*
G01X541527Y290355D02*
X545079D01*
G01X549055Y327250D02*
X542350D01*
X539200Y324100D01*
G01X535433Y1008860D02*
Y997245D01*
X536678Y996000D01*
G01X531498Y1008860D02*
Y996915D01*
X530083Y995500D01*
G01X549000Y151250D02*
Y150000D01*
X546500Y147500D01*
G01X559750Y264500D02*
Y252500D01*
G01D02*
Y249250D01*
X559500Y249000D01*
G01X545079Y286803D02*
Y290355D01*
G01X549014Y294678D02*
Y298230D01*
G01D02*
Y301782D01*
G01X545462Y298230D02*
X549014D01*
G01D02*
X552566D01*
G01X545079Y290355D02*
Y293907D01*
G01Y290355D02*
X548631D01*
G01X557055Y327250D02*
X553055D01*
G01D02*
X552955Y327150D01*
Y321600D01*
X553555Y321000D01*
G01X559053Y1008860D02*
Y997625D01*
X560678Y996000D01*
G01X576750Y66000D02*
Y62000D01*
G01D02*
Y58250D01*
X577000Y58000D01*
G01X571000Y151250D02*
X570750D01*
X568500Y149000D01*
Y147500D01*
G01X563250Y252500D02*
Y262500D01*
G01X579882Y269700D02*
X574700D01*
X574000Y269000D01*
G01X567305Y328500D02*
X569805Y326000D01*
X571555D01*
G01X570868Y1008860D02*
Y997690D01*
X569178Y996000D01*
G01X574803Y1008860D02*
Y997875D01*
X576678Y996000D01*
G01X585315Y38832D02*
Y44134D01*
G01X580013D02*
X585315D01*
G01D02*
X590617D01*
G01X591903Y80118D02*
X595905D01*
G01X585000Y256250D02*
X581222Y260028D01*
X580828D01*
G01X586613Y1008860D02*
Y996435D01*
X584678Y994500D01*
G01X599941Y66116D02*
Y70118D01*
G01D02*
Y74120D01*
G01X595939Y70118D02*
X599941D01*
G01X595905Y76116D02*
Y80118D01*
G01D02*
Y84120D01*
G01X600250Y200500D02*
X604500D01*
G01X600250Y205000D02*
X604500D01*
G01X600250Y218500D02*
X603500D01*
G01X600250Y214000D02*
X603500D01*
G01X600250Y209500D02*
X605000D01*
G01X594500Y240250D02*
Y236000D01*
G01X600250Y227500D02*
X604500D01*
G01X600250Y223000D02*
X604500D01*
G01X628250Y579000D02*
X625000D01*
X623500Y577500D01*
Y576500D01*
G01X639901Y70118D02*
X641928D01*
X661376Y89566D01*
Y93464D01*
G01X652714Y436538D02*
X645751D01*
X642800Y433587D01*
G01X644750Y440000D02*
X640113D01*
X638343Y441770D01*
X636500Y443396D01*
Y444800D01*
G01X635750Y453000D02*
Y457075D01*
X635325Y457500D01*
G01X628250Y575000D02*
Y570200D01*
G01Y584000D02*
Y588500D01*
G01D02*
Y591702D01*
X628524Y591976D01*
G01X654527Y38832D02*
Y44134D01*
G01X649225D02*
X654527D01*
G01D02*
X659829D01*
G01X643937Y80118D02*
X655139Y91320D01*
Y91359D01*
X656876Y93096D01*
Y93464D01*
G01X651964Y444288D02*
X655964D01*
G01D02*
X658500D01*
X659288Y443500D01*
X660000D01*
G01X659462Y495464D02*
X655964D01*
X654500Y494000D01*
G01X654300Y490300D02*
X658626D01*
X659462Y489464D01*
G01X667319Y-438119D02*
Y-518119D01*
G01X673916Y94544D02*
X670454D01*
G01X673836Y107874D02*
X670044D01*
X667748Y105578D01*
Y104000D01*
G01X674122Y130182D02*
X671056D01*
X671038Y130200D01*
X670522D01*
G01X675055Y262750D02*
Y261500D01*
X678055Y258500D01*
G01X659462Y489464D02*
Y484214D01*
G01X676748Y52000D02*
Y56500D01*
G01Y63500D02*
Y67048D01*
X684197Y74497D01*
Y74703D01*
G01X690966Y137784D02*
Y142028D01*
G01X687055Y262750D02*
Y258500D01*
G01X683055Y262750D02*
Y258500D01*
G01X679055Y262750D02*
Y259500D01*
X678055Y258500D01*
G01X682968Y762234D02*
Y758284D01*
G01X687968Y759984D02*
Y755284D01*
G01Y776984D02*
Y781784D01*
G01X683218Y802484D02*
X681268D01*
X678468Y805284D01*
G01X683218Y807484D02*
X680668D01*
X678468Y805284D01*
G01X704250Y59500D02*
X701500D01*
X700500Y60500D01*
X700000D01*
G01X704716Y152034D02*
Y156520D01*
G01X700216Y152034D02*
Y156368D01*
G01X706055Y262750D02*
Y258500D01*
G01X694712Y455464D02*
Y452014D01*
X692962Y450264D01*
G01X695500Y460500D02*
X694712Y459712D01*
Y455464D01*
G01X705500Y575600D02*
X705600D01*
X706500Y576500D01*
X709750D01*
G01Y568000D02*
X707100D01*
X705900Y569200D01*
G01X698818Y761634D02*
Y759350D01*
G01X698968Y782734D02*
X702918D01*
G01X706500Y859750D02*
X712500D01*
G01X706500Y863250D02*
X710750D01*
G01X702250Y863500D02*
X702500Y863250D01*
X706500D01*
G01X704000Y888250D02*
Y892500D01*
G01X720032Y53966D02*
X716034D01*
G01X724532D02*
X728966D01*
G01X720032Y65466D02*
X716466D01*
G01X724532D02*
X728966D01*
G01X715716Y87034D02*
Y82652D01*
G01X718216Y152034D02*
Y156520D01*
G01X713716Y152034D02*
Y156520D01*
G01X709216Y152034D02*
Y156520D01*
G01X722716Y152034D02*
Y156520D01*
G01X721200Y205800D02*
X719200Y203800D01*
Y202000D01*
G01X710055Y262750D02*
Y258500D01*
G01X714055Y262750D02*
Y258500D01*
G01X718055Y262750D02*
Y258000D01*
G01X724000Y482250D02*
X728250D01*
X728500Y482500D01*
G01X709750Y582000D02*
Y585200D01*
G01Y576500D02*
Y572000D01*
G01X715468Y754734D02*
X719918D01*
G01X727468Y779734D02*
X725318D01*
X724068Y778484D01*
X717468D01*
X715118Y776134D01*
G01X727968Y774984D02*
X723168D01*
G01X725968Y811234D02*
X717918D01*
X717468Y810784D01*
G01X766750Y849250D02*
X731250D01*
X720500Y860000D01*
G01X719750Y864000D02*
Y860750D01*
X720500Y860000D01*
G01X716250Y864000D02*
Y860250D01*
G01X714000Y867500D02*
Y871250D01*
G01X724250Y864000D02*
X719750D01*
G01X724250Y882500D02*
X717500D01*
X714500Y885500D01*
Y891000D01*
G01X719683Y1008860D02*
Y1000317D01*
X723000Y997000D01*
G01D02*
Y996500D01*
G01X740500Y79250D02*
Y75000D01*
G01X730748Y99500D02*
X729716Y100532D01*
X726282D01*
G01X727216Y152034D02*
Y156520D01*
G01X729748Y180750D02*
X733498D01*
G01X728250Y455500D02*
X732500D01*
G01Y482250D02*
Y485500D01*
G01X742517Y544718D02*
X738117D01*
G01D02*
X736282D01*
X734500Y546500D01*
Y547500D01*
G01X738117Y548218D02*
X742517D01*
G01X737750Y553500D02*
X734462Y553538D01*
G01X727968Y757984D02*
X733268D01*
G01X731468Y779734D02*
X727468D01*
G01X785000Y762000D02*
X781000Y758000D01*
X764500D01*
X758516Y763984D01*
X740768D01*
G01X736218D02*
X740768D01*
G01X735000Y780500D02*
X732266Y783234D01*
X731468D01*
G01D02*
X727468D01*
G01X729218Y801984D02*
X732768D01*
X733768Y800984D01*
Y800734D01*
G01X729218Y797484D02*
X732168D01*
X733768Y799084D01*
Y800734D01*
G01X729468Y811234D02*
X725968D01*
G01X729468Y814734D02*
Y817284D01*
X727468Y819284D01*
G01X725968Y814734D02*
Y817784D01*
X727468Y819284D01*
G01X731498Y1008860D02*
Y996500D01*
G01X743308Y1008860D02*
Y1001308D01*
X739368Y997368D01*
G01D02*
Y996610D01*
G01X754500Y67500D02*
X749300D01*
G01X758750D02*
X754500D01*
G01X757250Y88500D02*
X761000D01*
G01X757250Y82500D02*
X761000D01*
G01X757250Y99500D02*
Y103050D01*
X757200Y103100D01*
G01X760600Y94500D02*
X757250D01*
G01X746716Y123034D02*
X750216D01*
G01D02*
X750682Y123500D01*
X755248D01*
G01X756466Y116784D02*
X760522D01*
G01X759748Y123500D02*
X755248D01*
G01X746716Y126534D02*
Y130238D01*
G01X750216Y126534D02*
Y129708D01*
X750780Y130272D01*
X750916D01*
G01X745500Y148750D02*
Y145000D01*
G01X751623Y179750D02*
X755750D01*
X756000Y180000D01*
G01X749750Y457625D02*
Y454000D01*
G01X753214Y476038D02*
X755764D01*
X757802Y474000D01*
G01X755300Y485000D02*
Y489300D01*
G01X742517Y548218D02*
X742790Y548491D01*
X751484D01*
G01X799250Y546500D02*
Y545500D01*
X796750Y543000D01*
X761500D01*
X756000Y548500D01*
X751493D01*
X751484Y548491D01*
G01D02*
Y540600D01*
G01X746750Y571750D02*
X743000D01*
G01X748000Y579500D02*
X748499Y579999D01*
Y580449D01*
X751300Y583250D01*
X756000D01*
G01X752250Y575500D02*
X752000Y575250D01*
X743000D01*
G01X752250Y575500D02*
X752000Y575750D01*
Y579000D01*
X752750Y579750D01*
X756000D01*
G01X752250Y571000D02*
Y575500D01*
G01Y571000D02*
Y570250D01*
X754757Y567743D01*
X793145D01*
X799250Y561638D01*
Y561000D01*
G01X747750Y698500D02*
X756750Y689500D01*
X771000D01*
G01X762250Y67500D02*
Y71000D01*
G01X765748Y123500D02*
X770000D01*
G01X766250Y138500D02*
X768000D01*
X770500Y136000D01*
G01X766250Y134000D02*
X768500D01*
X770500Y136000D01*
G01X766150Y144300D02*
X770900D01*
G01X769466Y187659D02*
X765116D01*
G01X758000Y448500D02*
X758422Y448078D01*
X763974D01*
G01D02*
Y441278D01*
X763774Y441078D01*
G01X763000Y459250D02*
X760750D01*
X758500Y457000D01*
G01X771000Y459250D02*
Y464000D01*
G01X767000Y475250D02*
Y481257D01*
X767500Y481757D01*
Y482500D01*
X774500Y489500D01*
G01X760500Y484750D02*
Y489500D01*
G01X771484Y563491D02*
X765009D01*
G01X760125Y660750D02*
Y666875D01*
G01X766750Y853500D02*
Y849250D01*
G01Y858000D02*
Y853500D01*
G01X770868Y998632D02*
Y1008860D01*
G01X775748Y184250D02*
Y188500D01*
G01X791500Y442500D02*
X793000Y441000D01*
Y439500D01*
G01X784000Y467758D02*
Y469500D01*
G01X784274Y481578D02*
Y486274D01*
G01X784000Y469500D02*
X784274Y469774D01*
Y475578D01*
G01D02*
X784024Y475328D01*
X779774D01*
G01X786250Y546500D02*
X789500D01*
X790600Y547600D01*
G01X786750Y553500D02*
X789000D01*
X790000Y554500D01*
G01X786750Y561000D02*
X786788Y561038D01*
X790038D01*
X791000Y562000D01*
G01X779250Y644500D02*
X796000D01*
X799000Y647500D01*
Y655500D01*
G01X783034Y662407D02*
Y664034D01*
X785500Y666500D01*
G01X788500Y661750D02*
Y663500D01*
X785500Y666500D01*
G01X784804Y673304D02*
X779998D01*
G01D02*
X779750Y673056D01*
Y668000D01*
G01X775500Y705000D02*
X779500D01*
G01X787000Y725200D02*
X787300Y724700D01*
X788500Y723500D01*
X794000D01*
G01X787500Y778250D02*
Y783500D01*
G01X789500Y884750D02*
X785000D01*
G01D02*
Y892000D01*
G01X784000Y897000D02*
X785000Y896000D01*
Y892000D01*
G01X788750Y897000D02*
X790000D01*
G01D02*
X794500D01*
G01X786613Y996938D02*
Y1008860D01*
G01X778738Y998762D02*
Y1008860D01*
G01X774803D02*
Y999303D01*
G01X782678Y1008860D02*
Y998678D01*
G01X806274Y438828D02*
Y434726D01*
G01X793774Y434078D02*
Y432226D01*
X796000Y430000D01*
G01X798774Y433828D02*
Y431000D01*
X797774Y430000D01*
X796000D01*
G01X798774Y437328D02*
X796602Y439500D01*
X793000D01*
G01X800000Y458000D02*
X802078Y460078D01*
X806274D01*
G01X797750Y455750D02*
X800000Y458000D01*
G01X806274Y460078D02*
Y465078D01*
G01X799250Y553500D02*
Y546500D01*
G01Y553500D02*
Y561000D01*
G01X795844Y579468D02*
Y574968D01*
G01Y570468D02*
X798968D01*
X801500Y573000D01*
G01X795844Y574968D02*
Y570468D01*
G01Y583468D02*
X798532D01*
X802500Y579500D01*
G01X799000Y655500D02*
X799500Y655000D01*
X803500D01*
G01X792500Y661750D02*
X793372D01*
X795100Y660022D01*
Y659400D01*
X799000Y655500D01*
G01X802000Y728250D02*
Y724000D01*
G01X793500Y727500D02*
Y724000D01*
X794000Y723500D01*
G01X804968Y743784D02*
Y740532D01*
X810000Y735500D01*
G01X791500Y778250D02*
Y783500D01*
G01X801750Y867500D02*
Y860500D01*
G01D02*
Y856000D01*
G01X805250Y851000D02*
X810500D01*
G01X805250Y865750D02*
Y860500D01*
G01D02*
Y856000D01*
G01X790553Y1008860D02*
Y997053D01*
G01X794000Y996000D02*
Y998500D01*
G01D02*
X794488Y998988D01*
Y1008860D01*
G01X811838Y435740D02*
Y431338D01*
X811000Y430500D01*
G01X820438Y435740D02*
X826240D01*
X826500Y436000D01*
G01X821374Y465078D02*
X826000D01*
G01X810000Y731750D02*
Y735500D01*
G01X817750Y853500D02*
X813000D01*
X810500Y851000D01*
G01X821250Y849500D02*
Y845750D01*
G01X817750Y849500D02*
X814000D01*
G01X837319Y-438119D02*
Y-518119D01*
G01X833555Y270250D02*
Y262000D01*
G01X838055Y270250D02*
Y262500D01*
G01X830500Y410750D02*
X825850D01*
X825500Y411100D01*
G01X842555Y270250D02*
Y262000D01*
G01X851555Y270250D02*
Y262500D01*
G01X847055Y270250D02*
Y262500D01*
G01X854820Y352380D02*
Y348130D01*
G01Y344630D02*
X851570D01*
X850540Y345660D01*
Y346070D01*
G01X849500Y436250D02*
X853750D01*
X854000Y436500D01*
G01X858500Y436250D02*
X854250D01*
X854000Y436500D01*
G01X849500Y622000D02*
X849625D01*
X849750Y622125D01*
Y638500D01*
G01X846250D02*
Y642250D01*
G01X842218Y691284D02*
Y705718D01*
X846500Y710000D01*
G01X856891Y706312D02*
X850688D01*
X847000Y710000D01*
X846500D01*
G01X856750Y711000D02*
X853000D01*
X852500Y710500D01*
G01X844700Y726500D02*
X844500D01*
X842500Y724500D01*
Y719500D01*
G01X846500Y720000D02*
X846000Y719500D01*
X842500D01*
G01X845750Y868500D02*
Y865250D01*
X845500Y865000D01*
G01X849250Y868500D02*
X852600D01*
G01X866112Y89876D02*
Y85626D01*
G01X860555Y270250D02*
Y262500D01*
G01X856055Y270250D02*
Y262500D01*
G01X865055Y270250D02*
Y262500D01*
G01X870500Y444000D02*
X865750Y448750D01*
Y467500D01*
G01X862500Y436250D02*
X866250Y440000D01*
X866500D01*
X870500Y444000D01*
G01X865750Y467500D02*
Y470250D01*
X862500Y473500D01*
Y475277D01*
X862399Y475378D01*
Y478622D01*
X862500Y478723D01*
Y486000D01*
X865000Y488500D01*
G01X870625Y461750D02*
X872700D01*
X874450Y463500D01*
G01X871300Y479000D02*
X871500Y479200D01*
Y484000D01*
G01X867500Y617250D02*
Y621250D01*
G01D02*
X867050Y621700D01*
X862950D01*
X862500Y621250D01*
G01X876750Y636500D02*
X872500D01*
X872000Y636000D01*
G01X857500Y649250D02*
X861250D01*
G01X860500Y734000D02*
Y740500D01*
G01X876000Y330000D02*
X876940Y329060D01*
Y317250D01*
X877860Y316330D01*
G01X882000Y330000D02*
X883294Y328706D01*
X884704D01*
X888750Y324660D01*
G01X880820Y348130D02*
X886340D01*
X887950Y349740D01*
Y359730D01*
G01X880820Y351630D02*
X884120D01*
G01X887950Y359730D02*
Y362910D01*
X887940Y362920D01*
Y380200D01*
G01X878000Y404500D02*
X873250D01*
G01Y414000D02*
X874250Y413000D01*
X885000D01*
G01D02*
Y438700D01*
G01X878000Y404500D02*
X881000D01*
X885000Y408500D01*
Y413000D01*
G01X873250Y409500D02*
X877000D01*
G01X882700Y443100D02*
Y442200D01*
X881250Y440750D01*
X879500D01*
G01X880500Y478750D02*
X879750D01*
X879000Y479500D01*
X877000D01*
G01X880875Y615472D02*
X877903Y612500D01*
X877500D01*
G01X880250Y636500D02*
X884200D01*
G01X873500Y676250D02*
X877250D01*
X883500Y682500D01*
Y707500D01*
X881000Y710000D01*
G01D02*
X880784Y709784D01*
X875968D01*
G01X875500Y720500D02*
Y710252D01*
X875968Y709784D01*
G01X904500Y82000D02*
X944000Y121500D01*
Y140500D01*
X945000Y141500D01*
G01X918420Y449130D02*
X926949D01*
X931079Y445000D01*
X938951D01*
X941200Y447249D01*
Y448700D01*
G01X930750Y51500D02*
X935000D01*
G01X941260Y371535D02*
X937965D01*
X936000Y373500D01*
G01X937700Y448700D02*
X934000D01*
G01X935700Y452700D02*
Y456350D01*
X936030Y456680D01*
Y457540D01*
G01X964882Y371535D02*
X964874Y371527D01*
Y364626D01*
X965000Y364500D01*
G01X983524Y204578D02*
X980078D01*
G01X984260Y195257D02*
X980960D01*
G01X988660Y198757D02*
X984260D01*
G01D02*
X980570D01*
X980500Y198827D01*
X980490D01*
G01X988660Y195257D02*
Y190500D01*
G01Y198757D02*
X989481Y199578D01*
X997274D01*
G01X994500Y536750D02*
Y532000D01*
G01X990500Y536500D02*
X990750Y536750D01*
X994500D01*
G01Y540250D02*
Y543800D01*
G01X1026500Y141500D02*
X1021000D01*
X1020500Y142000D01*
G01X1017274Y214578D02*
Y219274D01*
G01X1014000Y487000D02*
Y483250D01*
X1011250Y480500D01*
G01X1010250Y473400D02*
X1011250Y474400D01*
Y480500D01*
G01X1018500Y496000D02*
X1014000Y491500D01*
Y487000D01*
G01X1008500Y536750D02*
Y533400D01*
G01Y540250D02*
Y543700D01*
G01X1011966Y898468D02*
Y893534D01*
G01Y879968D02*
X1007032D01*
G01X1011966Y902468D02*
X1007532D01*
G01X1034819Y-438119D02*
Y-518119D01*
G01X1066819Y-422119D02*
X1034819D01*
G01X1037750Y119500D02*
X1035000D01*
X1033500Y118000D01*
G01X1029750Y128500D02*
X1029000D01*
X1025000Y124500D01*
G01X1020500D02*
X1025000D01*
G01X1031100Y155000D02*
X1034000D01*
G01X1026750Y168500D02*
Y165750D01*
X1028000Y164500D01*
G01X1031524Y204578D02*
X1033922D01*
X1035323Y203177D01*
X1036019D01*
G01X1031524Y199578D02*
X1035922D01*
X1036000Y199500D01*
G01X1031524Y209578D02*
X1035922D01*
G01X1031524Y214078D02*
Y218476D01*
G01X1024966Y866968D02*
X1021468D01*
G01X1027716Y900000D02*
Y902500D01*
G01X1023716Y907718D02*
X1027716D01*
G01D02*
Y902500D01*
G01X1032216Y911218D02*
X1027716D01*
G01D02*
Y914784D01*
G01X1023716Y911218D02*
X1020282D01*
G01X1050819Y-438119D02*
Y-406119D01*
G01X1062819Y-422119D02*
G02I-12000J0D01*
G01X1057669D02*
G02I-6850J0D01*
G01X1045000Y25846D02*
Y32598D01*
G01D02*
Y39350D01*
G01X1038248Y32598D02*
X1045000D01*
G01D02*
X1051752D01*
G01X1052984Y43267D02*
X1057086D01*
G01X1052100Y176600D02*
Y173100D01*
X1051500Y172500D01*
G01X1045968Y172984D02*
X1051016D01*
X1051500Y172500D01*
G01X1052100Y182600D02*
X1052500Y183000D01*
Y187500D01*
G01X1045968Y180584D02*
Y185500D01*
G01X1045750Y685000D02*
X1042900D01*
X1042400Y684500D01*
G01X1047250Y930000D02*
X1042500D01*
G01X1057086Y43267D02*
Y47369D01*
G01Y43267D02*
X1061188D01*
G01X1056700Y173000D02*
X1057234Y173534D01*
X1060900D01*
G01X1056700Y179000D02*
X1058666Y177034D01*
X1060417D01*
X1060509Y177126D01*
G01X1066500Y180800D02*
Y185500D01*
G01X1060218Y223284D02*
X1057932D01*
X1056716Y224500D01*
G01X1062718Y227284D02*
X1059500D01*
X1056716Y224500D01*
G01X1067750Y741500D02*
X1069050D01*
X1071050Y743500D01*
X1072000D01*
G01X1067750Y737500D02*
X1068250Y738000D01*
X1070500D01*
X1071500Y739000D01*
G01X1065838Y761294D02*
X1061696D01*
G01X1065688Y753354D02*
X1061356D01*
G01X1073679Y73758D02*
X1072921Y73000D01*
X1072888D01*
X1071000Y71112D01*
Y71000D01*
G01X1073500Y141000D02*
X1078000D01*
G01X1084000Y141200D02*
X1083800Y141000D01*
X1078000D01*
G01X1083000Y180800D02*
Y188000D01*
X1080300Y190700D01*
Y191000D01*
G01X1074500Y180800D02*
Y185500D01*
G01X1078718Y200784D02*
X1082784D01*
X1084500Y202500D01*
G01X1080468Y207534D02*
Y206532D01*
X1084500Y202500D01*
G01X1077750Y627500D02*
X1074500D01*
G01X1077750Y631500D02*
X1074500D01*
X1073000Y633000D01*
Y637500D01*
G01X1077750Y679500D02*
X1076500D01*
X1074000Y677000D01*
G01X1077750Y683500D02*
X1074500D01*
X1074000Y683000D01*
G01X1077750Y691500D02*
X1077405Y691155D01*
X1074389D01*
G01X1077750Y695500D02*
X1075246D01*
X1074500Y694754D01*
G01X1077750Y687500D02*
X1074671D01*
X1074426Y687255D01*
G01X1077750Y707500D02*
X1075169D01*
X1074945Y707724D01*
X1074600D01*
G01X1077750Y703500D02*
X1074000D01*
G01X1077750Y699500D02*
X1074000D01*
G01X1077750Y711500D02*
X1074272D01*
X1074148Y711624D01*
G01X1077750Y730500D02*
X1073334D01*
X1073000Y730834D01*
G01X1077750Y726500D02*
X1073056D01*
X1073000Y726444D01*
G01X1077750Y722500D02*
X1073500D01*
X1073384Y722384D01*
G01X1077750Y715500D02*
X1077375Y715125D01*
X1074697D01*
X1074288Y715534D01*
G01X1077500Y745374D02*
X1087988D01*
G01X1070098Y761334D02*
Y764500D01*
G01X1079688Y753484D02*
Y756812D01*
X1077500Y759000D01*
G01X1085468Y890084D02*
Y895968D01*
G01X1096732Y25846D02*
Y32598D01*
G01D02*
Y39350D01*
G01X1089980Y32598D02*
X1096732D01*
G01X1090500Y90300D02*
Y88000D01*
X1088000Y85500D01*
G01X1107968Y250784D02*
X1102784D01*
X1102000Y250000D01*
G01X1099500Y259750D02*
Y261000D01*
X1102500Y264000D01*
Y264500D01*
G01X1089500Y408750D02*
Y405000D01*
G01X1101500Y457750D02*
X1097000D01*
G01X1101500Y461500D02*
Y457750D01*
G01X1088500Y753700D02*
X1093300D01*
X1095000Y752000D01*
G01X1099500Y753250D02*
X1096250D01*
X1095000Y752000D01*
G01X1103000Y753250D02*
X1099500D01*
G01Y756750D02*
X1096250D01*
X1095000Y758000D01*
G01X1103000Y756750D02*
X1099500D01*
G01X1101750Y776500D02*
X1099500D01*
X1098000Y775000D01*
G01X1101750Y772500D02*
X1100500D01*
X1098000Y775000D01*
G01X1097500Y797500D02*
Y792750D01*
G01D02*
X1101450D01*
X1103500Y794800D01*
G01X1097500Y789250D02*
X1094750D01*
X1093000Y791000D01*
G01X1100500Y780500D02*
Y781500D01*
X1097500Y784500D01*
G01X1096000Y816250D02*
Y812500D01*
X1095500Y812000D01*
G01X1096000Y819750D02*
Y820844D01*
X1098500Y823344D01*
G01X1096218Y859500D02*
Y863284D01*
G01X1101468Y847034D02*
X1100968Y847534D01*
X1100096D01*
X1098630Y849000D01*
X1097500D01*
G01X1092718Y863284D02*
Y859984D01*
G01X1096218Y867284D02*
Y863284D01*
G01D02*
X1100784D01*
X1102000Y864500D01*
G01X1092718Y871784D02*
Y867284D01*
G01D02*
X1089000D01*
G01X1093468Y890084D02*
Y896968D01*
G01X1099468Y888034D02*
X1099734Y888300D01*
X1103000D01*
G01X1114468Y248484D02*
X1120984D01*
X1123000Y250500D01*
G01X1116500Y280000D02*
X1118500D01*
X1120600Y282100D01*
Y282300D01*
G01X1102750Y428000D02*
X1105000Y430250D01*
Y465773D01*
X1103302Y467471D01*
X1103301Y467499D01*
X1103300Y467542D01*
Y492000D01*
G01X1117500Y614250D02*
X1113500D01*
G01X1111000Y634250D02*
Y632500D01*
X1113000Y630500D01*
G01X1103000Y634250D02*
Y632500D01*
X1105000Y630500D01*
G01X1107000Y634250D02*
Y632500D01*
X1105000Y630500D01*
G01X1115000Y634250D02*
Y632500D01*
X1113000Y630500D01*
G01X1104230Y738906D02*
X1110734D01*
X1110790Y738850D01*
G01X1107000Y763000D02*
X1105500Y764500D01*
Y768643D01*
X1105250Y768893D01*
Y772500D01*
G01X1106600Y753000D02*
X1106350Y753250D01*
X1103000D01*
G01X1107000Y757500D02*
X1106250Y756750D01*
X1103000D01*
G01X1118300Y753250D02*
X1122800D01*
G01X1105250Y776500D02*
X1106500Y777750D01*
Y780500D01*
G01X1105250Y772500D02*
Y776500D01*
G01X1106500Y780500D02*
Y784200D01*
X1103500Y787200D01*
G01X1107468Y809834D02*
X1111834Y813334D01*
G01X1113500Y824500D02*
X1113250Y824250D01*
Y817000D01*
G01X1116750D02*
Y819250D01*
X1121000Y823500D01*
G01X1121968Y847034D02*
X1118034D01*
G01X1110468D02*
X1113768D01*
G01X1129250Y278000D02*
Y287250D01*
X1128000Y288500D01*
G01X1122000Y614250D02*
X1126250D01*
X1126500Y614500D01*
G01X1129750Y618000D02*
X1126000D01*
G01X1122800Y753250D02*
X1125770D01*
X1126210Y752810D01*
G01X1130030Y820000D02*
X1129500D01*
X1128500Y821000D01*
Y825700D01*
G01X1134500Y830460D02*
Y834000D01*
X1135500Y835000D01*
G01X1128500Y833300D02*
X1127670Y832470D01*
X1123500D01*
G01X1142250Y274500D02*
X1145500D01*
X1146500Y275500D01*
G01X1142218Y282284D02*
X1145800D01*
G01X1142250Y278500D02*
X1144500D01*
X1145800Y279800D01*
Y282284D01*
G01X1151000Y592500D02*
X1153000D01*
X1155000Y594500D01*
G01X1146900Y604700D02*
Y605400D01*
X1150000Y608500D01*
X1152500D01*
G01X1151250Y822500D02*
X1155390Y818360D01*
Y818000D01*
G01D02*
X1151250D01*
G01Y814000D02*
X1151500D01*
X1154300Y811200D01*
Y809610D01*
G01X1143250Y862000D02*
Y858316D01*
X1143218Y858284D01*
G01X1135468Y858534D02*
Y854032D01*
G01X1162468Y253534D02*
Y257968D01*
G01X1159934Y589068D02*
X1154068D01*
X1154000Y589000D01*
G01X1159934Y609672D02*
X1165672D01*
G01X1167500Y620750D02*
Y616000D01*
X1166000Y614500D01*
Y613917D01*
X1165476Y613393D01*
G01X1152500Y827000D02*
X1157990D01*
G01X1173000Y386750D02*
X1173250D01*
X1176500Y383500D01*
G01X1168000Y390250D02*
X1173000D01*
G01X1179000Y403750D02*
X1175250D01*
X1175000Y404000D01*
X1174500D01*
G01X1183000Y403750D02*
Y406500D01*
X1182500Y407000D01*
G01X1179934Y573276D02*
Y567000D01*
G01X1181070Y777000D02*
Y781700D01*
X1180070Y782700D01*
X1180000D01*
X1173200Y789500D01*
G01X1195000Y403750D02*
X1191000D01*
G01D02*
Y419500D01*
X1189000Y421500D01*
G01X1187000Y403750D02*
Y410500D01*
X1187500Y411000D01*
G01X1199000Y403750D02*
Y407500D01*
X1197000Y409500D01*
G01X1192000Y757250D02*
Y761000D01*
X1192038Y761038D01*
Y761481D01*
G01X1202250Y749000D02*
X1201500D01*
X1197000Y753500D01*
X1196120D01*
X1195920Y753700D01*
G01X1196500Y757750D02*
Y754280D01*
X1195920Y753700D01*
G01X1196500Y761250D02*
X1196716Y761034D01*
X1201968D01*
G01X1188000Y757250D02*
Y762500D01*
G01X1187070Y777000D02*
Y778680D01*
X1184750Y781000D01*
G01X1198718Y807784D02*
Y804284D01*
G01D02*
Y800782D01*
G01X1197000Y851750D02*
Y848500D01*
X1196000Y847500D01*
G01X1188875Y861750D02*
Y856625D01*
G01X1192250Y875500D02*
X1195000D01*
X1196000Y874500D01*
G01X1195940Y868750D02*
Y874440D01*
X1196000Y874500D01*
G01X1215256Y200000D02*
X1210500D01*
X1208500Y202000D01*
G01X1215256Y203150D02*
X1209650D01*
X1208500Y202000D01*
G01X1215256Y228347D02*
X1210153D01*
X1208000Y230500D01*
Y231000D01*
G01X1215256Y247245D02*
X1209000D01*
X1208245Y248000D01*
X1202422D01*
X1201922Y248500D01*
G01X1215256Y269292D02*
X1210207D01*
X1208000Y271499D01*
G01X1215256Y256693D02*
X1205484D01*
X1202334Y259843D01*
G01D02*
X1202177Y260000D01*
G01X1215256Y259843D02*
X1202334D01*
G01X1215256Y281890D02*
X1210110D01*
X1208500Y283500D01*
G01X1215256Y272441D02*
X1208942D01*
X1208000Y271499D01*
G01X1215256Y285040D02*
X1210040D01*
X1208500Y283500D01*
G01X1215256Y297638D02*
X1208000D01*
G01X1215256Y294489D02*
X1211149D01*
X1208000Y297638D01*
G01X1215256Y307087D02*
X1209145D01*
X1208000Y308232D01*
Y309000D01*
G01X1215256Y319685D02*
X1210315D01*
X1208500Y321500D01*
G01X1215256Y310237D02*
X1209237D01*
X1208000Y309000D01*
G01X1215256Y332284D02*
X1208784D01*
X1206500Y330000D01*
G01X1215256Y322835D02*
X1209352D01*
X1208500Y321983D01*
Y321500D01*
G01X1215256Y335434D02*
X1207000D01*
X1206000Y334434D01*
Y331940D01*
X1206500Y331440D01*
Y330000D01*
G01X1215256Y344882D02*
X1209867D01*
X1208500Y346249D01*
Y346400D01*
G01X1215256Y348032D02*
X1210132D01*
X1208500Y346400D01*
G01X1215256Y357481D02*
X1210019D01*
X1208500Y359000D01*
G01X1215256Y360630D02*
X1210130D01*
X1208500Y359000D01*
G01X1215256Y370079D02*
X1208921D01*
X1208000Y371000D01*
G01X1215256Y373229D02*
X1210229D01*
X1208000Y371000D01*
G01X1212500Y436000D02*
X1214534Y433966D01*
Y432532D01*
G01X1210250Y432500D02*
X1210282Y432532D01*
X1214534D01*
G01X1206750Y432500D02*
Y436250D01*
X1209000Y438500D01*
G01X1222000Y440250D02*
X1217250D01*
X1216500Y439500D01*
G01X1222000Y452500D02*
X1217000D01*
G01X1209470Y565260D02*
Y562030D01*
X1209500Y562000D01*
Y561910D01*
G01X1205240Y568760D02*
X1209470D01*
G01X1203830Y576840D02*
Y570170D01*
X1205240Y568760D01*
G01X1209470D02*
X1212970D01*
X1213220Y568510D01*
G01X1220370Y596840D02*
Y599630D01*
X1215500Y604500D01*
Y605300D01*
G01X1217000Y630750D02*
X1219250D01*
X1221500Y633000D01*
G01X1214750Y731000D02*
X1213000D01*
X1210500Y733500D01*
G01X1214750Y735500D02*
X1212500D01*
X1210500Y733500D01*
G01X1207000Y761250D02*
X1206500Y760750D01*
Y757000D01*
G01X1212500Y761250D02*
X1213500Y760250D01*
Y756000D01*
G01X1205750Y753000D02*
Y756250D01*
X1206500Y757000D01*
G01X1202250Y753000D02*
Y757218D01*
X1201968Y757500D01*
G01Y761034D02*
Y757500D01*
G01X1202218Y807784D02*
Y804284D01*
G01Y807784D02*
Y811282D01*
G01X1211000Y851750D02*
Y847500D01*
G01X1207250Y878500D02*
Y876250D01*
X1208940Y874560D01*
G01D02*
Y868750D01*
G01X1210750Y878500D02*
Y882000D01*
X1211250Y882500D01*
X1211500D01*
G01X1232776Y203150D02*
X1238650D01*
X1239500Y204000D01*
G01X1232776Y209449D02*
X1240000D01*
G01X1232776Y215748D02*
X1237752D01*
X1239500Y214000D01*
G01X1232776Y212599D02*
X1238099D01*
X1239500Y214000D01*
G01X1232776Y206300D02*
X1237200D01*
X1239500Y204000D01*
G01X1232776Y253544D02*
X1236956D01*
X1239000Y251500D01*
G01X1232776Y250394D02*
X1237894D01*
X1239000Y251500D01*
G01X1232776Y266142D02*
X1241335D01*
X1241777Y265700D01*
G01X1232776Y262993D02*
X1239070D01*
X1241777Y265700D01*
G01X1232776Y275591D02*
X1240686D01*
G01X1232776Y278741D02*
X1237536D01*
X1240686Y275591D01*
G01X1232776Y291339D02*
X1237161D01*
X1238500Y290000D01*
G01X1232776Y300788D02*
X1237351D01*
X1239000Y302437D01*
G01X1232776Y288189D02*
X1237500D01*
X1238500Y289189D01*
Y290000D01*
G01X1232776Y303937D02*
X1237500D01*
X1239000Y302437D01*
G01X1232776Y313386D02*
X1237386D01*
X1238500Y314500D01*
Y316500D01*
G01X1232776Y316536D02*
X1235177Y316500D01*
X1238500D01*
G01X1232776Y325985D02*
X1238500D01*
G01X1232776Y329134D02*
X1236866D01*
X1238500Y327500D01*
Y325985D01*
G01X1232776Y351182D02*
X1237382D01*
X1239000Y352800D01*
G01X1232776Y338583D02*
X1238683D01*
X1239000Y338900D01*
G01X1232776Y341733D02*
X1237267D01*
X1239000Y340000D01*
Y338900D01*
G01X1232776Y363780D02*
X1238280D01*
X1239500Y365000D01*
Y366000D01*
G01X1232776Y354331D02*
X1237669D01*
X1239000Y353000D01*
Y352800D01*
G01X1232776Y366930D02*
X1238570D01*
X1239500Y366000D01*
G01X1232776Y376378D02*
X1234177Y377779D01*
Y379500D01*
G01X1225750Y731000D02*
X1229000Y727750D01*
Y726500D01*
G01X1225750Y735500D02*
Y731000D01*
G01X1228750Y753000D02*
Y757500D01*
G01X1224500D02*
X1228750D01*
G01D02*
Y762000D01*
G01X1225500Y793250D02*
Y796500D01*
X1223500Y798500D01*
G01X1240686Y275591D02*
X1241377Y274900D01*
G01X1244750Y456000D02*
Y456250D01*
X1242000Y459000D01*
G01X1251000Y476250D02*
X1246750D01*
G01X1247750Y762000D02*
X1249000Y763250D01*
Y765000D01*
X1249500Y765500D01*
G01X1241000Y775500D02*
X1248500D01*
G01X1242100Y821850D02*
X1245650D01*
G01X1257000Y36250D02*
Y33000D01*
G01X1260750Y30000D02*
X1260000D01*
X1257000Y33000D01*
G01X1257468Y466484D02*
X1258184Y467200D01*
X1263700D01*
G01X1257468Y474084D02*
Y478500D01*
G01X1263750Y555125D02*
Y550250D01*
X1263500Y550000D01*
G01X1256250Y559000D02*
Y562250D01*
X1254000Y564500D01*
G01D02*
Y567300D01*
X1257200Y570500D01*
G01X1263750Y562875D02*
X1265125D01*
X1267500Y560500D01*
Y549500D01*
G01X1264800Y570500D02*
X1266500D01*
X1269500Y573500D01*
X1271000D01*
G01X1257200Y570500D02*
X1257750Y571050D01*
Y577000D01*
G01D02*
X1255000Y579750D01*
Y583000D01*
G01X1253750Y680000D02*
X1257950D01*
X1259000Y678950D01*
G01X1261250Y667500D02*
X1262300Y668550D01*
Y670700D01*
G01X1253750Y671000D02*
X1257124D01*
X1258562Y672438D01*
G01X1255000Y675500D02*
X1255500D01*
X1258562Y672438D01*
G01X1254000Y695750D02*
X1260250D01*
X1262500Y698000D01*
Y699825D01*
G01X1253750Y699500D02*
X1259000D01*
G01X1253750Y711500D02*
X1256500D01*
X1257500Y710500D01*
G01X1255000Y716000D02*
Y719500D01*
X1259500Y724000D01*
G01X1262750Y779000D02*
X1267500D01*
G01X1262750Y783000D02*
X1267500D01*
G01X1265350Y835100D02*
X1269400D01*
X1269500Y835000D01*
G01X1263850Y847975D02*
X1264000Y848125D01*
Y853000D01*
G01X1272677Y344714D02*
Y349016D01*
G01D02*
Y353318D01*
G01Y349016D02*
X1276979D01*
G01X1268468Y465784D02*
X1269284Y466600D01*
X1272500D01*
G01X1268468Y471784D02*
Y475468D01*
X1270000Y477000D01*
G01X1291300Y540900D02*
Y543700D01*
X1289750Y545250D01*
X1271500D01*
G01Y548750D02*
X1268250D01*
X1267500Y549500D01*
G01X1272250Y564500D02*
Y567250D01*
X1271000Y568500D01*
G01X1275000Y598000D02*
X1282500D01*
G01X1285000Y663250D02*
X1284493Y663559D01*
X1283047D01*
X1281268Y661780D01*
G01X1281000Y716250D02*
X1281500Y715750D01*
Y713000D01*
G01X1281000Y709250D02*
X1282181D01*
X1283195Y708236D01*
X1285622D01*
X1287876Y710490D01*
X1287962D01*
G01X1295500Y34250D02*
X1291126D01*
X1291000Y34376D01*
X1290874D01*
G01X1287372Y291500D02*
X1295500D01*
G01X1284500Y318250D02*
X1285250D01*
X1292000Y311500D01*
X1307500D01*
X1308000Y311000D01*
G01X1291912Y434712D02*
X1298096D01*
X1298168Y434784D01*
G01D02*
X1299000Y433952D01*
Y429000D01*
G01X1293500Y470300D02*
Y475000D01*
G01X1285250Y564500D02*
Y567750D01*
X1286500Y569000D01*
G01X1302500Y564500D02*
X1300000D01*
X1297500Y562000D01*
G01X1289468Y663034D02*
X1290500Y665066D01*
X1291434Y666000D01*
X1291500D01*
G01X1296500Y830782D02*
X1300784D01*
G01X1310500Y43250D02*
X1306250D01*
X1306000Y43000D01*
G01X1314500Y43250D02*
X1310500D01*
G01X1304760Y50862D02*
X1309362D01*
X1309500Y51000D01*
G01X1308750Y316500D02*
Y319250D01*
X1307500Y320500D01*
G01X1324500Y306250D02*
X1324250Y306500D01*
X1314872D01*
G01X1305768Y434784D02*
X1310784D01*
X1311000Y435000D01*
G01X1302500Y559500D02*
X1303500D01*
X1308500Y564500D01*
G01X1312867Y559912D02*
Y564412D01*
G01X1308500Y564500D02*
X1308588Y564412D01*
X1312867D01*
G01Y581912D02*
X1307712D01*
X1305200Y579400D01*
Y575212D01*
X1307000Y573412D01*
G01X1312950Y573000D02*
X1312538Y573412D01*
X1307000D01*
G01X1311617Y577412D02*
X1307900D01*
G01X1312867Y590912D02*
X1308317D01*
X1306817Y592412D01*
G01X1312867Y586412D02*
X1307717D01*
X1306617Y587512D01*
G01X1312867Y595412D02*
X1308817D01*
G01X1312867Y607912D02*
X1306675D01*
X1306423Y608164D01*
G01X1312867Y603912D02*
X1305441D01*
X1305435Y603918D01*
G01X1312867Y612412D02*
X1305217D01*
G01X1312867Y621412D02*
X1308870D01*
X1306443Y618985D01*
G01X1312867Y616912D02*
X1308516D01*
X1306443Y618985D01*
G01X1303784Y785782D02*
Y784716D01*
X1306000Y782500D01*
G01X1314284Y785782D02*
Y782500D01*
G01X1308784Y785782D02*
Y785284D01*
X1306000Y782500D01*
G01X1304500Y834250D02*
Y838000D01*
G01X1300784Y834282D02*
Y838716D01*
G01X1308250Y855000D02*
Y858500D01*
G01Y855000D02*
Y852250D01*
X1306500Y850500D01*
X1305000D01*
G01X1308250Y858500D02*
Y864000D01*
G01X1304750Y855000D02*
Y858500D01*
G01D02*
Y861250D01*
X1303750Y862250D01*
G01X1312468Y917034D02*
Y919468D01*
X1314500Y921500D01*
G01X1316968Y917034D02*
Y919032D01*
X1314500Y921500D01*
G01X1335125Y119750D02*
X1331250D01*
X1331000Y120000D01*
G01X1339500Y305500D02*
X1338750Y306250D01*
X1324500D01*
G01Y309750D02*
Y316000D01*
X1322000Y318500D01*
G01X1325000Y420000D02*
X1318700D01*
X1317700Y421000D01*
G01D02*
Y427000D01*
G01X1323500Y448750D02*
Y452500D01*
G01X1316367Y603912D02*
X1316639D01*
X1319617Y600934D01*
Y598169D01*
X1322374Y595412D01*
X1323960D01*
X1324960Y594412D01*
X1326617D01*
G01X1327617Y622162D02*
Y624812D01*
X1329317Y626512D01*
G01X1332117Y622162D02*
Y623712D01*
X1329317Y626512D01*
G01X1323117Y622162D02*
Y626412D01*
G01X1328968Y676534D02*
Y679684D01*
G01X1318784Y801032D02*
Y793716D01*
G01X1317500Y906250D02*
X1318284Y907034D01*
X1321466D01*
G01X1332500Y54250D02*
X1333100Y54850D01*
Y58600D01*
G01X1347000Y88000D02*
Y84000D01*
G01X1350125Y119750D02*
Y118625D01*
X1347500Y116000D01*
G01X1341873Y344873D02*
X1344446Y342300D01*
Y340300D01*
G01D02*
X1350996Y333750D01*
X1375250D01*
X1378200Y330800D01*
Y326881D01*
X1378084Y326765D01*
Y320611D01*
G01X1347000Y428000D02*
X1350500Y424500D01*
X1351250D01*
G01X1343000Y456000D02*
X1338688D01*
X1338500Y456250D01*
G01X1343000Y462000D02*
Y466500D01*
G01X1334500Y557000D02*
X1335800Y555700D01*
Y547900D01*
X1337900Y545800D01*
X1342639D01*
G01X1336617Y562412D02*
Y559117D01*
X1334500Y557000D01*
G01X1346617Y619662D02*
Y617412D01*
X1342648Y613443D01*
Y612412D01*
G01X1342367Y619412D02*
X1346367D01*
X1346617Y619662D01*
G01Y623162D02*
Y626912D01*
G01X1342367Y623912D02*
Y627662D01*
G01X1333468Y676534D02*
Y680000D01*
G01X1352000Y81750D02*
Y85500D01*
G01X1353084Y282053D02*
Y277416D01*
X1354500Y276000D01*
G01X1355500Y416500D02*
Y419750D01*
X1355000Y420250D01*
G01Y423750D02*
X1352000D01*
X1351250Y424500D01*
G01X1350500Y420000D02*
X1354750D01*
X1355000Y420250D01*
G01X1354000Y438700D02*
X1359300Y444000D01*
X1362500D01*
G01D02*
Y449000D01*
G01X1354117Y562412D02*
Y557883D01*
X1355500Y556500D01*
G01X1363117Y562162D02*
Y560112D01*
X1360817Y557812D01*
G01X1348595Y555024D02*
X1354024D01*
X1355500Y556500D01*
G01X1358617Y562162D02*
Y560012D01*
X1360817Y557812D01*
G01X1369867Y593912D02*
X1365617D01*
X1364617Y592912D01*
G01Y619662D02*
Y618490D01*
X1362090Y615963D01*
X1361363D01*
X1360200Y614800D01*
G01X1356117Y609412D02*
X1359617Y612912D01*
Y614217D01*
X1360200Y614800D01*
G01X1354417Y623162D02*
Y626612D01*
X1353517Y627512D01*
G01X1350617Y624662D02*
Y627812D01*
X1349817Y628612D01*
G01X1364617Y623162D02*
Y625483D01*
X1363100Y627000D01*
G01X1360617Y623162D02*
Y624517D01*
X1363100Y627000D01*
G01X1369720Y110415D02*
Y106365D01*
G01X1378084Y320611D02*
Y319907D01*
G01D02*
Y315500D01*
X1378113Y315387D01*
X1379500Y314000D01*
G01X1374500Y449500D02*
Y462800D01*
G01X1371617Y565662D02*
Y566012D01*
X1367617Y570012D01*
G01D02*
Y565662D01*
G01X1371617Y562162D02*
Y559012D01*
X1369617Y557012D01*
G01X1367617Y562162D02*
Y559012D01*
X1369617Y557012D01*
G01X1373367Y593912D02*
X1377812D01*
X1378800Y594900D01*
G01X1390004Y110415D02*
Y106000D01*
X50000Y659500D03*
X58804Y699720D03*
X109000Y844220D03*
X111000Y981500D03*
X112900Y988500D03*
X124500Y515500D03*
X128000Y544050D03*
X121200Y584278D03*
X166200Y506500D03*
X172000Y486400D03*
X182000Y577500D03*
X176938Y680465D03*
X182500Y677500D03*
X242500Y565500D03*
X234000Y562000D03*
X236500Y574000D03*
X238500Y705000D03*
X253500Y707250D03*
X311500Y153000D03*
X299000Y148000D03*
X307129Y143000D03*
X305029Y147700D03*
X304300Y160200D03*
X304100Y167000D03*
X311300D03*
X312500Y159100D03*
X306155Y497700D03*
X305155Y504900D03*
X330250Y80000D03*
X330900Y134500D03*
X319014Y152977D03*
X328700Y154400D03*
X328629Y146800D03*
X330400Y141600D03*
X331040Y152601D03*
X330929Y148600D03*
X318200Y159100D03*
X320238Y497183D03*
X320338Y507683D03*
X316273Y520282D03*
X347000Y120040D03*
X340000D03*
X338000Y127500D03*
X337400Y134500D03*
X334000Y147600D03*
X344055Y529000D03*
X340055Y524000D03*
X342971Y525750D03*
X339000Y878500D03*
X336000Y871500D03*
X339000Y894000D03*
Y885500D03*
X337300Y949500D03*
X357394Y131496D03*
X353740Y133300D03*
X362009Y142520D03*
Y148819D03*
Y155119D03*
X352040Y143000D03*
X349829Y153400D03*
X362036Y170876D03*
X362034Y161406D03*
X355084Y172441D03*
X351929Y162200D03*
X353085Y187485D03*
X355040Y180000D03*
X362017Y183492D03*
X362036Y177155D03*
X358858Y177128D03*
X358848Y174010D03*
X354540Y199000D03*
X358879Y192929D03*
X351320Y194520D03*
X361987Y189747D03*
X358850Y196050D03*
X355090Y195660D03*
X355139Y190099D03*
X351731Y190274D03*
X361155Y496203D03*
X356555Y513000D03*
X357055Y507000D03*
X356055Y502000D03*
X368307Y133071D03*
X374606Y136221D03*
X368296Y136246D03*
X371456Y136221D03*
X368305Y139401D03*
X371482Y133058D03*
X365133Y129133D03*
X374600Y139390D03*
X377750Y139400D03*
X371458Y142520D03*
X377765Y155146D03*
X374589Y155110D03*
X371455Y148854D03*
X377787Y148812D03*
X368333Y155107D03*
X365140Y155100D03*
X377757Y145670D03*
X368333Y148827D03*
X368329Y151956D03*
X371493Y145667D03*
X368314Y142505D03*
Y145680D03*
X371457Y155080D03*
X377759Y152000D03*
X365146Y151942D03*
X365182Y142532D03*
X374607Y142520D03*
X377757D03*
X365186Y170876D03*
X377732Y167703D03*
X377718Y161417D03*
X371470Y167741D03*
X371489Y161411D03*
X368309Y170830D03*
X368334Y167706D03*
X365158Y164554D03*
X368325Y164585D03*
X368326Y161400D03*
X368271Y158268D03*
X374582Y161404D03*
X374577Y164559D03*
X377750Y170846D03*
X374570Y158267D03*
X365176Y161400D03*
X365186Y177175D03*
X368320Y183460D03*
X377741Y177188D03*
X377731Y180302D03*
X371457Y173978D03*
X365187Y186605D03*
X368308Y177202D03*
X374560Y177210D03*
X371485Y177175D03*
X368336Y189755D03*
X368307Y196062D03*
Y202361D03*
X377755D03*
Y199211D03*
Y196062D03*
Y192912D03*
Y189763D03*
X368307Y205511D03*
Y199211D03*
X368336Y192904D03*
X374606Y189763D03*
Y192912D03*
X374607Y218110D03*
X374606Y211810D03*
X377756D03*
X365158D03*
X371457D03*
X367665Y363430D03*
X368055Y380500D03*
X368555Y385000D03*
Y376500D03*
X371781Y387924D03*
X368555Y389000D03*
X368165Y393402D03*
X370500Y518000D03*
X379500Y963500D03*
X390354Y136221D03*
X380906Y136220D03*
X390355Y139371D03*
X380920Y139370D03*
X387173Y139376D03*
X392240Y129000D03*
X383680Y129030D03*
X396683Y139362D03*
X393510Y139340D03*
X384019Y139371D03*
X384055Y155117D03*
X396653D03*
X380907Y142520D03*
X387206Y145670D03*
X390355Y142520D03*
X393505Y145670D03*
X384093Y151968D03*
X393519Y151990D03*
X384056Y145670D03*
X390355D03*
X396655D03*
X387206Y142520D03*
X384056D03*
X390339Y151990D03*
X396639D03*
X380888Y148799D03*
X396655Y142520D03*
X393505D03*
X384055Y158266D03*
X396653D03*
X390354Y167715D03*
X396653D03*
X384032Y167703D03*
X380944Y161417D03*
X387219Y158290D03*
X387205Y167715D03*
X384041Y170888D03*
X380928Y167701D03*
X393528Y167702D03*
X390392Y186614D03*
X384055Y186613D03*
X396654Y186614D03*
X396653Y174015D03*
Y180314D03*
X387204Y177164D03*
X384032Y174003D03*
X384030Y177120D03*
X393542Y186614D03*
X393490Y174039D03*
X393541Y180315D03*
X384055Y202361D03*
X393503Y205510D03*
X396654Y202362D03*
X396653Y205511D03*
Y199211D03*
X384055Y192912D03*
Y196062D03*
X396653Y192912D03*
X384036Y189747D03*
X393519Y192900D03*
X387209Y192930D03*
X393503Y211809D03*
X380906Y211810D03*
X396654D03*
X396653Y208660D03*
X393503D03*
X390354Y218109D03*
Y221259D03*
X384055Y211810D03*
X393504Y218109D03*
X390354Y224408D03*
X389500Y319150D03*
X392589Y317729D03*
X394055Y335000D03*
X391325Y324520D03*
X386755Y326100D03*
X384160Y328812D03*
X391555Y338350D03*
X393061Y346800D03*
X393755Y350500D03*
X390230Y349327D03*
X396055Y338000D03*
X395855Y366890D03*
X392991Y365797D03*
X391628Y358852D03*
X394915Y359725D03*
X387515Y365500D03*
X387265Y384370D03*
X394935Y385150D03*
X382803Y385207D03*
X391215Y384900D03*
X396490Y388597D03*
X388500Y400575D03*
X390543Y391950D03*
X387000Y404275D03*
X396500Y910500D03*
X388750Y951750D03*
X387061Y986061D03*
X389500Y992000D03*
X402950Y133050D03*
X399835Y139375D03*
X412429Y136210D03*
X399783Y136237D03*
X402953Y139370D03*
X402800Y129180D03*
X406103Y139371D03*
X412415Y148794D03*
X399779Y142531D03*
X399804Y145670D03*
X412403Y142520D03*
X406102Y155117D03*
X412402Y155118D03*
X412401Y151967D03*
X399819Y151950D03*
X406125Y148804D03*
X406110Y145660D03*
X402954Y145670D03*
Y142520D03*
X406103D03*
X402938Y151950D03*
X402952Y167715D03*
X409251D03*
X412401Y158267D03*
X406102D03*
X399827Y167702D03*
X406140Y167716D03*
X406127Y161404D03*
X412427D03*
X412426Y167703D03*
X402977Y174003D03*
X402952Y186613D03*
X409251D03*
X409288Y180315D03*
X402952Y180314D03*
X409251Y174015D03*
X399841Y186614D03*
X399840Y180315D03*
X399790Y174039D03*
X406126Y174003D03*
X406139Y180315D03*
X406101Y186613D03*
X412426Y174003D03*
X412439Y186614D03*
X412400Y180314D03*
X412401Y205510D03*
X402952Y192912D03*
X409251D03*
X406128Y192901D03*
X399791Y192938D03*
X412428Y192901D03*
X402953Y211810D03*
X412402D03*
X399803Y218109D03*
Y221259D03*
Y208660D03*
Y211810D03*
X406102D03*
X406099Y214950D03*
X409249Y214965D03*
X412767Y233162D03*
X400000Y237500D03*
X409500Y271500D03*
X410826Y332086D03*
Y328149D03*
Y324212D03*
X406889Y332086D03*
Y328149D03*
Y324212D03*
X402952Y332086D03*
Y328149D03*
X404920Y330117D03*
X412794D03*
X404920Y334054D03*
X412794D03*
X408857D03*
X400983D03*
X397983Y333998D03*
X408857Y330117D03*
X400523Y325283D03*
X412815Y349860D03*
X408857Y341928D03*
X412794D03*
X397555Y345146D03*
X398055Y350296D03*
X398555Y339283D03*
X408857Y345865D03*
X404965Y342120D03*
X412794Y337991D03*
X400055Y343146D03*
X408857Y365550D03*
Y357676D03*
X412794Y365550D03*
Y357676D03*
X397117Y364138D03*
X412794Y353739D03*
X404920Y369487D03*
X412794Y361613D03*
X408925Y361680D03*
X400395Y362450D03*
X400885Y354120D03*
X404935Y353840D03*
X412794Y369487D03*
X408857D03*
Y353739D03*
Y385237D03*
Y377363D03*
X412794D03*
Y385237D03*
Y381300D03*
X399923Y372000D03*
X408857Y400985D03*
Y393111D03*
X412794Y400985D03*
Y393111D03*
X408857Y389174D03*
X400983Y400985D03*
X404920Y397048D03*
Y400985D03*
Y389174D03*
X412794Y397048D03*
Y389174D03*
X408857Y397048D03*
X400983D03*
X404920Y393111D03*
X410826Y414764D03*
X406889D03*
X402952D03*
X408857Y416733D03*
Y408859D03*
X412794Y416733D03*
Y408859D03*
X400983Y404922D03*
X412794Y412796D03*
X404920Y404922D03*
X408857D03*
Y412796D03*
X412794Y404922D03*
X404920Y416733D03*
X400983D03*
X410826Y422638D03*
Y418701D03*
X406889Y422638D03*
Y418701D03*
X402952D03*
X408857Y424607D03*
X412794D03*
X408857Y420670D03*
X412794D03*
X404555Y430500D03*
X404920Y420670D03*
X406555Y428300D03*
X399555Y438500D03*
X428375Y119735D03*
X418940Y125000D03*
X415552Y136221D03*
X421590Y128500D03*
X418702Y136221D03*
X413540Y128500D03*
X425000Y136220D03*
X428116Y136218D03*
X421851Y136221D03*
X423686Y126215D03*
X415549Y151990D03*
X418702Y142520D03*
X425001D03*
X421851D03*
X415552D03*
X428151D03*
X418700Y148818D03*
X428149D03*
X415551D03*
X424999D03*
X421850D03*
X428149Y164565D03*
Y170865D03*
X421876Y167705D03*
X415575Y167703D03*
X424999Y161416D03*
X428149D03*
X418726Y167703D03*
X428149Y183463D03*
Y177164D03*
X421876Y174005D03*
Y180304D03*
Y186603D03*
X415551Y186614D03*
X415587Y180315D03*
X415551Y174015D03*
X418726Y174003D03*
Y180303D03*
X418701Y186614D03*
X424999Y199211D03*
X428149D03*
X424999Y202361D03*
X428149D03*
X421876Y192902D03*
X428149Y192912D03*
X415551D03*
X424999D03*
X418727Y192902D03*
X418701Y211810D03*
X425001D03*
X428150D03*
X415551D03*
X421850D03*
X428172Y221320D03*
X424979Y218127D03*
X428047Y218049D03*
X415551Y218109D03*
X418729Y218100D03*
X421850Y218109D03*
X418729Y221268D03*
X420500Y234500D03*
X422630Y227232D03*
X426147Y230982D03*
X420714Y225190D03*
X429444Y230192D03*
X419000Y227405D03*
X427965Y318293D03*
X419913Y318051D03*
X417650Y316400D03*
X416482Y319022D03*
X424555Y318000D03*
X420668Y330117D03*
X428542D03*
X420668Y334054D03*
X428542D03*
X424023Y320783D03*
X424605Y334054D03*
Y330117D03*
X416731D03*
X416950Y321783D03*
X416731Y334054D03*
X424605Y345865D03*
X420668Y337991D03*
X428542Y345865D03*
X416615Y349930D03*
X428542Y349802D03*
Y341928D03*
X424605Y337991D03*
X428542D03*
X420668Y341928D03*
X424605Y349802D03*
X420668D03*
X416731Y337991D03*
X420668Y345865D03*
X416731Y341928D03*
X424605D03*
Y369487D03*
Y361613D03*
Y353739D03*
X428542Y361613D03*
Y369487D03*
Y353739D03*
X416731D03*
X420668Y357676D03*
X428542Y365550D03*
X416731Y369487D03*
X420668Y353739D03*
X416731Y365550D03*
X424605D03*
X420668D03*
X416731Y361613D03*
X420668Y369487D03*
X424605Y357676D03*
X420668Y361613D03*
X416555Y357500D03*
X428542Y357676D03*
X424605Y385237D03*
X428542D03*
Y381300D03*
X428500Y377000D03*
X416731Y381300D03*
Y377363D03*
X428445Y373550D03*
X420668Y377363D03*
Y385237D03*
X416731D03*
X424605Y381300D03*
X420668D03*
X428542Y400985D03*
X424605D03*
Y393111D03*
X428542Y397048D03*
X420668Y400985D03*
X416731Y389174D03*
X428555Y393000D03*
X420668Y389174D03*
X416731Y393111D03*
Y397048D03*
X420668Y393111D03*
X424605Y397048D03*
X428542Y389174D03*
X420668Y397048D03*
X416731Y400985D03*
X424605Y389174D03*
Y404922D03*
Y408859D03*
X420668Y404922D03*
X428542Y408859D03*
X420668D03*
X428542Y404922D03*
X428523Y416683D03*
X416731Y416733D03*
Y404922D03*
Y412796D03*
X424605D03*
X423555Y431500D03*
X416731Y420670D03*
Y424607D03*
X419500Y914000D03*
X432540Y123000D03*
X435640D03*
X437599Y136221D03*
X434450D03*
X439540Y124500D03*
X431407Y136285D03*
X440931Y129061D03*
X431348Y125911D03*
X442323Y126000D03*
X437945Y127159D03*
X434449Y155118D03*
X431300Y142520D03*
X437599D03*
X437598Y148818D03*
Y155118D03*
X434450Y142520D03*
X440765Y145670D03*
X443928Y148811D03*
X443891Y151999D03*
X443890Y142565D03*
X443909Y145650D03*
X443936Y155118D03*
X431299Y164565D03*
Y170865D03*
X434449Y167716D03*
Y161417D03*
X431299Y161416D03*
X437598Y167716D03*
Y161417D03*
X443899Y161430D03*
X443882Y167737D03*
X443899Y164530D03*
X443871Y158278D03*
X431299Y183463D03*
X434449Y180314D03*
Y174015D03*
X431299Y177164D03*
X434448Y186613D03*
X431299D03*
X437598Y174015D03*
Y180314D03*
Y186614D03*
X443910Y174041D03*
X443879Y180320D03*
X443887Y177138D03*
X440769Y183480D03*
X443919D03*
X434414Y205514D03*
X434449Y199212D03*
Y192913D03*
X437598Y205511D03*
Y199212D03*
Y192913D03*
X443897Y205512D03*
Y192914D03*
X443898Y199212D03*
X443897Y202363D03*
Y196063D03*
X434449Y211810D03*
X437598D03*
X443897Y211811D03*
Y208662D03*
X431336Y218111D03*
X434448Y218109D03*
X437598D03*
X436529Y229500D03*
X434334Y226789D03*
X443113Y226339D03*
X439980Y232126D03*
X441379Y229700D03*
X432307Y224857D03*
X437112Y232239D03*
X445892Y225995D03*
X436500Y241000D03*
X438500Y250000D03*
X431023Y317283D03*
X430513Y320841D03*
X436416Y330117D03*
X444290D03*
X440353D03*
X434448Y320783D03*
X440353Y334054D03*
X432523Y330283D03*
X444555Y334000D03*
X441335Y321000D03*
X436416Y334054D03*
X440353Y349802D03*
X444290D03*
X440353Y341928D03*
X436416Y345865D03*
X432585Y345850D03*
X444290Y341928D03*
X432365Y341880D03*
X444290Y337991D03*
X432605Y337880D03*
X444290Y345865D03*
X440353D03*
X440555Y338000D03*
X440353Y369487D03*
X444290Y365550D03*
X440353Y353739D03*
X444290Y357676D03*
X432479Y369487D03*
Y361613D03*
X444290Y369487D03*
X436416D03*
X440353Y357676D03*
X444290Y353739D03*
X440353Y365550D03*
X436416Y353739D03*
Y361613D03*
X444290Y385237D03*
Y377363D03*
X440353Y381300D03*
X432479Y385237D03*
X436416Y377363D03*
X432479D03*
Y381300D03*
X444290D03*
X440353Y377363D03*
X436416Y381300D03*
X440353Y400985D03*
Y389174D03*
X432479Y400985D03*
Y397048D03*
Y393111D03*
Y389174D03*
X444290Y397048D03*
X440353D03*
X436416D03*
X444290Y400985D03*
X436416D03*
X444290Y389174D03*
X436416D03*
X432479Y408859D03*
Y404922D03*
X436416D03*
Y408859D03*
X444290Y404922D03*
Y408859D03*
X440353D03*
Y404922D03*
X444323Y416883D03*
X436523Y416683D03*
X440353Y412796D03*
X432479D03*
X442535Y426770D03*
X434723Y426283D03*
X448669Y126510D03*
X450209Y129230D03*
X447389Y129580D03*
X454676Y137495D03*
X456429Y135000D03*
X457929Y132500D03*
X451679Y148250D03*
X461685Y150386D03*
X455731Y154302D03*
X460300Y141100D03*
X454929Y146500D03*
X453929Y140334D03*
X459069Y151980D03*
X451329Y165570D03*
X453599Y156693D03*
X458429Y185000D03*
X450196Y189764D03*
X454329Y199800D03*
X452929Y203900D03*
X452329Y194300D03*
X447063Y199234D03*
X447047Y189764D03*
X451292Y197637D03*
X456479Y202400D03*
X455929Y192800D03*
X456229Y196700D03*
X453829Y215600D03*
X453729Y219300D03*
X452393Y210236D03*
X458029Y213469D03*
X457798Y217769D03*
X457729Y206800D03*
X448840Y225775D03*
X455429Y227500D03*
X451929Y229800D03*
X456929Y224507D03*
X456103Y330117D03*
X460040D03*
X448227D03*
X452223Y333983D03*
X448227Y334054D03*
X460040D03*
X456103D03*
X460040Y349802D03*
Y341928D03*
X448227Y349802D03*
Y341928D03*
X456103D03*
X460040Y337991D03*
X455825Y349840D03*
X448000Y346000D03*
X456055Y338000D03*
X452055D03*
X452165Y349470D03*
X456103Y365550D03*
Y357676D03*
X460040Y369487D03*
Y361613D03*
X448227Y369487D03*
Y361613D03*
Y353739D03*
X456103Y369487D03*
Y353739D03*
Y361613D03*
X460040Y357676D03*
Y365550D03*
X448227D03*
Y357676D03*
X456103Y385237D03*
Y377363D03*
X460040Y381300D03*
X448227D03*
X460040Y385237D03*
X456103Y381300D03*
X460040Y377363D03*
X448227Y385237D03*
Y377363D03*
X460040Y389174D03*
X448227D03*
X456103Y400985D03*
X460040D03*
X456103Y393111D03*
X460040D03*
Y397048D03*
X448227Y400985D03*
Y393111D03*
X456103Y397048D03*
X448227D03*
X456103Y389174D03*
X456223Y404883D03*
Y408783D03*
X456103Y412796D03*
X460023Y408883D03*
X452123Y416783D03*
X460040Y412796D03*
X448227D03*
X452223Y404883D03*
X448227Y408859D03*
X452223Y408783D03*
X448227Y404922D03*
X450725Y425460D03*
X471480Y105660D03*
X466464Y151000D03*
X466500Y144500D03*
X463969Y147610D03*
X469429Y172500D03*
Y165590D03*
X473131Y169131D03*
X477429Y162500D03*
X469429Y179500D03*
X465679Y192600D03*
X464570Y215750D03*
X467300Y320100D03*
X471851Y322243D03*
Y326180D03*
X463977Y330117D03*
X467914D03*
X463977Y334054D03*
X467914D03*
X475788Y330117D03*
Y349802D03*
Y341928D03*
X467914Y349802D03*
X463977Y341928D03*
X471851Y337991D03*
X467914D03*
X463977D03*
X471851Y349802D03*
X467914Y345865D03*
X475788Y369487D03*
Y361613D03*
Y357676D03*
X467914Y369487D03*
Y361613D03*
Y365550D03*
Y357676D03*
Y353739D03*
X463977Y365550D03*
Y357676D03*
X471851Y361613D03*
Y369487D03*
Y353739D03*
Y357676D03*
X463977Y369487D03*
Y361613D03*
Y385237D03*
X475788Y381300D03*
Y377363D03*
X467914Y385237D03*
Y377363D03*
Y381300D03*
X463977Y377363D03*
X471851D03*
Y381300D03*
X463977D03*
X475788Y400985D03*
Y397048D03*
Y393111D03*
X471851D03*
Y397048D03*
X475788Y389174D03*
X467914Y400985D03*
Y397048D03*
Y393111D03*
Y389174D03*
X463977Y393111D03*
Y397048D03*
Y400985D03*
X471851D03*
Y389174D03*
X463977D03*
Y408859D03*
Y404922D03*
X467914Y408859D03*
Y404922D03*
X471851Y412796D03*
X475788D03*
X471851Y416733D03*
X467914Y412796D03*
X475788Y424607D03*
X480500Y181800D03*
X493855Y312700D03*
X488155Y315700D03*
X490455Y319200D03*
X481255Y320000D03*
X483955Y318600D03*
X493504Y332086D03*
Y328149D03*
Y324212D03*
X491536Y334054D03*
X479725Y330117D03*
X479655Y322500D03*
X487500Y333833D03*
X483662Y334054D03*
X487599Y330117D03*
X483662Y326180D03*
X484000Y322000D03*
X487599Y326180D03*
X487155Y321900D03*
X483662Y330117D03*
X491536Y341928D03*
X479725Y337991D03*
X487599D03*
X483662D03*
Y341928D03*
X487599D03*
X483662Y345865D03*
X487599Y349802D03*
X483662D03*
X487599Y345865D03*
X479725Y341928D03*
Y349802D03*
X487603Y369483D03*
X483662Y357676D03*
X487599D03*
X483663Y365463D03*
X483662Y361613D03*
Y353739D03*
X487599D03*
X483683Y369403D03*
X479725Y369487D03*
Y361613D03*
X487643Y361523D03*
X491500Y353500D03*
X491536Y369487D03*
Y361613D03*
X479725Y365550D03*
Y357676D03*
X491536Y385237D03*
Y377363D03*
X479725Y381300D03*
X491536D03*
X479725Y385237D03*
Y377363D03*
X491536Y400985D03*
Y393111D03*
X479725Y397048D03*
Y389174D03*
X491536Y397048D03*
Y389174D03*
X479725Y400985D03*
Y393111D03*
X493504Y414764D03*
X491536Y416733D03*
Y408859D03*
X487599Y416733D03*
X483662Y408859D03*
X487599Y404922D03*
X479725Y412796D03*
X491536D03*
Y404922D03*
X483662Y412796D03*
Y404922D03*
X479725Y416733D03*
X493504Y422638D03*
Y418701D03*
X491536Y420670D03*
Y424607D03*
X483662D03*
X487599D03*
Y420670D03*
X505678Y310921D03*
X506000Y317500D03*
X498855Y311100D03*
X498955Y316900D03*
X501378Y332086D03*
Y328149D03*
X497441Y332086D03*
Y328149D03*
Y324212D03*
X505523Y332086D03*
X499410Y322243D03*
X495473Y334054D03*
X511500Y348000D03*
X511455Y338700D03*
X495473Y341928D03*
X505523Y363582D03*
X507955Y356100D03*
X505523Y371456D03*
X503347Y381300D03*
X495473Y385237D03*
Y377363D03*
X503347Y397048D03*
Y389174D03*
X495473Y400985D03*
Y393111D03*
X501378Y414764D03*
X497441D03*
X499410Y416733D03*
Y412796D03*
Y408859D03*
X503347D03*
Y404922D03*
X495473Y416733D03*
Y412796D03*
Y408859D03*
X501378Y418701D03*
X497441Y422638D03*
Y418701D03*
X499410Y420670D03*
Y424607D03*
X503347Y420670D03*
X495473Y424607D03*
Y420670D03*
X513407Y311502D03*
X513500Y315800D03*
X522345Y311699D03*
X522365Y316365D03*
X521800Y322000D03*
X527667Y322182D03*
X523500Y347500D03*
Y352000D03*
Y342000D03*
X523100Y364300D03*
X526800Y359600D03*
X519500Y365500D03*
X523500Y357500D03*
X538875Y138000D03*
X533441Y211775D03*
X542000Y249000D03*
X528600Y316700D03*
X539300Y317600D03*
X534000Y317500D03*
X539200Y324100D03*
X530000Y342000D03*
X529400Y352800D03*
X530100Y347200D03*
X546500Y147500D03*
X559750Y264500D03*
X547500Y360168D03*
X568500Y147500D03*
X563250Y262500D03*
X579221Y237250D03*
X580828Y260028D03*
X604500Y205000D03*
Y200500D03*
X603500Y218500D03*
Y214000D03*
X605000Y209500D03*
X594500Y236000D03*
X604500Y227500D03*
Y223000D03*
X599000Y804000D03*
X622500Y696500D03*
X625000Y706000D03*
X632500Y530000D03*
X691400Y231100D03*
X710100Y182700D03*
X720500Y478750D03*
X723000Y996500D03*
X731498D03*
X739368Y996610D03*
X727558Y996500D03*
X756000Y180000D03*
X780000Y250000D03*
X862500Y65000D03*
X866112Y85626D03*
X865000Y488500D03*
X874000Y56000D03*
X873500Y61500D03*
X884500Y323500D03*
X881000Y736500D03*
X902000Y63000D03*
X935000Y51500D03*
X937000Y63000D03*
X945000Y141500D03*
X947500Y153000D03*
X959900Y180700D03*
X974500Y188500D03*
X975007Y194300D03*
X1002500Y653000D03*
X1001100Y776500D03*
X1015000Y477500D03*
X1011500Y667500D03*
X1022000Y492500D03*
X1022500Y637500D03*
X1027504Y853366D03*
X1045000Y266600D03*
X1041410Y695394D03*
Y690694D03*
Y699834D03*
X1055000Y214500D03*
X1055500Y360000D03*
X1062940Y629945D03*
X1065978Y664568D03*
X1063056Y681554D03*
X1062700Y672600D03*
X1054080Y680630D03*
X1061696Y761294D03*
X1061356Y753354D03*
X1084500Y223500D03*
X1074000Y660500D03*
X1074500Y665500D03*
X1102000Y250000D03*
X1102500Y264500D03*
X1089500Y405000D03*
X1088000Y461000D03*
X1088400Y647484D03*
X1103300Y492000D03*
X1113500Y614250D03*
X1113000Y630500D03*
X1105000D03*
X1114500Y645000D03*
X1118630Y714820D03*
X1110790Y738850D03*
X1116550Y783600D03*
X1119060Y791083D03*
X1132500Y333000D03*
X1126500Y614500D03*
X1132423Y663902D03*
X1135553Y663957D03*
X1132440Y676555D03*
X1129272Y673350D03*
X1129271Y670275D03*
X1126102Y676518D03*
X1122985Y670262D03*
X1122938Y676540D03*
X1132402Y673405D03*
X1132398Y667102D03*
X1129290Y676555D03*
X1126121Y679722D03*
X1132421Y679648D03*
X1132395Y670225D03*
X1126117Y685952D03*
X1129273Y689170D03*
X1126122Y689171D03*
X1129290Y692303D03*
X1126116Y692279D03*
X1132423Y695469D03*
X1132440Y692265D03*
Y686004D03*
X1132434Y682860D03*
X1129278Y682804D03*
X1119265Y683864D03*
X1135551Y685967D03*
X1129289Y686005D03*
X1126157Y695435D03*
X1129238Y704878D03*
X1132440Y701714D03*
X1129270D03*
X1126121Y711218D03*
X1129285Y708056D03*
X1126114Y701703D03*
X1126093Y704874D03*
X1132406Y704904D03*
X1132440Y698564D03*
X1129290D03*
X1126155Y708029D03*
X1132445Y714345D03*
X1129260Y714350D03*
X1135570Y711218D03*
X1126121Y714368D03*
X1132417Y711189D03*
X1129277Y711210D03*
X1128959Y729952D03*
X1126969Y727981D03*
X1132398Y720624D03*
X1132459Y717481D03*
X1127183Y740805D03*
X1126671Y744629D03*
X1126885Y736721D03*
X1123393Y743726D03*
X1124497Y734140D03*
X1124326Y738960D03*
X1126955Y731909D03*
X1124978Y747578D03*
X1130900Y766700D03*
X1124460Y768140D03*
X1125900Y764200D03*
X1129501Y776929D03*
X1134245Y769145D03*
X1127945Y769970D03*
X1121215Y769936D03*
X1120400Y781600D03*
X1126360Y792640D03*
X1127160Y788837D03*
X1129497Y792673D03*
X1130610Y788820D03*
X1134145Y788450D03*
X1132684Y792636D03*
X1124360Y788390D03*
X1132600Y784822D03*
X1120529Y786350D03*
X1123254Y792663D03*
X1131095Y799965D03*
X1124796Y800150D03*
X1135000Y810000D03*
X1134244Y799984D03*
X1121000Y808500D03*
X1127945Y799935D03*
X1121646Y799924D03*
X1123500Y832470D03*
X1135500Y835000D03*
X1144425Y325500D03*
X1143000Y629000D03*
X1138757Y663937D03*
X1151337Y660807D03*
X1151354Y663936D03*
X1148150Y663956D03*
X1141900Y663944D03*
X1148188Y667106D03*
Y670256D03*
X1151282Y667088D03*
X1141600Y673590D03*
X1141868Y680064D03*
X1151337Y670256D03*
X1141954Y676581D03*
X1135589Y673368D03*
X1144983Y667085D03*
X1145020Y670200D03*
X1136150Y676500D03*
X1135685Y679613D03*
X1135598Y667080D03*
X1135595Y670225D03*
X1141868Y670273D03*
X1138708Y667113D03*
X1139245Y675106D03*
X1135589Y682854D03*
Y695415D03*
X1151300Y682854D03*
Y692303D03*
Y689153D03*
Y686004D03*
Y695452D03*
X1148150D03*
Y692303D03*
Y689153D03*
Y686004D03*
Y682854D03*
X1139858Y692074D03*
X1139000Y685667D03*
X1144880Y707720D03*
X1145000Y711200D03*
X1138729Y714360D03*
X1151307Y714306D03*
X1141765Y711030D03*
X1145053Y714327D03*
X1148169Y711219D03*
X1141840Y714339D03*
X1138320Y710066D03*
X1151300Y698602D03*
X1148150D03*
X1135589Y701714D03*
X1151352Y711178D03*
X1140710Y707750D03*
X1138400Y705300D03*
X1136304Y707482D03*
X1151318Y717518D03*
X1148135Y720634D03*
X1138685Y720633D03*
X1141870Y717518D03*
X1148167Y717517D03*
X1138730Y717480D03*
X1141904Y720633D03*
X1150734Y736950D03*
X1149470Y734451D03*
X1137030Y745300D03*
X1146370Y769310D03*
X1142095Y773774D03*
X1151564Y776924D03*
X1146200Y766300D03*
X1142323Y780250D03*
X1138961Y776940D03*
X1145265Y776945D03*
X1151592Y773748D03*
X1150310Y783840D03*
X1142120Y795830D03*
X1145270D03*
X1138970D03*
X1145270Y792670D03*
X1141700Y785113D03*
X1138545Y787952D03*
X1145740Y789140D03*
X1138931Y792658D03*
X1142086Y789513D03*
X1136236Y782142D03*
X1151590Y792660D03*
X1143470Y782805D03*
X1140650Y782496D03*
X1151565Y787951D03*
X1142110Y792660D03*
X1149400Y800000D03*
X1142010Y809500D03*
X1141100Y831600D03*
X1159100Y640800D03*
X1157599Y663956D03*
X1167098Y663932D03*
X1160748Y660807D03*
Y657657D03*
X1160741Y663949D03*
X1163946Y663946D03*
X1157613Y673418D03*
X1167692Y674996D03*
X1160768Y676535D03*
X1154470Y673363D03*
X1152090Y677010D03*
X1154218Y679964D03*
X1154496Y667096D03*
X1163917Y670275D03*
X1160741Y667099D03*
X1163914Y673352D03*
X1167034Y667092D03*
X1157655Y667087D03*
X1160770Y673421D03*
X1163944Y667076D03*
X1154487Y670256D03*
X1160748Y682854D03*
X1157599Y686004D03*
X1154449D03*
Y682854D03*
Y689153D03*
X1160748Y695452D03*
X1157599D03*
Y692303D03*
X1154449Y695452D03*
Y692303D03*
X1163898Y695452D03*
X1160748Y692303D03*
X1163898D03*
X1157599Y689153D03*
X1160748D03*
X1163898D03*
X1160748Y686004D03*
X1163898D03*
X1157670Y707960D03*
X1167048Y714312D03*
X1163968Y708000D03*
X1154434Y714335D03*
X1157581Y714331D03*
X1163905Y711206D03*
X1157636Y711200D03*
X1163898Y698602D03*
X1160748D03*
X1157599D03*
X1154449D03*
X1167103Y711107D03*
X1167000Y727500D03*
X1157637Y717463D03*
X1157643Y720642D03*
X1152248Y730404D03*
X1154430Y717481D03*
X1152400Y727600D03*
X1167049Y717501D03*
X1167048Y720612D03*
X1163898Y717462D03*
Y720612D03*
X1157112Y731702D03*
X1164200Y744500D03*
X1157000Y734500D03*
X1166100Y731500D03*
X1152023Y733299D03*
X1163830Y747899D03*
X1158100Y769700D03*
X1162450Y769190D03*
X1167002Y767508D03*
X1167326Y776936D03*
X1167320Y770290D03*
X1157871Y773728D03*
X1161051Y792660D03*
X1164196Y795814D03*
X1153219Y781303D03*
X1161545Y788844D03*
X1162693Y780865D03*
X1158092Y787715D03*
X1154712Y792690D03*
X1165492Y780957D03*
X1154200Y788900D03*
X1154700Y795790D03*
X1161022Y785693D03*
X1165063Y787500D03*
X1167410Y785530D03*
X1167330Y795830D03*
X1163605Y783513D03*
X1167277Y792658D03*
X1157866Y795844D03*
X1154800Y799000D03*
X1165300Y809610D03*
X1160300D03*
X1154300D03*
X1155390Y818000D03*
X1157990Y827000D03*
X1173332Y663938D03*
X1176506Y663916D03*
X1176525Y679676D03*
X1170181Y670240D03*
X1176503Y670218D03*
X1182803Y670234D03*
X1176534Y673368D03*
X1179653Y670234D03*
X1173309Y673406D03*
X1179662Y673421D03*
X1176534Y676555D03*
X1179667Y679655D03*
X1182831Y679666D03*
X1182815Y676573D03*
X1170192Y667100D03*
X1176526Y667092D03*
X1173403Y670237D03*
X1173349Y667099D03*
X1182785Y685977D03*
X1176520Y685970D03*
X1179663Y685959D03*
X1173365Y695397D03*
X1169800Y682200D03*
X1173392Y685974D03*
X1173389Y689121D03*
X1176482Y682840D03*
X1176529Y692276D03*
X1179685Y692292D03*
X1176496Y695415D03*
X1179664Y695466D03*
X1182796Y695415D03*
X1179678Y689111D03*
X1182817Y689155D03*
X1173384Y692265D03*
X1182815Y701696D03*
X1182796Y708013D03*
X1182813Y698619D03*
X1176496Y698564D03*
X1179671Y698565D03*
X1170248Y714330D03*
X1173350Y698590D03*
X1179703Y714331D03*
X1173347Y714350D03*
X1176503Y714342D03*
X1176515Y704845D03*
X1179676Y711207D03*
X1179660Y704850D03*
X1171200Y706170D03*
X1179660Y708050D03*
X1176515Y708045D03*
X1173015Y708329D03*
X1176515Y711144D03*
X1173262Y711119D03*
X1182802Y714356D03*
X1169282Y729708D03*
X1173400Y717480D03*
X1176499Y720609D03*
X1170199Y717501D03*
X1173348Y720613D03*
X1176489Y717469D03*
X1171500Y733725D03*
X1175000Y734870D03*
X1171108Y777368D03*
X1170950Y795960D03*
X1170911Y784912D03*
X1170718Y782118D03*
X1170300Y809610D03*
X1185965Y676573D03*
X1190500Y674207D03*
X1185945Y695415D03*
X1190000Y699500D03*
X1196000Y710500D03*
X1190000Y705500D03*
X1201250Y627000D03*
X1203500Y698520D03*
X1218040Y719850D03*
X1249773Y551500D03*
X1249000Y723250D03*
X1258562Y672438D03*
X1259000Y699500D03*
X1257500Y710500D03*
X1259500Y724000D03*
X1279600Y694800D03*
X1276000Y694000D03*
X1272700Y694900D03*
X1277000Y712500D03*
X1272500D03*
X1275000Y732000D03*
X1287962Y710490D03*
X1289500Y716500D03*
X1292500Y730478D03*
X1305000Y596500D03*
X1306423Y608164D03*
X1305217Y612412D03*
X1305435Y603918D03*
X1306443Y618985D03*
X1307150Y691500D03*
X1307000Y729100D03*
X1310500Y737500D03*
X1307000Y732500D03*
X1300491Y732991D03*
X1319400Y522100D03*
X1318700Y533500D03*
X1322900Y524600D03*
X1322400Y533100D03*
X1318000Y696500D03*
X1319000Y708000D03*
X1354900Y522600D03*
X1351900Y524600D03*
X1352400Y533600D03*
X1355900Y536600D03*
X1381415Y581195D03*
X1379600Y584200D03*
X1378800Y594900D03*
X1380925Y598315D03*
X1377800Y603800D03*
X1378082Y614266D03*
X1381637Y611225D03*
X1381578Y607117D03*
X1377996Y610847D03*
X1380925Y602035D03*
X1377996Y607382D03*
X1385135Y581195D03*
X1387200Y584100D03*
X1384400Y598300D03*
Y601900D03*
G54D181*
G01X74304Y839970D02*
Y829696D01*
X74750Y829250D01*
X99750D01*
X105000Y834500D01*
G01X89022Y770504D02*
Y772102D01*
X86404Y774720D01*
G01X106654Y794785D02*
X101069D01*
X100104Y793820D01*
G01X92554Y790220D02*
X95954Y793620D01*
X99904D01*
X100104Y793820D01*
G01X106654Y796750D02*
X96974D01*
X96404Y797320D01*
G01X92554Y798220D02*
X95504D01*
X96404Y797320D01*
G01X105000Y834500D02*
X120000Y849500D01*
Y862500D01*
X128000Y870500D01*
G01X130000Y678500D02*
X130250Y678750D01*
X134000D01*
G01X137554Y783720D02*
X131304Y789970D01*
X131204D01*
G01X122954Y794785D02*
X126939D01*
X131204Y790520D01*
Y789970D01*
G01X122954Y796750D02*
X133174D01*
G01X134000Y678750D02*
Y674750D01*
G01Y678750D02*
X137000D01*
X139000Y680750D01*
X143500D01*
G01X139625Y688460D02*
X135960D01*
X134000Y686500D01*
G01D02*
Y682250D01*
G01X137554Y791720D02*
Y792370D01*
X133174Y796750D01*
G01X142400Y844280D02*
X145780D01*
G01X142400Y846840D02*
X145660D01*
X146500Y846000D01*
Y845000D01*
X145780Y844280D01*
G01X149250Y848000D02*
Y844000D01*
G01D02*
X148970Y844280D01*
X145780D01*
G01X149250Y848000D02*
Y851750D01*
G01X161805Y530000D02*
X157305D01*
G01X161805D02*
Y525750D01*
G01X157305Y530000D02*
X159555Y532250D01*
Y536250D01*
G01X165305Y530000D02*
X169555D01*
G01X166000Y666500D02*
X161250D01*
G01X153500Y674250D02*
Y678750D01*
G01D02*
X157500D01*
X159500Y680750D01*
X163000D01*
G01X159125Y688960D02*
X156960D01*
X154500Y686500D01*
G01X153500Y682250D02*
Y685500D01*
X154500Y686500D01*
G01X171500Y681500D02*
X163750D01*
X163000Y680750D01*
G01X168495Y524625D02*
X169555Y525685D01*
Y530000D01*
G01X166000Y662500D02*
Y666500D01*
G01X351250Y893000D02*
X348250Y890000D01*
X332758D01*
X332129Y889371D01*
G01X374018Y991000D02*
Y1008860D01*
G01X373678Y985750D02*
X374018Y986090D01*
Y991000D01*
G01X377953Y1008860D02*
Y1002225D01*
X380103Y1000075D01*
Y990132D01*
X377464Y987493D01*
G01X623917Y70118D02*
X623878Y70157D01*
Y80820D01*
X636522Y93464D01*
X638876D01*
G01X631909Y70118D02*
X632500Y70709D01*
Y81450D01*
X642550Y91500D01*
X646290D01*
X647876Y93086D01*
Y93464D01*
G01X635945Y80118D02*
X640894Y85067D01*
Y85106D01*
X645788Y90000D01*
X648912D01*
X652376Y93464D01*
G01X627953Y80118D02*
X628618D01*
X641964Y93464D01*
X643376D01*
G01X639300Y609900D02*
X646700D01*
G01D02*
X647285Y609315D01*
X654629D01*
X655194Y608750D01*
X662492D01*
X662692Y608550D01*
X674050D01*
X677500Y612000D01*
G01X669280Y111000D02*
X664998Y106718D01*
Y94120D01*
X668824Y90294D01*
X674666D01*
G01X677416Y94544D02*
X674666Y91794D01*
Y90294D01*
G01X669280Y111000D02*
X674210D01*
X677336Y107874D01*
G01X674122Y126682D02*
X669430D01*
X664748Y122000D01*
Y115532D01*
X669280Y111000D01*
G01X678222Y126342D02*
X674462D01*
X674122Y126682D01*
G01X681826Y94934D02*
X677806D01*
X677416Y94544D01*
G01X677336Y107874D02*
X677720Y107490D01*
X681322D01*
X681576Y107744D01*
X681836D01*
G01X681748Y134000D02*
X678578Y130830D01*
Y126698D01*
X678222Y126342D01*
G01X690512Y129702D02*
Y133136D01*
X687228Y136420D01*
X684168D01*
X681748Y134000D01*
G01X704933Y98147D02*
Y105185D01*
X707716Y107968D01*
Y110457D01*
G01X699716Y137284D02*
X702964D01*
X707716Y132532D01*
Y132111D01*
G01X693055Y261500D02*
X696655Y265100D01*
Y273306D01*
X706332Y282983D01*
Y298068D01*
X706494Y298230D01*
G01X692555Y267500D02*
Y274794D01*
X697959Y280198D01*
Y292404D01*
X702555Y297000D01*
Y309000D01*
X709500Y315945D01*
X710434D01*
G01X724532Y61966D02*
X720032D01*
G01X710748Y100000D02*
X710733Y102885D01*
X712858Y105010D01*
Y107784D01*
G01X716795Y134784D02*
Y141953D01*
X715748Y143000D01*
G01X718763Y134784D02*
Y139400D01*
X719819Y140456D01*
Y140468D01*
X719839Y140488D01*
G01X720732Y134784D02*
Y137984D01*
X722787Y140039D01*
Y142485D01*
X723248Y142946D01*
Y144500D01*
G01X714826Y134784D02*
Y139422D01*
X710748Y143500D01*
Y144000D01*
G01X727216Y148534D02*
Y144792D01*
X724287Y141863D01*
Y139039D01*
X722700Y137452D01*
Y134784D01*
G01X713716Y148534D02*
Y145032D01*
X715748Y143000D01*
G01X718216Y148534D02*
X719819Y146931D01*
Y140508D01*
X719839Y140488D01*
G01X722716Y148534D02*
X723248Y148002D01*
Y144500D01*
G01X709216Y148534D02*
X710748Y147002D01*
Y144000D01*
G01X732500Y478750D02*
X738500Y472750D01*
Y457500D01*
X716500Y435500D01*
Y320500D01*
X715000Y319000D01*
Y308701D01*
X714369Y308070D01*
G01X728500Y61500D02*
X728034Y61966D01*
X724532D01*
G01X737200Y58720D02*
X734780D01*
X732000Y61500D01*
X728500D01*
G01X748248Y118500D02*
X748079Y118331D01*
X735216D01*
G01X746500Y105000D02*
Y106500D01*
X740574Y112426D01*
X735216D01*
G01X731716Y148534D02*
X727216D01*
G01X731716Y144984D02*
Y148534D01*
G01D02*
X736032D01*
X736248Y148750D01*
G01Y152250D02*
X735500Y152998D01*
Y155400D01*
X737600Y157500D01*
X744000D01*
G01X725000Y452300D02*
X724750Y452550D01*
Y455500D01*
G01D02*
X724940Y455690D01*
Y464572D01*
G01X727500Y471072D02*
Y478000D01*
X728250Y478750D01*
X732500D01*
G01X724250Y899000D02*
X728250Y903000D01*
X737290D01*
G01X744000Y157500D02*
X744252Y157752D01*
X804514D01*
X1015125Y368363D01*
Y374184D01*
X1038775Y397834D01*
Y397875D01*
X1039250Y398350D01*
Y475388D01*
X1043175Y479313D01*
Y538675D01*
X1071500Y567000D01*
Y589000D01*
G01X744000Y465500D02*
X744125Y465375D01*
X749750D01*
G01X753214Y471538D02*
Y468839D01*
X749750Y465375D01*
G01X749714Y471538D02*
Y476038D01*
G01Y471538D02*
X744038D01*
X744000Y471500D01*
G01X749714Y476038D02*
Y482986D01*
X749700Y483000D01*
G01X775750Y644500D02*
X771000D01*
G01X775750Y649000D02*
X771500Y653250D01*
X764000D01*
G01X768750Y668000D02*
X767875Y667125D01*
Y660750D01*
G01X772250Y668000D02*
X776250D01*
G01X772250D02*
Y672250D01*
G01X764500Y668000D02*
X768750D01*
G01X766250Y698500D02*
Y695250D01*
X768746Y692754D01*
X774938D01*
G01X766250Y698500D02*
Y707552D01*
X765998Y707804D01*
G01D02*
X760646D01*
X760500Y707950D01*
G01X765998Y711304D02*
X770498D01*
G01D02*
X775196D01*
X775500Y711000D01*
G01X770498Y707804D02*
Y703502D01*
X774271Y699729D01*
G01X826198Y239950D02*
Y260302D01*
X824500Y262000D01*
Y290626D01*
X820126Y295000D01*
X815862D01*
X813834Y297028D01*
Y310666D01*
X808000Y316500D01*
Y316966D01*
X803966Y321000D01*
X778500D01*
X773500Y326000D01*
G01X775750Y649000D02*
Y644500D01*
G01X776250Y668000D02*
X775534Y667284D01*
Y658532D01*
G01X792500Y658250D02*
X788500D01*
G01Y653000D02*
X786843Y654657D01*
X783034D01*
G01X788500Y658250D02*
X786627D01*
X783034Y654657D01*
G01X780058Y685354D02*
Y676864D01*
X779998Y676804D01*
G01D02*
X777498Y679304D01*
Y685354D01*
G01X774938Y692754D02*
Y690562D01*
X776000Y689500D01*
X784682D01*
X828500Y645682D01*
Y610500D01*
X857500Y581500D01*
Y485500D01*
G01X780058Y685354D02*
X780204Y685500D01*
X785500D01*
G01X777498Y692754D02*
Y696502D01*
X774271Y699729D01*
G01X775500Y711000D02*
Y717500D01*
G01X789968Y743784D02*
X776500D01*
X775500Y742784D01*
Y717500D01*
G01X793500Y733500D02*
X791000D01*
X790300Y732800D01*
X787000D01*
G01X805750Y363500D02*
X808500D01*
G01X805250D02*
X803500D01*
G01X804968Y763784D02*
X805000Y763752D01*
Y757500D01*
X794968Y747468D01*
Y743784D01*
G01D02*
Y738468D01*
X794000Y737500D01*
G01X793500Y733500D02*
Y737000D01*
X794000Y737500D01*
G01X798000Y731750D02*
X795250D01*
X793500Y733500D01*
G01X794968Y763784D02*
Y759968D01*
X790000Y755000D01*
Y743816D01*
X789968Y743784D01*
G01X866500Y104250D02*
X854250D01*
X832000Y126500D01*
Y137500D01*
G01X865700Y477000D02*
Y474800D01*
X869250Y471250D01*
G01X873750Y467500D02*
X869250D01*
G01D02*
Y471250D01*
G01X876250Y101500D02*
X889380D01*
X942000Y154120D01*
Y250373D01*
X1036175Y344548D01*
Y364975D01*
X1060766Y389566D01*
Y395426D01*
G01X879500Y91250D02*
X882750D01*
X943500Y152000D01*
Y249751D01*
X1037675Y343926D01*
Y362797D01*
X1062716Y387838D01*
Y397484D01*
X1061200Y399000D01*
G01X878375Y461750D02*
X880250D01*
X881500Y463000D01*
Y467500D01*
G01X877250D02*
X881500D01*
G01X1089000Y508500D02*
Y497000D01*
X1068150Y476150D01*
Y385599D01*
X1043100Y360549D01*
Y341678D01*
X952575Y251153D01*
Y57528D01*
X946844Y51797D01*
G01X994660Y513600D02*
Y519660D01*
X997220Y522220D01*
Y526400D01*
G01X994000Y507800D02*
X994660Y508460D01*
Y513600D01*
G01X994000Y507800D02*
X992000Y505800D01*
Y505500D01*
G01X1011500Y667500D02*
Y729600D01*
X987050Y754050D01*
Y757958D01*
X988517Y759425D01*
X991967D01*
X998025Y765483D01*
Y771319D01*
X1001100Y774394D01*
Y776500D01*
G01X1008660Y513600D02*
Y518660D01*
X1011220Y521220D01*
Y526400D01*
G01X1007500Y507000D02*
X1008660Y508160D01*
Y513600D01*
G01X1008100Y504000D02*
X1007500Y504600D01*
Y507000D01*
G01X1070098Y757834D02*
X1070058Y757794D01*
X1065838D01*
G01D02*
X1060294D01*
X1056350Y753850D01*
Y748000D01*
G01X1070478Y753474D02*
X1070098Y753854D01*
Y757834D01*
G01X1083700Y835725D02*
X1096535D01*
X1099550Y838740D01*
G01X1094800Y691800D02*
X1091719D01*
X1091000Y692519D01*
G01X1118630Y714820D02*
X1118160Y714350D01*
X1099150D01*
X1096500Y717000D01*
G01X1095900Y722000D02*
X1096500Y721400D01*
Y717000D01*
G01X1121397Y715906D02*
X1121314D01*
X1120750Y716470D01*
X1116555D01*
X1115635Y715550D01*
X1103950D01*
X1101500Y718000D01*
G01D02*
Y722600D01*
X1101100Y723000D01*
G01D02*
X1097647Y726853D01*
X1094853D01*
G01X1106500Y833750D02*
X1104540D01*
X1099550Y838740D01*
G01X1120000Y629500D02*
X1117750Y631750D01*
Y637052D01*
X1117150Y637652D01*
Y646076D01*
X1120040Y648966D01*
Y650381D01*
X1126947Y657288D01*
Y658464D01*
X1127696Y659213D01*
G01X1106500Y718100D02*
X1108850Y720450D01*
X1112612D01*
X1115456Y717606D01*
X1121607D01*
X1123307Y715906D01*
X1124547D01*
G01X1106200Y723100D02*
X1106730Y723630D01*
X1111130D01*
X1115260Y719500D01*
X1120953D01*
X1121397Y719056D01*
G01X1106500Y833750D02*
X1104500Y831750D01*
Y827834D01*
X1104546Y827788D01*
Y823344D01*
G01X1337612Y63000D02*
X1283500D01*
X1281825Y64675D01*
Y258806D01*
X1273500Y267131D01*
Y323500D01*
X1250500Y346500D01*
Y369500D01*
X1201000Y419000D01*
Y427500D01*
X1199000Y429500D01*
Y459000D01*
X1181750Y476250D01*
Y501309D01*
X1157798Y525261D01*
X1128149D01*
G01X1120500Y639500D02*
Y646030D01*
X1122467Y647997D01*
Y649467D01*
X1130846Y657846D01*
Y659213D01*
G01X1124000Y644500D02*
X1124200Y644700D01*
Y649453D01*
X1132646Y657899D01*
Y659773D01*
X1133996Y661123D01*
Y662363D01*
G01X1120000Y634500D02*
Y636500D01*
X1118350Y638150D01*
Y645578D01*
X1121240Y648468D01*
Y649758D01*
X1129496Y658014D01*
Y659773D01*
X1130846Y661123D01*
Y662363D01*
G01X1133996Y668662D02*
X1134032D01*
X1135595Y670225D01*
G01X1132395D02*
X1133982Y671812D01*
X1133996D01*
G01X1124547Y697008D02*
X1124584D01*
X1126157Y695435D01*
G01X1133996Y703308D02*
X1135537Y704849D01*
X1137949D01*
X1138400Y705300D01*
G01X1124547Y712756D02*
X1122747Y714556D01*
X1120837D01*
X1120573Y714820D01*
X1118630D01*
G01X1130846Y709607D02*
X1132196Y708257D01*
X1135528D01*
X1136200Y707585D01*
X1136201D01*
X1136304Y707482D01*
G01X1139500Y639500D02*
X1143225Y642225D01*
Y647025D01*
X1143444Y647244D01*
Y659213D01*
G01X1139500Y644500D02*
Y645626D01*
X1142094Y648220D01*
Y659773D01*
X1143444Y661123D01*
Y662363D01*
G01Y665512D02*
X1141930Y663998D01*
Y663974D01*
X1141900Y663944D01*
G01X1146594Y668662D02*
X1146562D01*
X1144985Y667085D01*
X1144983D01*
G01X1146594Y671812D02*
X1145040Y670258D01*
Y670220D01*
X1145020Y670200D01*
G01X1137145Y668662D02*
X1135598Y667115D01*
Y667080D01*
G01X1143444Y668662D02*
X1141868Y670238D01*
Y670273D01*
G01X1210800Y379700D02*
Y399590D01*
X1199450Y410940D01*
Y426550D01*
X1197500Y428500D01*
Y458000D01*
X1178500Y477000D01*
Y502000D01*
X1158500Y522000D01*
X1151500D01*
G01X1193500Y626500D02*
X1189500D01*
X1185862Y630138D01*
X1182379D01*
X1167141Y645376D01*
Y648950D01*
X1165660Y650431D01*
Y656840D01*
X1164000Y658500D01*
Y660370D01*
X1162342Y662028D01*
Y662363D01*
G01X1168641Y665512D02*
Y665475D01*
X1167098Y663932D01*
G01X1159192Y665512D02*
X1160710Y663994D01*
Y663980D01*
X1160741Y663949D01*
G01X1159192Y668662D02*
Y668624D01*
X1157655Y667087D01*
G01X1162342Y671812D02*
X1160800Y673354D01*
Y673391D01*
X1160770Y673421D01*
G01X1168641Y712756D02*
Y712645D01*
X1167103Y711107D01*
G01X1214060Y868750D02*
Y872560D01*
X1217000Y875500D01*
Y885000D01*
X1211000Y891000D01*
X1189000D01*
X1172000Y874000D01*
Y865622D01*
X1165000Y858622D01*
Y858000D01*
X1164500Y857500D01*
G01X1171791Y659213D02*
Y652667D01*
X1174000Y650458D01*
Y647842D01*
X1181992Y639850D01*
X1185150D01*
X1185500Y639500D01*
G01X1182000Y643000D02*
X1180964D01*
X1175500Y648464D01*
Y650373D01*
X1173352Y652521D01*
Y660648D01*
X1171791Y662209D01*
Y662363D01*
G01X1188000Y634500D02*
X1187050Y635450D01*
X1181312D01*
X1170500Y646262D01*
Y650406D01*
X1168641Y652265D01*
Y659213D01*
G01X1191500Y631000D02*
X1190862Y631638D01*
X1183001D01*
X1169000Y645639D01*
Y650490D01*
X1168291Y651199D01*
X1167291Y652200D01*
Y659773D01*
X1168641Y661123D01*
Y662363D01*
G01X1203000Y645500D02*
X1202775Y645725D01*
X1193780D01*
X1188420Y651085D01*
Y651176D01*
X1181989Y657607D01*
Y657611D01*
X1181240Y658360D01*
Y659213D01*
G01X1174940Y668662D02*
Y668646D01*
X1173393Y667099D01*
X1173349D01*
G01X1178090Y706457D02*
Y706420D01*
X1176515Y704845D01*
G01X1184389Y709607D02*
X1183537D01*
X1181937Y711207D01*
X1179676D01*
G01X1184389Y706457D02*
X1183574D01*
X1182177Y705060D01*
X1179870D01*
X1179660Y704850D01*
G01X1174940Y706457D02*
X1171487D01*
X1171200Y706170D01*
G01X1181240Y709607D02*
X1181217D01*
X1179660Y708050D01*
G01X1178090Y709607D02*
X1178077D01*
X1176515Y708045D01*
G01X1174940Y709607D02*
X1174807D01*
X1173529Y708329D01*
X1173015D01*
G01X1178090Y712756D02*
Y712719D01*
X1176515Y711144D01*
G01X1174940Y712756D02*
X1174646D01*
X1173262Y711372D01*
Y711119D01*
G01X1205750Y749000D02*
Y746910D01*
X1197503Y738663D01*
X1193204D01*
X1191065Y736524D01*
X1190358D01*
X1179500Y725666D01*
Y724855D01*
X1178650Y724005D01*
X1176843D01*
X1175893Y723055D01*
X1175790D01*
X1174940Y722205D01*
G01X1181240Y715906D02*
X1182790Y714356D01*
X1182802D01*
G01X1181125Y861750D02*
X1178750D01*
X1177000Y860000D01*
G01X1185000Y869250D02*
X1182250D01*
X1169000Y856000D01*
G01X1181125Y861750D02*
X1184875Y865500D01*
X1190000D01*
X1193250Y862250D01*
X1195940D01*
G01X1215256Y231496D02*
X1211004D01*
X1209000Y233500D01*
X1205500D01*
X1202875Y236125D01*
X1191357D01*
X1191332Y236150D01*
X1191066D01*
X1189734Y237482D01*
X1188500D01*
G01X1184750Y237000D02*
X1188000D01*
X1188482Y237482D01*
X1188500D01*
G01X1187539Y706457D02*
X1188543D01*
X1189500Y705500D01*
X1190000D01*
G01X1202000Y709000D02*
X1201475Y708475D01*
X1192502D01*
X1192220Y708757D01*
X1188389D01*
X1187539Y709607D01*
G01X1213000Y712500D02*
X1212850Y712650D01*
X1199450D01*
X1198550Y713550D01*
X1188333D01*
X1187539Y712756D01*
G01X1208500Y710500D02*
X1207850Y711150D01*
X1198350D01*
X1197150Y712350D01*
X1189043D01*
X1188099Y711406D01*
X1186624D01*
X1185274Y712756D01*
X1184389D01*
G01X1207000Y715500D02*
X1205000Y717500D01*
X1192415D01*
X1191521Y716606D01*
X1188239D01*
X1187539Y715906D01*
G01X1202000Y720000D02*
X1201417Y719417D01*
X1192917D01*
X1191106Y717606D01*
X1186394D01*
X1184944Y719056D01*
X1184389D01*
G01X1202500Y727500D02*
X1202000Y727000D01*
X1194500D01*
X1189705Y722205D01*
X1187539D01*
G01X1184389D02*
X1185839Y720755D01*
X1190855D01*
X1195050Y724950D01*
X1213550D01*
X1215500Y723000D01*
G01X1195940Y862250D02*
Y864440D01*
X1197000Y865500D01*
X1208440D01*
X1208940Y865000D01*
Y862250D01*
G01X1201060Y868750D02*
Y876940D01*
X1198500Y879500D01*
X1192750D01*
X1188750Y875500D01*
G01X1185000Y869250D02*
Y871750D01*
X1188750Y875500D01*
G01X1215256Y376378D02*
X1214122D01*
X1210800Y379700D01*
G01X1304760Y58612D02*
X1282000D01*
X1273000Y67612D01*
Y225000D01*
X1280000Y232000D01*
Y255000D01*
X1269000Y266000D01*
Y325500D01*
X1247500Y347000D01*
Y370000D01*
X1213000Y404500D01*
X1209500D01*
G01X1222250Y722500D02*
X1221750Y723000D01*
X1215500D01*
G01X1229000Y740000D02*
Y741000D01*
X1221000Y749000D01*
X1205750D01*
G01X1207000Y764750D02*
X1207250D01*
X1210000Y762000D01*
Y756742D01*
X1215242Y751500D01*
X1222856D01*
X1228839Y745517D01*
X1243759D01*
X1246500Y742776D01*
Y738500D01*
G01X1207720Y775850D02*
X1207688Y767688D01*
X1207000Y767000D01*
Y764750D01*
G01X1221000D02*
X1212500D01*
G01D02*
X1210248Y767002D01*
Y769252D01*
X1210280Y775850D01*
G01X1232776Y190552D02*
X1234448D01*
X1234500Y190500D01*
X1239000D01*
G01X1225750Y722500D02*
X1226000D01*
X1228900Y719600D01*
X1229000D01*
G01X1255000Y588000D02*
X1242500D01*
G01X1240750Y729500D02*
X1243500D01*
X1246500Y732500D01*
Y738500D01*
G01X1264250Y30000D02*
X1269500D01*
G01X1257238Y235000D02*
X1258677D01*
X1260677Y237000D01*
G01X1269500Y30000D02*
X1270500D01*
X1275984Y24516D01*
Y17914D01*
G01X1292968Y847034D02*
Y858668D01*
X1293000Y858700D01*
Y862100D01*
G01X1297468Y847034D02*
Y856168D01*
X1299500Y858200D01*
Y865000D01*
G01X1303533Y874634D02*
Y873533D01*
X1293000Y863000D01*
Y862100D01*
G01X1312867Y568912D02*
X1308617D01*
G01X1305000Y596500D02*
X1300700Y592200D01*
Y575822D01*
X1307610Y568912D01*
X1308617D01*
G01X1303784Y789282D02*
X1302782D01*
X1301000Y787500D01*
Y781566D01*
X1303784Y778782D01*
G01X1308784Y789282D02*
X1309218D01*
X1311534Y786966D01*
Y781532D01*
X1308784Y778782D01*
G01X1313784D02*
X1315782D01*
X1317160Y780160D01*
Y787860D01*
X1316563Y788457D01*
X1315044D01*
X1314284Y789216D01*
Y789282D01*
G01X1303784Y794284D02*
Y789282D01*
G01Y794284D02*
Y801032D01*
G01X1308784Y794284D02*
Y789282D01*
G01Y794284D02*
Y801032D01*
G01X1313784D02*
X1313934Y797507D01*
Y794066D01*
X1314000Y794000D01*
G01X1314284Y789282D02*
X1314000Y789566D01*
Y794000D01*
G01X1304500Y830750D02*
Y828500D01*
X1306000Y827000D01*
G01X1308784Y821032D02*
Y824216D01*
X1306000Y827000D01*
G01X1305498Y874634D02*
Y870998D01*
X1299500Y865000D01*
G01X1303070Y909853D02*
X1303500Y909423D01*
Y894500D01*
X1303533Y894467D01*
Y890934D01*
G01X1305498D02*
Y897030D01*
X1306968Y898500D01*
G01X1301968Y913534D02*
Y910955D01*
X1303070Y909853D01*
G01X1307468Y913534D02*
Y902502D01*
X1306968Y902002D01*
Y898500D01*
G01X1367067Y42323D02*
X1363813Y45577D01*
X1359876D01*
X1342453Y63000D01*
X1337612D01*
G01X1367067Y42323D02*
X1392657D01*
G01X1367250Y356500D02*
X1365500D01*
G01X1367750D02*
X1369000D01*
G54D34*
X63304Y714520D03*
X55304Y750520D03*
X63272Y794304D03*
X58772D03*
X67772D03*
X81304Y714520D03*
X69804Y840020D03*
X96772Y714304D03*
X92772D03*
X87804Y840020D03*
X103804Y759520D03*
X102304Y887020D03*
X127654Y308753D03*
X179500Y862300D03*
X189555Y566800D03*
X194500Y861300D03*
X199000Y883800D03*
X210000Y829300D03*
X212000Y883800D03*
X232000Y829300D03*
X228000D03*
X220000D03*
X224000D03*
X216000Y883800D03*
X225000Y887300D03*
X229500D03*
X234623Y565983D03*
X273500Y197800D03*
X313485Y245172D03*
X312555Y439300D03*
X317985Y245172D03*
X341000Y94300D03*
X347000Y112729D03*
X357429Y246800D03*
X361929D03*
X352929D03*
X361178Y982300D03*
X366429Y246800D03*
X375429D03*
X370929D03*
X379929D03*
X376000Y869800D03*
X371500D03*
X380000Y918800D03*
X375500D03*
X373678Y982300D03*
X386555Y299300D03*
X395555D03*
X384500Y870300D03*
X384000Y918800D03*
X396929Y253800D03*
X412500Y265300D03*
X400555Y299300D03*
X405555D03*
X409555D03*
X398000Y870300D03*
X424929Y249700D03*
X420429D03*
X424929Y257700D03*
X423055Y293800D03*
X418555Y299300D03*
X414055D03*
X434540Y106300D03*
X440000Y236300D03*
X433929Y257700D03*
X444778Y805300D03*
X438278D03*
X444278Y875800D03*
X458555Y293300D03*
X450778Y875800D03*
X475778Y805300D03*
X469278D03*
X473778Y875800D03*
X480278D03*
X549000Y151300D03*
X549055Y327300D03*
X558955Y368200D03*
X554955D03*
X571000Y151300D03*
X659462Y480764D03*
X682382Y122742D03*
X678222Y122892D03*
X686432Y126312D03*
X690512Y126252D03*
X704716Y148584D03*
X698968Y779284D03*
X704000Y884800D03*
X724532Y54016D03*
X720032Y62016D03*
X715716Y87084D03*
X715468Y754784D03*
X736248Y148800D03*
X731716Y148584D03*
X725748Y180800D03*
X726000Y891300D03*
X763000Y455800D03*
X767000D03*
Y471800D03*
X765998Y707854D03*
X770498D03*
X788774Y475378D03*
X779774D03*
X780500Y881300D03*
X785000D03*
X806000Y728300D03*
X838055Y270300D03*
X833555D03*
X847055D03*
X851555D03*
X856055D03*
X842555D03*
X866500Y100800D03*
X865055Y270300D03*
X860555D03*
X868820Y356680D03*
X863820D03*
X867000Y432800D03*
X862500D03*
X869468Y701584D03*
X879500Y87800D03*
X873468Y701584D03*
X919000Y51800D03*
X998000Y480800D03*
X1003000D03*
X999000Y536800D03*
X1003000D03*
X1010500Y451800D03*
X1011000Y496800D03*
X1017000Y536800D03*
X1013000D03*
X1029500Y120800D03*
X1025500Y133300D03*
X1035000Y175300D03*
X1027716Y907768D03*
X1032216D03*
X1039500Y175300D03*
X1070478Y750024D03*
X1074968Y749984D03*
X1070098Y757884D03*
X1093961Y99842D03*
X1089961D03*
X1089500Y408800D03*
X1088000Y454300D03*
X1092500D03*
X1087988Y741924D03*
X1101968Y806584D03*
X1117500Y614300D03*
X1103000Y634300D03*
X1107000D03*
X1115000D03*
X1111000Y742300D03*
X1107468Y806384D03*
X1106500Y833800D03*
X1122000Y614300D03*
X1149934Y581472D03*
X1137500Y622300D03*
X1151500Y626800D03*
X1146500Y622300D03*
X1146000Y634300D03*
X1151500D03*
X1135468Y858584D03*
X1159500Y620300D03*
X1179000Y400300D03*
X1172000Y753800D03*
X1180000D03*
X1184000D03*
X1176000D03*
X1191000Y400300D03*
X1195000D03*
X1189000Y742300D03*
X1192000Y753800D03*
X1213000Y630800D03*
X1209000D03*
X1205000D03*
X1201000D03*
X1201968Y761084D03*
X1215716Y805768D03*
X1211216D03*
X1207000Y805800D03*
X1215500Y851800D03*
X1201500D03*
X1226500Y440300D03*
X1225500Y789800D03*
X1220000Y805800D03*
X1246500Y465300D03*
X1242000D03*
X1238100Y853900D03*
X1257000Y36300D03*
X1271500Y545300D03*
X1276000Y660300D03*
X1281000Y705800D03*
X1277000Y716300D03*
X1295500Y30800D03*
X1284500Y314800D03*
X1293968Y659584D03*
X1285000Y659800D03*
X1310500Y39800D03*
X1314500D03*
X1299968Y658084D03*
X1303784Y785832D03*
X1308784D03*
X1314284D03*
X1312500Y854050D03*
X1307468Y913584D03*
X1301968D03*
X1312468D03*
X1327000Y328800D03*
X1323500Y433300D03*
Y445300D03*
X1332117Y618712D03*
X1327617D03*
X1328968Y673084D03*
X1326000Y854050D03*
X1317000D03*
X1321500D03*
X1316968Y913584D03*
X1332500Y50800D03*
X1336500Y135300D03*
X1338500Y456300D03*
X1347468Y453084D03*
X1352000Y78300D03*
X1363117Y562212D03*
X1354417Y619712D03*
G54D16*
X26504Y840720D03*
X26500Y854200D03*
X51504Y842720D03*
X66004Y830720D03*
X78004Y889720D03*
X92472Y770504D03*
X92504Y790220D03*
Y798220D03*
Y806720D03*
Y811220D03*
X138700Y666500D03*
X141004Y808220D03*
Y803720D03*
Y799720D03*
Y812720D03*
X155500Y469800D03*
X165255Y530000D03*
X157255D03*
X163255Y550500D03*
X161200Y666500D03*
X152700Y844000D03*
X168500Y457800D03*
X190500Y474800D03*
X185255Y525500D03*
X185443Y537396D03*
X194200Y869500D03*
X211223Y521183D03*
X215700Y812000D03*
X221755Y560000D03*
Y564500D03*
X240700Y423000D03*
Y427000D03*
X247200Y855500D03*
Y859500D03*
Y847500D03*
X294859Y419678D03*
X324200Y98000D03*
X319205Y313152D03*
X319129Y334500D03*
X318129Y348500D03*
Y354000D03*
X344629Y237500D03*
X359723Y463783D03*
X358723Y473783D03*
Y478283D03*
X359635Y468450D03*
X358723Y482783D03*
X379255Y330500D03*
Y335000D03*
Y339500D03*
Y344000D03*
Y357500D03*
Y362000D03*
X365005Y405270D03*
Y410000D03*
Y414500D03*
Y419000D03*
X402200Y265400D03*
X405700Y885000D03*
X410700Y915500D03*
Y911500D03*
X429200Y236500D03*
X426455Y283200D03*
Y279200D03*
X430700Y941500D03*
Y945500D03*
X458200Y117500D03*
X465700Y185000D03*
X600200Y200500D03*
Y205000D03*
Y214000D03*
Y218500D03*
X648200Y440000D03*
X656164Y436538D03*
X651700Y453000D03*
X657700Y606900D03*
Y613400D03*
X681526Y99024D03*
Y103524D03*
X685276Y94934D03*
X685286Y107744D03*
X678200Y768500D03*
X686668Y797784D03*
Y807484D03*
Y802484D03*
X707700Y59500D03*
Y72500D03*
Y68000D03*
X722700Y197500D03*
Y193500D03*
X725400Y209000D03*
X729168Y797484D03*
X727700Y887000D03*
Y882500D03*
Y899000D03*
X749200Y82500D03*
Y88500D03*
Y94500D03*
Y99500D03*
X756416Y116784D03*
Y112284D03*
X753164Y476038D03*
X772200Y668000D03*
X770200Y858000D03*
Y853500D03*
X758200Y874500D03*
X786200Y546500D03*
X786700Y553500D03*
Y561000D03*
X779200Y644500D03*
X795794Y570468D03*
Y574968D03*
Y579468D03*
X809974Y469578D03*
X821200Y853500D03*
X851200Y715500D03*
X860341Y706312D03*
X882200Y334500D03*
Y338500D03*
X946794Y51797D03*
X948200Y59500D03*
X939150Y452700D03*
X1015200Y907000D03*
X1015416Y902468D03*
X1033200Y128500D03*
X1030200Y168500D03*
Y173000D03*
X1031474Y199578D03*
Y204578D03*
Y209578D03*
X1049200Y681000D03*
Y693000D03*
Y685000D03*
Y697000D03*
Y709000D03*
Y701000D03*
Y705000D03*
X1063668Y219284D03*
X1063700Y215000D03*
X1081200Y631500D03*
Y627500D03*
Y644000D03*
Y635500D03*
Y648000D03*
Y656000D03*
Y652000D03*
Y661500D03*
Y675500D03*
Y671500D03*
X1069700Y668000D03*
Y673000D03*
X1081200Y667500D03*
Y679500D03*
Y691500D03*
Y687500D03*
Y695500D03*
Y683500D03*
Y711500D03*
Y699500D03*
Y707500D03*
Y703500D03*
Y715500D03*
Y722500D03*
Y726500D03*
Y730500D03*
X1096168Y867284D03*
Y871784D03*
X1142200Y262500D03*
Y270500D03*
Y258500D03*
Y266500D03*
X1142168Y286284D03*
X1142200Y278500D03*
X1149700Y597000D03*
X1141700Y827000D03*
X1151200Y818000D03*
X1176700Y621000D03*
X1205700Y749000D03*
X1225700Y722500D03*
Y740500D03*
X1232200Y762000D03*
Y757500D03*
Y753000D03*
X1247377Y255000D03*
Y259500D03*
X1248200Y451500D03*
Y456000D03*
X1240700Y729500D03*
X1264200Y30000D03*
X1257188Y235000D03*
X1261200Y577000D03*
X1253700Y671000D03*
Y684000D03*
X1262700Y779000D03*
X1276700Y674500D03*
Y681000D03*
X1308700Y316500D03*
X1316200Y318000D03*
X1316317Y559912D03*
Y564412D03*
Y568912D03*
Y581912D03*
X1316400Y573000D03*
X1316317Y590912D03*
Y607912D03*
Y621412D03*
Y616912D03*
X1342317Y623912D03*
X1357700Y448000D03*
G54D25*
X40054Y829345D03*
X47554Y833220D03*
X40054Y837095D03*
X168495Y516875D03*
X175995Y520750D03*
X168495Y524625D03*
X198250Y789125D03*
Y796875D03*
Y810875D03*
Y803125D03*
X205750Y793000D03*
Y807000D03*
X278409Y430678D03*
X270909Y434553D03*
Y426803D03*
X757250Y461500D03*
X749750Y465375D03*
Y457625D03*
X1080518Y220224D03*
X1073018Y216349D03*
Y224099D03*
X1312260Y54737D03*
X1304760Y50862D03*
Y58612D03*
G54D52*
X159555Y536250D03*
X163430Y543750D03*
X155680D03*
X764000Y653250D03*
X767875Y660750D03*
X760125D03*
X869987Y82376D03*
X866112Y89876D03*
X870625Y461750D03*
X873862Y89876D03*
X874500Y454250D03*
X878375Y461750D03*
X905625Y60750D03*
X909500Y53250D03*
X913375Y60750D03*
X1095500Y436750D03*
X1099375Y444250D03*
X1091625D03*
X1339000Y112250D03*
X1342875Y119750D03*
X1335125D03*
X1354000Y112250D03*
X1357875Y119750D03*
X1350125D03*
G54D109*
X629000Y333600D03*
Y358400D03*
X649500Y333600D03*
Y358400D03*
G54D154*
X1203830Y576840D03*
Y596840D03*
X1220370Y576840D03*
Y596840D03*
G54D136*
X789968Y743784D03*
Y763784D03*
X804968Y743784D03*
X799968D03*
X794968D03*
Y763784D03*
X799968D03*
X804968D03*
X870500Y720500D03*
X865500D03*
X860500D03*
Y740500D03*
X865500D03*
X870500D03*
X875500Y720500D03*
Y740500D03*
X1151468Y225784D03*
X1146468D03*
X1141468D03*
Y245784D03*
X1146468D03*
X1151468D03*
X1156468Y225784D03*
Y245784D03*
X1313784Y801032D03*
X1308784D03*
X1303784D03*
Y821032D03*
X1308784D03*
X1313784D03*
X1318784Y801032D03*
Y821032D03*
X1348084Y282757D03*
Y319907D03*
X1353084Y282757D03*
X1358084D03*
X1363084D03*
Y319907D03*
X1358084D03*
X1353084D03*
X1368084Y282757D03*
X1373084D03*
X1378084D03*
Y319907D03*
X1373084D03*
X1368084D03*
X1383084Y282757D03*
Y319907D03*
G54D145*
X1045000Y32598D03*
X1096732D03*
G54D163*
X1301500Y392957D03*
Y415043D03*
G54D118*
X707716Y110457D03*
Y132111D03*
X735716Y110457D03*
Y132111D03*
X780668Y448125D03*
Y454031D03*
X792880Y448125D03*
Y454031D03*
X1348106Y433547D03*
X1335894D03*
X1348106Y439453D03*
X1335894D03*
G54D70*
X224297Y905248D03*
X230703D03*
G54D172*
X1346586Y582112D03*
X1344617D03*
X1342648D03*
X1340680D03*
X1338711D03*
Y604712D03*
X1340680D03*
X1342648D03*
X1344617D03*
X1346586D03*
X1350523Y582112D03*
X1348554D03*
Y604712D03*
X1350523D03*
G54D127*
X749700Y483000D03*
X755300Y481000D03*
Y485000D03*
X865700Y477000D03*
X871300Y475000D03*
Y479000D03*
G54D43*
X121890Y269528D03*
X131890D03*
X141890D03*
X1346396Y21656D03*
X1338526D03*
X1346396Y29526D03*
X1338526D03*
X1362146Y21656D03*
X1354271D03*
X1362146Y29526D03*
X1354271D03*
X1377896Y21656D03*
X1370021D03*
X1377896Y29526D03*
X1370021D03*
X1385766Y21656D03*
Y29526D03*
G54D61*
X189800Y861000D03*
X193300Y852000D03*
X193800Y874000D03*
X215300Y816500D03*
X458229Y101500D03*
X602198Y426116D03*
Y431116D03*
Y441116D03*
Y436116D03*
Y451116D03*
Y446116D03*
X676548Y56500D03*
Y63500D03*
X725000Y202000D03*
X769574Y441078D03*
X852300Y720000D03*
X875768Y709784D03*
X1044300Y105500D03*
Y111000D03*
X1106300Y780500D03*
X1152700Y604700D03*
X1254800Y716000D03*
X1293300Y363000D03*
X1308300Y564500D03*
X1330800Y420000D03*
X1317417Y577412D03*
X1342417Y562412D03*
G54D182*
G01X-185516Y-508119D02*
Y-490619D01*
G01X-176346D02*
Y-508119D01*
G01Y-499369D02*
X-185516D01*
G01X-163431Y-508119D02*
X-165178Y-507827D01*
X-166706Y-506661D01*
X-168016Y-504911D01*
X-168890Y-502869D01*
X-169326Y-500536D01*
Y-498202D01*
X-168890Y-495869D01*
X-168016Y-493827D01*
X-166706Y-492078D01*
X-165178Y-490911D01*
X-163431Y-490619D01*
X-161685Y-490911D01*
X-160156Y-492078D01*
X-158846Y-493827D01*
X-157972Y-495869D01*
X-157536Y-498202D01*
Y-500536D01*
X-157972Y-502869D01*
X-158846Y-504911D01*
X-160156Y-506661D01*
X-161685Y-507827D01*
X-163431Y-508119D01*
G01X-150953D02*
Y-490619D01*
X-140909Y-508119D01*
Y-490619D01*
G01X-124064Y-508119D02*
X-132798D01*
Y-490619D01*
X-124064D01*
G01X-127558Y-499077D02*
X-132798D01*
G01X-110931Y-508119D02*
Y-500244D01*
X-115298Y-490619D01*
G01X-106564D02*
X-110931Y-500244D01*
G01X-74185Y-498786D02*
X-73311Y-497911D01*
X-72656Y-496453D01*
X-72219Y-494410D01*
X-72656Y-492661D01*
X-73529Y-491494D01*
X-75058Y-490619D01*
X-80953D01*
Y-508119D01*
X-73748D01*
X-72219Y-506953D01*
X-71346Y-505202D01*
X-70909Y-503161D01*
X-71346Y-501119D01*
X-72656Y-499369D01*
X-74185Y-498786D01*
X-80953D01*
G01X-63890Y-508119D02*
X-58431Y-490619D01*
X-52972Y-508119D01*
G01X-54938Y-501994D02*
X-61925D01*
G01X-45734Y-508119D02*
Y-490619D01*
X-41368D01*
X-39621Y-491494D01*
X-38311Y-492661D01*
X-37219Y-494410D01*
X-36346Y-496453D01*
X-36128Y-499369D01*
X-36346Y-502286D01*
X-37219Y-504328D01*
X-38311Y-506078D01*
X-39621Y-507244D01*
X-41368Y-508119D01*
X-45734D01*
G01X-22121Y-499369D02*
X-17754D01*
Y-504619D01*
X-19064Y-506369D01*
X-20593Y-507536D01*
X-22776Y-508119D01*
X-24959Y-507536D01*
X-26488Y-506369D01*
X-27798Y-504619D01*
X-28671Y-502577D01*
X-29108Y-500244D01*
Y-498202D01*
X-28671Y-496453D01*
X-27798Y-494410D01*
X-26488Y-492661D01*
X-25178Y-491494D01*
X-23431Y-490619D01*
X-21903D01*
X-20156Y-491202D01*
X-18846Y-492369D01*
G01X-1564Y-508119D02*
X-10298D01*
Y-490619D01*
X-1564D01*
G01X-5058Y-499077D02*
X-10298D01*
G01X7202Y-508119D02*
Y-490619D01*
X12661D01*
X14407Y-491494D01*
X15499Y-492661D01*
X15936Y-494994D01*
X15499Y-497328D01*
X14189Y-498786D01*
X12661Y-499661D01*
X7202D01*
G01X12661D02*
X15936Y-508119D01*
G01X48315Y-498786D02*
X49189Y-497911D01*
X49844Y-496453D01*
X50281Y-494410D01*
X49844Y-492661D01*
X48971Y-491494D01*
X47442Y-490619D01*
X41547D01*
Y-508119D01*
X48752D01*
X50281Y-506953D01*
X51154Y-505202D01*
X51591Y-503161D01*
X51154Y-501119D01*
X49844Y-499369D01*
X48315Y-498786D01*
X41547D01*
G01X58610Y-508119D02*
X64069Y-490619D01*
X69528Y-508119D01*
G01X67562Y-501994D02*
X60575D01*
G01X76984Y-505786D02*
X78731Y-507244D01*
X80696Y-508119D01*
X82442D01*
X84189Y-507244D01*
X85499Y-505786D01*
X86154Y-503744D01*
X85717Y-501703D01*
X84626Y-499952D01*
X82661Y-498786D01*
X80041Y-498202D01*
X78512Y-497036D01*
X77857Y-494994D01*
X78294Y-492952D01*
X79386Y-491494D01*
X80914Y-490619D01*
X82442D01*
X83971Y-491202D01*
X85281Y-492661D01*
G01X103436Y-508119D02*
X94702D01*
Y-490619D01*
X103436D01*
G01X99942Y-499077D02*
X94702D01*
G01X118315Y-498786D02*
X119189Y-497911D01*
X119844Y-496453D01*
X120281Y-494410D01*
X119844Y-492661D01*
X118971Y-491494D01*
X117442Y-490619D01*
X111547D01*
Y-508119D01*
X118752D01*
X120281Y-506953D01*
X121154Y-505202D01*
X121591Y-503161D01*
X121154Y-501119D01*
X119844Y-499369D01*
X118315Y-498786D01*
X111547D01*
G01X134069Y-508119D02*
X132322Y-507827D01*
X130794Y-506661D01*
X129484Y-504911D01*
X128610Y-502869D01*
X128174Y-500536D01*
Y-498202D01*
X128610Y-495869D01*
X129484Y-493827D01*
X130794Y-492078D01*
X132322Y-490911D01*
X134069Y-490619D01*
X135815Y-490911D01*
X137344Y-492078D01*
X138654Y-493827D01*
X139528Y-495869D01*
X139964Y-498202D01*
Y-500536D01*
X139528Y-502869D01*
X138654Y-504911D01*
X137344Y-506661D01*
X135815Y-507827D01*
X134069Y-508119D01*
G01X146110D02*
X151569Y-490619D01*
X157028Y-508119D01*
G01X155062Y-501994D02*
X148075D01*
G01X164702Y-508119D02*
Y-490619D01*
X170161D01*
X171907Y-491494D01*
X172999Y-492661D01*
X173436Y-494994D01*
X172999Y-497328D01*
X171689Y-498786D01*
X170161Y-499661D01*
X164702D01*
G01X170161D02*
X173436Y-508119D01*
G01X181766D02*
Y-490619D01*
X186132D01*
X187879Y-491494D01*
X189189Y-492661D01*
X190281Y-494410D01*
X191154Y-496453D01*
X191372Y-499369D01*
X191154Y-502286D01*
X190281Y-504328D01*
X189189Y-506078D01*
X187879Y-507244D01*
X186132Y-508119D01*
X181766D01*
G01X-37858Y-463119D02*
Y-445619D01*
X-32181Y-460202D01*
X-26504Y-445619D01*
Y-463119D01*
G01X-14681D02*
X-15991Y-462827D01*
X-17301Y-461661D01*
X-18175Y-459619D01*
X-18611Y-457286D01*
X-18175Y-454952D01*
X-17301Y-452911D01*
X-15991Y-451744D01*
X-14681Y-451453D01*
X-13371Y-451744D01*
X-12061Y-452911D01*
X-11188Y-454952D01*
X-10969Y-457286D01*
X-11188Y-459619D01*
X-12061Y-461661D01*
X-13371Y-462827D01*
X-14681Y-463119D01*
G01X6749Y-445619D02*
Y-463119D01*
G01Y-460495D02*
X5876Y-461953D01*
X4565Y-462827D01*
X3037Y-463119D01*
X1291Y-462536D01*
X-19Y-461078D01*
X-893Y-459328D01*
X-1111Y-457286D01*
X-893Y-455244D01*
X-19Y-453494D01*
X1291Y-452036D01*
X3037Y-451453D01*
X4565Y-451744D01*
X5657Y-452328D01*
X6749Y-453494D01*
G01X17044Y-455244D02*
X24031D01*
X23376Y-453202D01*
X22284Y-452036D01*
X20756Y-451453D01*
X19227Y-451744D01*
X17917Y-452619D01*
X17044Y-454661D01*
X16607Y-456411D01*
Y-458161D01*
X17044Y-459911D01*
X18136Y-461661D01*
X19446Y-462827D01*
X20974Y-463119D01*
X22502Y-462536D01*
X24031Y-460786D01*
G01X37819Y-463119D02*
Y-445619D01*
G01X281019Y-508119D02*
Y-490619D01*
X278399Y-494119D01*
G01Y-508119D02*
X283639D01*
G01X293716Y-504619D02*
X295025Y-506661D01*
X296772Y-507827D01*
X298737Y-508119D01*
X300484Y-507827D01*
X302231Y-506369D01*
X303322Y-504619D01*
X303541Y-502869D01*
X303104Y-500828D01*
X301576Y-499369D01*
X300047Y-498786D01*
X298082D01*
G01X300047D02*
X301357Y-497911D01*
X302449Y-496453D01*
X302886Y-494703D01*
X302449Y-492952D01*
X301357Y-491494D01*
X299392Y-490619D01*
X297427Y-490911D01*
X295462Y-492078D01*
G01X312307Y-506078D02*
X313836Y-507536D01*
X315582Y-508119D01*
X317329Y-507536D01*
X318857Y-505786D01*
X319949Y-503161D01*
X320386Y-500536D01*
Y-497328D01*
X319949Y-494703D01*
X318857Y-492369D01*
X317547Y-491202D01*
X316019Y-490619D01*
X314272Y-491202D01*
X312962Y-492369D01*
X312089Y-494119D01*
X311652Y-496453D01*
X312089Y-498494D01*
X313181Y-500536D01*
X314491Y-501703D01*
X316019Y-501994D01*
X317765Y-501411D01*
X319076Y-499952D01*
X320386Y-497328D01*
G01X336139Y-508119D02*
Y-490619D01*
X328060Y-503161D01*
X338978D01*
G01X351019Y-508119D02*
X352547Y-507827D01*
X354294Y-506953D01*
X355386Y-505495D01*
X355822Y-503452D01*
X355386Y-501411D01*
X354076Y-499661D01*
X352111Y-498786D01*
X349927D01*
X348617Y-498202D01*
X347525Y-496744D01*
X347089Y-494703D01*
X347744Y-492661D01*
X349272Y-491202D01*
X351019Y-490619D01*
X352765Y-491202D01*
X354294Y-492661D01*
X354949Y-494703D01*
X354512Y-496744D01*
X353421Y-498202D01*
X352111Y-498786D01*
X349927D01*
X347962Y-499661D01*
X346652Y-501411D01*
X346216Y-503452D01*
X346652Y-505495D01*
X347744Y-506953D01*
X349491Y-507827D01*
X351019Y-508119D01*
G01X267902Y-463119D02*
Y-445619D01*
X273142D01*
X274889Y-446494D01*
X276199Y-448536D01*
X276636Y-450869D01*
X276199Y-453202D01*
X275107Y-454952D01*
X273142Y-455828D01*
X267902D01*
G01X294572Y-447078D02*
X293262Y-446202D01*
X291734Y-445619D01*
X289987D01*
X288022Y-446494D01*
X286494Y-447952D01*
X285402Y-449703D01*
X284529Y-452619D01*
X284310Y-455244D01*
X284747Y-457869D01*
X285402Y-459619D01*
X286712Y-461369D01*
X288241Y-462536D01*
X289769Y-463119D01*
X291297D01*
X292826Y-462536D01*
X294136Y-461661D01*
X295228Y-460495D01*
G01X309015Y-453786D02*
X309889Y-452911D01*
X310544Y-451453D01*
X310981Y-449410D01*
X310544Y-447661D01*
X309671Y-446494D01*
X308142Y-445619D01*
X302247D01*
Y-463119D01*
X309452D01*
X310981Y-461953D01*
X311854Y-460202D01*
X312291Y-458161D01*
X311854Y-456119D01*
X310544Y-454369D01*
X309015Y-453786D01*
X302247D01*
G01X318219Y-468952D02*
X331319D01*
G01X337247Y-463119D02*
Y-445619D01*
X347291Y-463119D01*
Y-445619D01*
G01X359769Y-463119D02*
X358022Y-462827D01*
X356494Y-461661D01*
X355184Y-459911D01*
X354310Y-457869D01*
X353874Y-455536D01*
Y-453202D01*
X354310Y-450869D01*
X355184Y-448827D01*
X356494Y-447078D01*
X358022Y-445911D01*
X359769Y-445619D01*
X361515Y-445911D01*
X363044Y-447078D01*
X364354Y-448827D01*
X365228Y-450869D01*
X365664Y-453202D01*
Y-455536D01*
X365228Y-457869D01*
X364354Y-459911D01*
X363044Y-461661D01*
X361515Y-462827D01*
X359769Y-463119D01*
G01X410610Y-445619D02*
X416069Y-463119D01*
X421528Y-445619D01*
G01X437936Y-463119D02*
X429202D01*
Y-445619D01*
X437936D01*
G01X434442Y-454077D02*
X429202D01*
G01X446702Y-463119D02*
Y-445619D01*
X452161D01*
X453907Y-446494D01*
X454999Y-447661D01*
X455436Y-449994D01*
X454999Y-452328D01*
X453689Y-453786D01*
X452161Y-454661D01*
X446702D01*
G01X452161D02*
X455436Y-463119D01*
G01X468569Y-463702D02*
X468132Y-463411D01*
Y-462827D01*
X468569Y-462536D01*
X469006Y-462827D01*
Y-463411D01*
X468569Y-463702D01*
G01X433569Y-508119D02*
Y-490619D01*
X430949Y-494119D01*
G01Y-508119D02*
X436189D01*
G01X452815Y-498786D02*
X453689Y-497911D01*
X454344Y-496453D01*
X454781Y-494410D01*
X454344Y-492661D01*
X453471Y-491494D01*
X451942Y-490619D01*
X446047D01*
Y-508119D01*
X453252D01*
X454781Y-506953D01*
X455654Y-505202D01*
X456091Y-503161D01*
X455654Y-501119D01*
X454344Y-499369D01*
X452815Y-498786D01*
X446047D01*
G01X544152Y-445619D02*
Y-463119D01*
X552886D01*
G01X569949D02*
Y-451453D01*
G01Y-453494D02*
X569076Y-452328D01*
X567765Y-451744D01*
X566237Y-451453D01*
X564709Y-452036D01*
X563399Y-453202D01*
X562525Y-454952D01*
X562089Y-457286D01*
X562525Y-459619D01*
X563399Y-461369D01*
X564709Y-462536D01*
X566237Y-463119D01*
X567765Y-462827D01*
X569076Y-461953D01*
X569949Y-460786D01*
G01X578934Y-468369D02*
X580244Y-468952D01*
X581991Y-468369D01*
X583082Y-467203D01*
X583956Y-465744D01*
X585265Y-461078D01*
X588104Y-451453D01*
G01X581117D02*
X585265Y-461078D01*
G01X597744Y-455244D02*
X604731D01*
X604076Y-453202D01*
X602984Y-452036D01*
X601456Y-451453D01*
X599927Y-451744D01*
X598617Y-452619D01*
X597744Y-454661D01*
X597307Y-456411D01*
Y-458161D01*
X597744Y-459911D01*
X598836Y-461661D01*
X600146Y-462827D01*
X601674Y-463119D01*
X603202Y-462536D01*
X604731Y-460786D01*
G01X615462Y-463119D02*
Y-451453D01*
G01Y-453786D02*
X616554Y-452619D01*
X617646Y-451744D01*
X619174Y-451453D01*
X620265Y-451744D01*
X621576Y-452619D01*
G01X570402Y-490619D02*
Y-508119D01*
X579136D01*
G01X592269D02*
Y-490619D01*
X589649Y-494119D01*
G01Y-508119D02*
X594889D01*
G01X686702Y-490619D02*
Y-508119D01*
X695436D01*
G01X703984Y-513369D02*
X705294Y-513952D01*
X707041Y-513369D01*
X708132Y-512203D01*
X709006Y-510744D01*
X710315Y-506078D01*
X713154Y-496453D01*
G01X706167D02*
X710315Y-506078D01*
G01X722357Y-508119D02*
Y-496453D01*
G01Y-499369D02*
X723231Y-497911D01*
X724541Y-496744D01*
X726287Y-496453D01*
X727815Y-496744D01*
X729126Y-497911D01*
X729781Y-499952D01*
Y-508119D01*
G01X739857D02*
Y-496453D01*
G01Y-499369D02*
X740731Y-497911D01*
X742041Y-496744D01*
X743787Y-496453D01*
X745315Y-496744D01*
X746626Y-497911D01*
X747281Y-499952D01*
Y-508119D01*
G01X774202Y-490619D02*
Y-508119D01*
X782936D01*
G01X796069Y-496453D02*
Y-508119D01*
G01Y-491786D02*
X795632Y-491494D01*
Y-490911D01*
X796069Y-490619D01*
X796506Y-490911D01*
Y-491494D01*
X796069Y-491786D01*
G01X809857Y-496453D02*
Y-504619D01*
X810731Y-506661D01*
X812041Y-507827D01*
X813569Y-508119D01*
X815097Y-507827D01*
X816407Y-506661D01*
X817281Y-504619D01*
G01Y-508119D02*
Y-496453D01*
G01X686266Y-463119D02*
Y-445619D01*
X690632D01*
X692379Y-446494D01*
X693689Y-447661D01*
X694781Y-449410D01*
X695654Y-451453D01*
X695872Y-454369D01*
X695654Y-457286D01*
X694781Y-459328D01*
X693689Y-461078D01*
X692379Y-462244D01*
X690632Y-463119D01*
X686266D01*
G01X705294Y-455244D02*
X712281D01*
X711626Y-453202D01*
X710534Y-452036D01*
X709006Y-451453D01*
X707477Y-451744D01*
X706167Y-452619D01*
X705294Y-454661D01*
X704857Y-456411D01*
Y-458161D01*
X705294Y-459911D01*
X706386Y-461661D01*
X707696Y-462827D01*
X709224Y-463119D01*
X710752Y-462536D01*
X712281Y-460786D01*
G01X722794Y-461078D02*
X723886Y-462244D01*
X725414Y-463119D01*
X726724D01*
X728034Y-462536D01*
X728907Y-461661D01*
X729344Y-460495D01*
X729126Y-458744D01*
X728252Y-457869D01*
X724322Y-456119D01*
X723449Y-454077D01*
X723886Y-452619D01*
X724759Y-451744D01*
X726069Y-451453D01*
X727379Y-451744D01*
X728689Y-452619D01*
G01X743569Y-451453D02*
Y-463119D01*
G01Y-446786D02*
X743132Y-446494D01*
Y-445911D01*
X743569Y-445619D01*
X744006Y-445911D01*
Y-446494D01*
X743569Y-446786D01*
G01X758012Y-467494D02*
X759541Y-468661D01*
X761287Y-468952D01*
X762815Y-468661D01*
X764126Y-467203D01*
X764999Y-465161D01*
Y-451453D01*
G01Y-453786D02*
X764126Y-452619D01*
X762815Y-451744D01*
X761287Y-451453D01*
X759541Y-452036D01*
X758449Y-453202D01*
X757575Y-455244D01*
X757139Y-457286D01*
X757357Y-459036D01*
X758231Y-461078D01*
X759541Y-462536D01*
X761287Y-463119D01*
X762597Y-462827D01*
X764126Y-461661D01*
X764999Y-460495D01*
G01X774857Y-463119D02*
Y-451453D01*
G01Y-454369D02*
X775731Y-452911D01*
X777041Y-451744D01*
X778787Y-451453D01*
X780315Y-451744D01*
X781626Y-452911D01*
X782281Y-454952D01*
Y-463119D01*
G01X792794Y-455244D02*
X799781D01*
X799126Y-453202D01*
X798034Y-452036D01*
X796506Y-451453D01*
X794977Y-451744D01*
X793667Y-452619D01*
X792794Y-454661D01*
X792357Y-456411D01*
Y-458161D01*
X792794Y-459911D01*
X793886Y-461661D01*
X795196Y-462827D01*
X796724Y-463119D01*
X798252Y-462536D01*
X799781Y-460786D01*
G01X810512Y-463119D02*
Y-451453D01*
G01Y-453786D02*
X811604Y-452619D01*
X812696Y-451744D01*
X814224Y-451453D01*
X815315Y-451744D01*
X816626Y-452619D01*
G01X857269Y-508119D02*
Y-490619D01*
X854649Y-494119D01*
G01Y-508119D02*
X859889D01*
G01X874769D02*
Y-490619D01*
X872149Y-494119D01*
G01Y-508119D02*
X877389D01*
G01X888339Y-508702D02*
X896199Y-490619D01*
G01X909769Y-508119D02*
Y-490619D01*
X907149Y-494119D01*
G01Y-508119D02*
X912389D01*
G01X922466Y-504619D02*
X923775Y-506661D01*
X925522Y-507827D01*
X927487Y-508119D01*
X929234Y-507827D01*
X930981Y-506369D01*
X932072Y-504619D01*
X932291Y-502869D01*
X931854Y-500828D01*
X930326Y-499369D01*
X928797Y-498786D01*
X926832D01*
G01X928797D02*
X930107Y-497911D01*
X931199Y-496453D01*
X931636Y-494703D01*
X931199Y-492952D01*
X930107Y-491494D01*
X928142Y-490619D01*
X926177Y-490911D01*
X924212Y-492078D01*
G01X940839Y-508702D02*
X948699Y-490619D01*
G01X958121Y-493536D02*
X959431Y-491786D01*
X960959Y-490911D01*
X962706Y-490619D01*
X964889Y-491202D01*
X966417Y-492661D01*
X966854Y-494410D01*
X966636Y-496161D01*
X965762Y-497619D01*
X961396Y-500536D01*
X959431Y-502577D01*
X958121Y-505495D01*
X957684Y-508119D01*
X966854D01*
G01X979769Y-490619D02*
X978022Y-491202D01*
X976712Y-492661D01*
X975839Y-494410D01*
X975184Y-496744D01*
X974966Y-499369D01*
X975184Y-501994D01*
X975839Y-504328D01*
X976712Y-506078D01*
X978022Y-507536D01*
X979769Y-508119D01*
X981515Y-507536D01*
X982826Y-506078D01*
X983699Y-504328D01*
X984354Y-501994D01*
X984572Y-499369D01*
X984354Y-496744D01*
X983699Y-494410D01*
X982826Y-492661D01*
X981515Y-491202D01*
X979769Y-490619D01*
G01X997269Y-508119D02*
Y-490619D01*
X994649Y-494119D01*
G01Y-508119D02*
X999889D01*
G01X1017389D02*
Y-490619D01*
X1009310Y-503161D01*
X1020228D01*
G01X904966Y-463119D02*
Y-445619D01*
X909332D01*
X911079Y-446494D01*
X912389Y-447661D01*
X913481Y-449410D01*
X914354Y-451453D01*
X914572Y-454369D01*
X914354Y-457286D01*
X913481Y-459328D01*
X912389Y-461078D01*
X911079Y-462244D01*
X909332Y-463119D01*
X904966D01*
G01X931199D02*
Y-451453D01*
G01Y-453494D02*
X930326Y-452328D01*
X929015Y-451744D01*
X927487Y-451453D01*
X925959Y-452036D01*
X924649Y-453202D01*
X923775Y-454952D01*
X923339Y-457286D01*
X923775Y-459619D01*
X924649Y-461369D01*
X925959Y-462536D01*
X927487Y-463119D01*
X929015Y-462827D01*
X930326Y-461953D01*
X931199Y-460786D01*
G01X944769Y-445619D02*
Y-463119D01*
G01X941712Y-451453D02*
X947826D01*
G01X958994Y-455244D02*
X965981D01*
X965326Y-453202D01*
X964234Y-452036D01*
X962706Y-451453D01*
X961177Y-451744D01*
X959867Y-452619D01*
X958994Y-454661D01*
X958557Y-456411D01*
Y-458161D01*
X958994Y-459911D01*
X960086Y-461661D01*
X961396Y-462827D01*
X962924Y-463119D01*
X964452Y-462536D01*
X965981Y-460786D01*
G54D35*
X63304Y717920D03*
X55304Y753920D03*
X63272Y797704D03*
X58772D03*
X67772D03*
X81304Y717920D03*
X69804Y843420D03*
X96772Y717704D03*
X92772D03*
X87804Y843420D03*
X103804Y762920D03*
X102304Y890420D03*
X127654Y312153D03*
X179500Y865700D03*
X189555Y570200D03*
X194500Y864700D03*
X199000Y887200D03*
X210000Y832700D03*
X212000Y887200D03*
X232000Y832700D03*
X228000D03*
X220000D03*
X224000D03*
X216000Y887200D03*
X225000Y890700D03*
X229500D03*
X234623Y569383D03*
X273500Y201200D03*
X313485Y248572D03*
X312555Y442700D03*
X317985Y248572D03*
X341000Y97700D03*
X347000Y116129D03*
X357429Y250200D03*
X361929D03*
X352929D03*
X361178Y985700D03*
X366429Y250200D03*
X375429D03*
X370929D03*
X379929D03*
X376000Y873200D03*
X371500D03*
X380000Y922200D03*
X375500D03*
X373678Y985700D03*
X386555Y302700D03*
X395555D03*
X384500Y873700D03*
X384000Y922200D03*
X412500Y268700D03*
X396929Y257200D03*
X400555Y302700D03*
X405555D03*
X409555D03*
X398000Y873700D03*
X424929Y253100D03*
X420429D03*
X424929Y261100D03*
X423055Y297200D03*
X418555Y302700D03*
X414055D03*
X434540Y109700D03*
X440000Y239700D03*
X433929Y261100D03*
X444778Y808700D03*
X438278D03*
X444278Y879200D03*
X458555Y296700D03*
X450778Y879200D03*
X475778Y808700D03*
X469278D03*
X473778Y879200D03*
X480278D03*
X549000Y154700D03*
X549055Y330700D03*
X558955Y371600D03*
X554955D03*
X571000Y154700D03*
X659462Y484164D03*
X682382Y126142D03*
X686432Y129712D03*
X678222Y126292D03*
X690512Y129652D03*
X704716Y151984D03*
X698968Y782684D03*
X704000Y888200D03*
X724532Y57416D03*
X720032Y65416D03*
X715716Y90484D03*
X715468Y758184D03*
X736248Y152200D03*
X731716Y151984D03*
X725748Y184200D03*
X726000Y894700D03*
X763000Y459200D03*
X767000D03*
Y475200D03*
X765998Y711254D03*
X770498D03*
X788774Y478778D03*
X779774D03*
X780500Y884700D03*
X785000D03*
X806000Y731700D03*
X838055Y273700D03*
X833555D03*
X847055D03*
X851555D03*
X856055D03*
X842555D03*
X866500Y104200D03*
X865055Y273700D03*
X860555D03*
X868820Y360080D03*
X863820D03*
X867000Y436200D03*
X862500D03*
X869468Y704984D03*
X879500Y91200D03*
X873468Y704984D03*
X919000Y55200D03*
X998000Y484200D03*
X1003000D03*
X999000Y540200D03*
X1003000D03*
X1010500Y455200D03*
X1011000Y500200D03*
X1017000Y540200D03*
X1013000D03*
X1029500Y124200D03*
X1025500Y136700D03*
X1035000Y178700D03*
X1027716Y911168D03*
X1032216D03*
X1039500Y178700D03*
X1070478Y753424D03*
X1074968Y753384D03*
X1070098Y761284D03*
X1093961Y103242D03*
X1089961D03*
X1089500Y412200D03*
X1088000Y457700D03*
X1092500D03*
X1087988Y745324D03*
X1101968Y809984D03*
X1117500Y617700D03*
X1103000Y637700D03*
X1107000D03*
X1115000D03*
X1111000Y745700D03*
X1107468Y809784D03*
X1106500Y837200D03*
X1122000Y617700D03*
X1149934Y584872D03*
X1137500Y625700D03*
X1151500Y630200D03*
X1146500Y625700D03*
X1146000Y637700D03*
X1151500D03*
X1135468Y861984D03*
X1159500Y623700D03*
X1179000Y403700D03*
X1172000Y757200D03*
X1180000D03*
X1184000D03*
X1176000D03*
X1191000Y403700D03*
X1195000D03*
X1189000Y745700D03*
X1192000Y757200D03*
X1213000Y634200D03*
X1209000D03*
X1205000D03*
X1201000D03*
X1201968Y764484D03*
X1215716Y809168D03*
X1211216D03*
X1207000Y809200D03*
X1215500Y855200D03*
X1201500D03*
X1226500Y443700D03*
X1225500Y793200D03*
X1220000Y809200D03*
X1246500Y468700D03*
X1242000D03*
X1238100Y857300D03*
X1257000Y39700D03*
X1271500Y548700D03*
X1276000Y663700D03*
X1281000Y709200D03*
X1277000Y719700D03*
X1295500Y34200D03*
X1284500Y318200D03*
X1293968Y662984D03*
X1285000Y663200D03*
X1310500Y43200D03*
X1314500D03*
X1299968Y661484D03*
X1303784Y789232D03*
X1308784D03*
X1314284D03*
X1312500Y857450D03*
X1307468Y916984D03*
X1301968D03*
X1312468D03*
X1327000Y332200D03*
X1323500Y448700D03*
Y436700D03*
X1332117Y622112D03*
X1327617D03*
X1328968Y676484D03*
X1326000Y857450D03*
X1317000D03*
X1321500D03*
X1316968Y916984D03*
X1332500Y54200D03*
X1336500Y138700D03*
X1338500Y459700D03*
X1347468Y456484D03*
X1352000Y81700D03*
X1363117Y565612D03*
X1354417Y623112D03*
G54D17*
X23104Y840720D03*
X23100Y854200D03*
X48104Y842720D03*
X62604Y830720D03*
X74604Y889720D03*
X89072Y770504D03*
X89104Y790220D03*
Y798220D03*
Y806720D03*
Y811220D03*
X135300Y666500D03*
X137604Y808220D03*
Y803720D03*
Y799720D03*
Y812720D03*
X149300Y844000D03*
X165100Y457800D03*
X152100Y469800D03*
X161855Y530000D03*
X153855D03*
X159855Y550500D03*
X157800Y666500D03*
X181855Y525500D03*
X182043Y537396D03*
X187100Y474800D03*
X190800Y869500D03*
X207823Y521183D03*
X212300Y812000D03*
X218355Y560000D03*
Y564500D03*
X237300Y423000D03*
Y427000D03*
X243800Y855500D03*
Y859500D03*
Y847500D03*
X291459Y419678D03*
X320800Y98000D03*
X315805Y313152D03*
X315729Y334500D03*
X314729Y348500D03*
Y354000D03*
X341229Y237500D03*
X361605Y405270D03*
Y410000D03*
Y414500D03*
Y419000D03*
X356323Y463783D03*
X355323Y473783D03*
Y478283D03*
X356235Y468450D03*
X355323Y482783D03*
X375855Y330500D03*
Y335000D03*
Y339500D03*
Y344000D03*
Y357500D03*
Y362000D03*
X398800Y265400D03*
X402300Y885000D03*
X407300Y915500D03*
Y911500D03*
X425800Y236500D03*
X423055Y283200D03*
Y279200D03*
X427300Y941500D03*
Y945500D03*
X454800Y117500D03*
X462300Y185000D03*
X596800Y200500D03*
Y205000D03*
Y214000D03*
Y218500D03*
X644800Y440000D03*
X652764Y436538D03*
X648300Y453000D03*
X654300Y606900D03*
Y613400D03*
X674800Y768500D03*
X678126Y99024D03*
Y103524D03*
X681876Y94934D03*
X681886Y107744D03*
X683268Y797784D03*
Y807484D03*
Y802484D03*
X704300Y59500D03*
Y72500D03*
Y68000D03*
X719300Y197500D03*
Y193500D03*
X722000Y209000D03*
X724300Y887000D03*
Y882500D03*
Y899000D03*
X725768Y797484D03*
X745800Y82500D03*
Y88500D03*
Y94500D03*
Y99500D03*
X753016Y116784D03*
Y112284D03*
X749764Y476038D03*
X754800Y874500D03*
X768800Y668000D03*
X766800Y858000D03*
Y853500D03*
X782800Y546500D03*
X783300Y553500D03*
Y561000D03*
X775800Y644500D03*
X806574Y469578D03*
X792394Y570468D03*
Y574968D03*
Y579468D03*
X817800Y853500D03*
X847800Y715500D03*
X856941Y706312D03*
X878800Y334500D03*
Y338500D03*
X935750Y452700D03*
X943394Y51797D03*
X944800Y59500D03*
X1011800Y907000D03*
X1012016Y902468D03*
X1029800Y128500D03*
X1026800Y168500D03*
Y173000D03*
X1028074Y199578D03*
Y204578D03*
Y209578D03*
X1045800Y681000D03*
Y693000D03*
Y685000D03*
Y697000D03*
Y709000D03*
Y701000D03*
Y705000D03*
X1060268Y219284D03*
X1060300Y215000D03*
X1066300Y668000D03*
Y673000D03*
X1077800Y631500D03*
Y627500D03*
Y644000D03*
Y635500D03*
Y648000D03*
Y656000D03*
Y652000D03*
Y661500D03*
Y675500D03*
Y671500D03*
Y667500D03*
Y679500D03*
Y691500D03*
Y687500D03*
Y695500D03*
Y683500D03*
Y711500D03*
Y699500D03*
Y707500D03*
Y703500D03*
Y715500D03*
Y722500D03*
Y726500D03*
Y730500D03*
X1092768Y867284D03*
Y871784D03*
X1138800Y262500D03*
Y270500D03*
Y258500D03*
Y266500D03*
X1138768Y286284D03*
X1138800Y278500D03*
X1146300Y597000D03*
X1138300Y827000D03*
X1147800Y818000D03*
X1173300Y621000D03*
X1202300Y749000D03*
X1222300Y722500D03*
Y740500D03*
X1228800Y762000D03*
Y757500D03*
Y753000D03*
X1243977Y255000D03*
Y259500D03*
X1244800Y451500D03*
Y456000D03*
X1237300Y729500D03*
X1260800Y30000D03*
X1253788Y235000D03*
X1257800Y577000D03*
X1250300Y671000D03*
Y684000D03*
X1259300Y779000D03*
X1273300Y674500D03*
Y681000D03*
X1312800Y318000D03*
X1305300Y316500D03*
X1312917Y559912D03*
Y564412D03*
Y568912D03*
Y581912D03*
X1313000Y573000D03*
X1312917Y590912D03*
Y607912D03*
Y621412D03*
Y616912D03*
X1338917Y623912D03*
X1354300Y448000D03*
G54D44*
X127654Y303753D03*
X190500Y889800D03*
X212500Y807300D03*
X203500Y889800D03*
X220500D03*
X274000Y915800D03*
X269000D03*
X295500Y130300D03*
X306400Y75200D03*
X301400D03*
X302159Y430478D03*
X332500Y941400D03*
X348000Y87300D03*
X353000Y76800D03*
X348000Y76300D03*
X392000Y45300D03*
X659462Y495264D03*
X687968Y776784D03*
X727968Y774784D03*
X784274Y481378D03*
X775500Y710800D03*
X806274Y459878D03*
X1018500Y501800D03*
X1026500Y147300D03*
X1052100Y182400D03*
X1095000Y757800D03*
X1175177Y231800D03*
X1190500Y233300D03*
X1263700Y473000D03*
X1324000Y55800D03*
X1347000Y83800D03*
X1343000Y461800D03*
X1362500Y443800D03*
Y454800D03*
G54D173*
X1344617Y593412D03*
G54D62*
X196800Y905710D03*
Y913310D03*
X204900Y905710D03*
Y913310D03*
X267500Y204800D03*
Y197200D03*
X307485Y250672D03*
Y243072D03*
X324485Y251172D03*
Y243572D03*
X328429Y320300D03*
Y312700D03*
Y327200D03*
Y334800D03*
Y341700D03*
Y349300D03*
Y356200D03*
Y363800D03*
X318555Y436200D03*
X326555D03*
X318555Y443800D03*
X326555D03*
X336429Y320300D03*
Y312700D03*
Y327200D03*
Y334800D03*
Y341700D03*
Y349300D03*
Y356200D03*
Y363800D03*
X385500Y37600D03*
Y45200D03*
X579882Y269700D03*
Y277300D03*
X640500Y395700D03*
Y403300D03*
X648500Y395700D03*
Y403300D03*
X657000Y395700D03*
Y403300D03*
X692962Y450264D03*
Y442664D03*
X787000Y725200D03*
Y732800D03*
X802824Y336248D03*
Y343848D03*
X811838Y435740D03*
X820438D03*
X811838Y443340D03*
X820438D03*
X1028500Y254200D03*
X1036500D03*
X1028500Y261800D03*
X1036500D03*
X1045968Y172984D03*
Y180584D03*
X1066500Y173200D03*
Y180800D03*
X1084000Y148800D03*
Y141200D03*
X1083000Y173200D03*
X1072000Y165800D03*
Y158200D03*
X1080000Y165800D03*
Y158200D03*
X1074500Y173200D03*
X1083000Y180800D03*
X1074500D03*
X1085468Y882484D03*
Y890084D03*
X1088500Y753700D03*
Y761300D03*
X1103500Y787200D03*
Y794800D03*
X1093468Y882484D03*
Y890084D03*
X1114468Y248484D03*
Y256084D03*
X1128500Y825700D03*
Y833300D03*
X1141468Y876484D03*
X1149468D03*
X1141468Y884084D03*
X1149468D03*
X1157468Y876484D03*
X1165468D03*
X1157468Y884084D03*
X1165468D03*
X1257468Y466484D03*
Y474084D03*
X1277500Y462700D03*
Y470300D03*
X1293500Y446200D03*
Y453800D03*
Y462700D03*
X1285500D03*
X1293500Y470300D03*
X1285500D03*
X1302000Y462700D03*
Y470300D03*
X1366500Y429800D03*
Y422200D03*
X1374500Y429800D03*
Y422200D03*
G54D71*
X224297Y912750D03*
X230703D03*
G54D128*
X751484Y548491D03*
Y553491D03*
Y558491D03*
Y563491D03*
X771484Y548491D03*
Y563491D03*
Y558491D03*
Y553491D03*
X997274Y199578D03*
Y204578D03*
Y209578D03*
Y214578D03*
X1017274Y204578D03*
Y199578D03*
Y214578D03*
Y209578D03*
X1159934Y599672D03*
Y604672D03*
Y609672D03*
Y614672D03*
X1179934D03*
Y609672D03*
Y604672D03*
Y599672D03*
X1255000Y583000D03*
Y588000D03*
Y593000D03*
Y598000D03*
X1275000Y583000D03*
Y598000D03*
Y593000D03*
Y588000D03*
X1287372Y301500D03*
Y296500D03*
Y291500D03*
Y306500D03*
X1314872Y291500D03*
Y296500D03*
Y301500D03*
Y306500D03*
G54D164*
X1312500Y14200D03*
Y19800D03*
X1321000Y14200D03*
Y19800D03*
G54D119*
X708216Y112426D03*
Y114394D03*
Y116363D03*
Y118331D03*
Y120300D03*
Y122268D03*
Y124237D03*
Y126205D03*
Y128174D03*
Y130142D03*
X735216Y122268D03*
Y120300D03*
Y118331D03*
Y116363D03*
Y114394D03*
Y112426D03*
Y130142D03*
Y128174D03*
Y126205D03*
Y124237D03*
G54D155*
X1212840Y775850D03*
X1210280D03*
X1207720D03*
X1205160D03*
Y792150D03*
X1207720D03*
X1210280D03*
X1212840D03*
G54D53*
X166200Y666500D03*
X310100Y56700D03*
Y51700D03*
Y61700D03*
X380200Y943000D03*
X432255Y290600D03*
X682700Y473000D03*
X759948Y123500D03*
X787974Y434078D03*
X784200Y897000D03*
X806474Y465078D03*
X876200Y330000D03*
X1050916Y277968D03*
X1050700Y283000D03*
X1067700Y141000D03*
X1079200Y412000D03*
X1091700Y61000D03*
Y66500D03*
X1110700Y280000D03*
X1140168Y252784D03*
X1145200Y592500D03*
X1146700Y827000D03*
X1181270Y777000D03*
X1222200Y452500D03*
X1248400Y209700D03*
X1249200Y675500D03*
X1276200Y569000D03*
X1286112Y434712D03*
X1304200Y363000D03*
X1344700Y420000D03*
X1348317Y562412D03*
G54D26*
X48004Y849720D03*
X149200Y848000D03*
X225200Y883500D03*
X243700Y851500D03*
X312723Y497183D03*
Y524683D03*
X341129Y241500D03*
X339455Y449840D03*
X355223Y486783D03*
X433700Y268500D03*
X559700Y252500D03*
X563755Y328500D03*
X648200Y457000D03*
X758700Y67500D03*
X792294Y583468D03*
X801700Y860500D03*
Y856000D03*
X845700Y868500D03*
X869700Y409500D03*
X876700Y636500D03*
X927200Y51500D03*
X1011916Y879968D03*
X1037700Y124000D03*
X1052700Y287500D03*
X1052424Y291756D03*
Y296156D03*
X1052400Y299600D03*
X1048416Y900968D03*
X1064200Y737500D03*
X1054200Y844500D03*
X1113200Y817000D03*
X1138668Y282284D03*
X1147700Y814000D03*
X1138200Y822500D03*
X1147700D03*
X1207200Y878500D03*
X1249700Y197500D03*
Y201500D03*
Y205500D03*
X1248200Y435500D03*
X1281700Y564500D03*
X1369817Y593912D03*
G54D80*
X286359Y430678D03*
X294959Y426938D03*
Y434418D03*
G54D146*
X1066929Y43267D03*
X1057086D03*
X1084646D03*
X1074803D03*
G54D137*
X805750Y363500D03*
X805250D03*
X1367750Y356500D03*
X1367250D03*
G54D183*
G01X131890Y269528D02*
X130654Y270764D01*
Y305703D01*
X127654Y308703D01*
G01X121890Y269528D02*
Y289217D01*
X117654Y293453D01*
Y301703D01*
G01X127654Y303953D02*
X125154D01*
X122904Y301703D01*
X117654D01*
G01X132123Y318877D02*
X134694Y316306D01*
X137944D01*
X138000Y316250D01*
G01X119904Y316453D02*
X120029D01*
X121529Y314953D01*
Y309203D01*
G01X119904Y320953D02*
Y316453D01*
G01X123654Y320953D02*
X119904D01*
G01X138250Y283500D02*
Y280357D01*
X141890Y276717D01*
Y269528D01*
G01X138250Y283500D02*
X135364Y287292D01*
Y290190D01*
G01D02*
Y294663D01*
X139191Y298490D01*
Y298593D01*
G01X139750Y312000D02*
Y310750D01*
X143066Y307434D01*
Y306093D01*
G01X138000Y316250D02*
X139750Y314500D01*
Y312000D01*
G01X180118Y739409D02*
Y729409D01*
G01X373894Y7992D02*
X375902Y10000D01*
X381500D01*
X385000Y13500D01*
G01X386264Y7992D02*
Y9764D01*
X390000Y13500D01*
G01X421138Y7992D02*
X414008D01*
X414000Y8000D01*
G01X433508Y7992D02*
X437492D01*
X438500Y9000D01*
G01X432055Y290600D02*
X435000Y293545D01*
Y294000D01*
G01X438055Y290600D02*
X438174D01*
X442074Y294500D01*
X452477D01*
X452977Y295000D01*
G01X458429Y101500D02*
Y105000D01*
X459429Y106000D01*
G01X452429Y101500D02*
X450929D01*
X448929Y99500D01*
G01X452977Y295000D02*
X453500Y295523D01*
Y303500D01*
G01X520000Y146000D02*
X516500D01*
X515000Y144500D01*
X506500D01*
X504500Y146500D01*
X503929D01*
G01X520000Y152000D02*
X508929D01*
X506429Y149500D01*
G01X590315Y9134D02*
X585300Y14149D01*
Y26000D01*
X595200Y35900D01*
X658300D01*
X664300Y41900D01*
Y61300D01*
X666500Y63500D01*
X670748D01*
G01X649527Y19134D02*
X670748Y40355D01*
Y56500D01*
G01X706716Y90534D02*
Y90968D01*
X709848Y94100D01*
G01X708216Y124237D02*
X703975D01*
X703608Y123870D01*
X695878D01*
X694466Y125282D01*
Y133282D01*
G01D02*
Y137784D01*
G01X712858Y134784D02*
Y138390D01*
X710673Y140575D01*
X707472D01*
X706822Y141225D01*
G01X704716Y148534D02*
Y143331D01*
X706822Y141225D01*
G01X720216Y90534D02*
Y96732D01*
X718448Y98500D01*
Y100900D01*
G01X718763Y107784D02*
Y101215D01*
X718448Y100900D01*
G01X714826Y107784D02*
Y104500D01*
X713048Y102722D01*
Y97300D01*
X709848Y94100D01*
G01X735216Y116363D02*
X743137D01*
X744000Y115500D01*
G01X752966Y116784D02*
X751682Y115500D01*
X744000D01*
G01X862500Y65000D02*
X857000Y70500D01*
Y80500D01*
G01X869987Y82376D02*
X858876D01*
X857000Y80500D01*
G01X879500Y87750D02*
X874126Y82376D01*
X869987D01*
G01X885750Y56500D02*
X879500D01*
G01D02*
X874500D01*
X874000Y56000D01*
G01X878500Y77000D02*
X873000Y71500D01*
Y68500D01*
G01X879500Y67500D02*
X873500Y61500D01*
G01X886200Y70500D02*
X882500D01*
X879500Y67500D01*
G01X886200Y84500D02*
X886000D01*
X878500Y77000D01*
G01X907000Y465050D02*
X937450Y495500D01*
Y679050D01*
X881000Y735500D01*
Y736500D01*
G01X893250Y52625D02*
X899125D01*
X899750Y53250D01*
G01D02*
X909500D01*
G01X904500Y71250D02*
Y76000D01*
G01D02*
X907500D01*
X947500Y116000D01*
Y153000D01*
G01X919000Y55250D02*
X911500D01*
X909500Y53250D01*
G01X917250Y70500D02*
X912250D01*
G01X913375Y60750D02*
Y65125D01*
X912250Y66250D01*
G01Y70500D02*
Y66250D01*
G01X1184389Y687560D02*
X1185839Y689010D01*
X1191530D01*
X1192845Y690325D01*
X1214035D01*
X1220210Y696500D01*
X1239100D01*
G01X1224750Y692250D02*
X1219920D01*
X1215195Y687525D01*
X1192982D01*
X1192946Y687560D01*
X1187539D01*
G01X1184389Y700158D02*
X1185939Y701708D01*
X1190667D01*
X1190867Y701908D01*
X1192317D01*
X1193275Y700950D01*
X1208950D01*
X1209500Y701500D01*
G01X1187539Y703308D02*
X1187981Y703750D01*
X1207750D01*
X1211775Y707775D01*
X1222275D01*
X1223500Y709000D01*
G01X1250250Y711500D02*
X1247000D01*
X1240475Y704975D01*
X1213945D01*
X1210470Y701500D01*
X1209500D01*
G01X1250500Y692250D02*
X1224750D01*
G01X1249000Y716000D02*
X1246500D01*
X1239500Y709000D01*
X1223500D01*
G01X1239100Y696500D02*
X1245000D01*
X1248000Y699500D01*
X1250250D01*
G01X1268631Y38583D02*
X1261862D01*
G01X1257000Y39750D02*
X1257833D01*
X1259000Y38583D01*
X1261862D01*
G01X1250500Y695750D02*
Y699250D01*
X1250250Y699500D01*
G01X1254000Y692250D02*
X1250500D01*
G01X1312500Y19800D02*
Y25800D01*
X1306500Y31800D01*
Y38000D01*
G01X1312500Y14200D02*
X1320700Y6000D01*
X1325500D01*
X1330000Y10500D01*
Y30000D01*
X1347000Y47000D01*
Y48000D01*
G01X1318500Y37500D02*
X1316250Y39750D01*
X1314500D01*
G01X1310500D02*
X1308250D01*
X1306500Y38000D01*
G01X1312260Y54737D02*
X1318237D01*
X1318500Y55000D01*
G01Y37500D02*
X1321000Y35000D01*
Y19800D01*
G01Y14200D02*
X1326750Y19950D01*
Y35250D01*
X1342500Y51000D01*
G01X1324000Y56000D02*
X1319500D01*
X1318500Y55000D01*
G01X1328200Y50000D02*
X1324000D01*
G01X1332500Y50750D02*
X1328950D01*
X1328200Y50000D01*
G01X1339000Y112250D02*
X1343250D01*
X1343500Y112000D01*
G01X1354000Y112250D02*
X1349750D01*
X1349500Y112000D01*
G54D81*
X302750Y18000D03*
X318250D03*
G54D63*
X214800Y823000D03*
X207200D03*
X244700Y841500D03*
X252300D03*
X274800Y188500D03*
X267200D03*
X274800Y180500D03*
X267200D03*
X314785Y227872D03*
X307185D03*
X314785Y235872D03*
X307185D03*
X313205Y319652D03*
X313129Y328500D03*
X313629Y342000D03*
X306729D03*
X299129D03*
X313629Y360500D03*
X322685Y235872D03*
X330285D03*
X322685Y227872D03*
X330285D03*
X320805Y319652D03*
X320729Y328500D03*
X321229Y342000D03*
Y360500D03*
X375200Y66000D03*
X367600D03*
X396700Y271400D03*
X405129Y251400D03*
X412729D03*
X404300Y271400D03*
X405129Y259400D03*
X412729D03*
X573300Y431500D03*
X565700D03*
X573300Y439500D03*
X565700D03*
X595598Y386616D03*
X603198D03*
X595598Y377616D03*
X603198D03*
X595598Y395116D03*
X603198D03*
X595598Y403616D03*
X603198D03*
X595598Y419616D03*
X603198D03*
X595598Y411616D03*
X603198D03*
X619700Y413000D03*
X627300D03*
X619700Y429000D03*
X627300D03*
X619700Y421000D03*
X627300D03*
X619700Y437000D03*
X627300D03*
X687966Y88544D03*
X680366D03*
X685186Y114964D03*
X677586D03*
X681662Y479464D03*
X689262D03*
X681662Y487464D03*
X689262D03*
X681662Y495464D03*
X689262D03*
X681700Y511500D03*
X689300D03*
X681662Y503464D03*
X689262D03*
X681700Y519500D03*
X689300D03*
X771574Y448078D03*
X763974D03*
X786300Y361500D03*
X778700D03*
X786300Y369500D03*
X778700D03*
X786300Y377500D03*
X778700D03*
X786300Y385500D03*
X778700D03*
X824300Y382000D03*
X816700D03*
X824300Y374000D03*
X816700D03*
X824300Y398000D03*
X816700D03*
X824300Y390000D03*
X816700D03*
X855300Y370000D03*
X847700D03*
X855300Y378500D03*
X847700D03*
X852300Y726500D03*
X844700D03*
X1000200Y69500D03*
X1007800D03*
X1052700Y858500D03*
Y850500D03*
Y874500D03*
Y866500D03*
X1045416Y906968D03*
X1053016D03*
X1045416Y914968D03*
X1053016D03*
X1060300Y858500D03*
Y850500D03*
Y874500D03*
Y866500D03*
X1257200Y570500D03*
X1264800D03*
X1298168Y434784D03*
X1305768D03*
X1325300Y427000D03*
X1317700D03*
X1364700Y380000D03*
Y388000D03*
X1372300Y380000D03*
Y388000D03*
G54D156*
X1233050Y778453D03*
Y772547D03*
X1248950Y778465D03*
Y772547D03*
G54D174*
X1371572Y122170D03*
G54D138*
X837031Y396460D03*
Y399019D03*
Y401578D03*
Y404137D03*
Y406696D03*
X856517Y401578D03*
Y399019D03*
Y396460D03*
Y406696D03*
Y404137D03*
X1106725Y865166D03*
Y867725D03*
Y870284D03*
Y872843D03*
Y875402D03*
X1126211D03*
Y872843D03*
Y870284D03*
Y867725D03*
Y865166D03*
G54D90*
X321001Y83682D03*
X319032D03*
X322969D03*
X324938D03*
X326906D03*
X328875D03*
X332812D03*
X330843D03*
G54D54*
X175993Y544096D03*
X179743D03*
Y554696D03*
X175993D03*
X183493Y544096D03*
Y554696D03*
X1094250Y90300D03*
X1090500D03*
X1086750D03*
Y79700D03*
X1090500D03*
X1094250D03*
G54D72*
X234614Y891272D03*
X236386D03*
G54D36*
X71804Y793920D03*
X175500Y906700D03*
X171500D03*
X190800Y467000D03*
X186800D03*
X238455Y565800D03*
X309500Y88200D03*
X328555Y506700D03*
X324555D03*
X347023Y505983D03*
X373500Y14700D03*
X377000D03*
X367500Y869700D03*
X380500Y14700D03*
X594500Y240200D03*
X651964Y440738D03*
X685748Y99700D03*
X683055Y262700D03*
X687055D03*
X706500Y859700D03*
X711500Y68200D03*
X714055Y262700D03*
X718055D03*
X724000Y478700D03*
X729748Y180700D03*
X738117Y544668D03*
X742517D03*
X743000Y571700D03*
X771000Y455700D03*
X806274Y438778D03*
X792774Y475278D03*
X849500Y432700D03*
X857500Y649200D03*
X904500Y67700D03*
X984260Y195207D03*
X988660D03*
X1097500Y789200D03*
X1118300Y753200D03*
X1110468Y846984D03*
X1122800Y753200D03*
X1150258Y753394D03*
X1156768Y753484D03*
X1164200Y753400D03*
X1173000Y386700D03*
X1209470Y565210D03*
X1226500Y432200D03*
X1242100Y821800D03*
X1254000Y692200D03*
X1250500D03*
X1273000Y716200D03*
X1358617Y562112D03*
X1371617D03*
X1367617D03*
G54D27*
X51604Y849720D03*
X152800Y848000D03*
X228800Y883500D03*
X247300Y851500D03*
X316323Y497183D03*
Y524683D03*
X344729Y241500D03*
X343055Y449840D03*
X358823Y486783D03*
X437300Y268500D03*
X563300Y252500D03*
X567355Y328500D03*
X651800Y457000D03*
X762300Y67500D03*
X795894Y583468D03*
X805300Y860500D03*
Y856000D03*
X849300Y868500D03*
X873300Y409500D03*
X880300Y636500D03*
X930800Y51500D03*
X1015516Y879968D03*
X1041300Y124000D03*
X1052016Y900968D03*
X1056300Y287500D03*
X1056024Y291756D03*
Y296156D03*
X1056000Y299600D03*
X1067800Y737500D03*
X1057800Y844500D03*
X1116800Y817000D03*
X1142268Y282284D03*
X1151300Y814000D03*
X1141800Y822500D03*
X1151300D03*
X1210800Y878500D03*
X1253300Y197500D03*
Y201500D03*
Y205500D03*
X1251800Y435500D03*
X1285300Y564500D03*
X1373417Y593912D03*
G54D165*
X1317000Y331850D03*
X1322500D03*
G54D18*
X23104Y845220D03*
Y849720D03*
X30104Y885720D03*
X55104Y830720D03*
X56104Y872720D03*
Y877720D03*
Y868220D03*
Y882220D03*
X74604Y885720D03*
X89104Y815220D03*
X99104Y882720D03*
X116454Y316453D03*
Y320953D03*
X101104Y844220D03*
X138300Y283500D03*
X136300Y312000D03*
X143300Y666500D03*
X137604Y791720D03*
Y783720D03*
X152100Y474300D03*
X172600Y457800D03*
X181855Y530000D03*
X190300Y840000D03*
Y844000D03*
Y856500D03*
X186800Y865500D03*
X190800Y878500D03*
X237300Y419000D03*
Y431000D03*
X243300Y835500D03*
X243800Y863500D03*
X260959Y425678D03*
Y430178D03*
Y434678D03*
X269300Y884500D03*
X312823Y507683D03*
X320800Y93500D03*
X317323Y464283D03*
Y459783D03*
X317293Y454373D03*
X318323Y479783D03*
Y475283D03*
X343800Y884500D03*
Y878500D03*
Y893000D03*
X361355Y385000D03*
Y376000D03*
Y380500D03*
Y371000D03*
X361615Y400500D03*
X361355Y394000D03*
Y389500D03*
X351300Y884500D03*
Y878500D03*
Y893000D03*
Y889000D03*
X375855Y312500D03*
Y317000D03*
Y321500D03*
Y326000D03*
Y348500D03*
Y353000D03*
Y366500D03*
Y371000D03*
Y375500D03*
X376823Y387783D03*
X375075Y403780D03*
X375105Y408500D03*
Y417500D03*
Y413000D03*
Y426500D03*
Y422000D03*
Y431000D03*
Y435500D03*
X402300Y880500D03*
X421300Y268000D03*
X423055Y287200D03*
Y275200D03*
X438840Y106000D03*
Y110000D03*
X431840Y117500D03*
X438800Y244000D03*
X446300Y106000D03*
Y110000D03*
Y114500D03*
X457800Y277500D03*
Y273000D03*
X459800Y282000D03*
X462729Y165500D03*
Y172500D03*
Y180500D03*
X462300Y197000D03*
X462229Y189500D03*
X462300Y286500D03*
X469355Y293800D03*
X596800Y209500D03*
Y223000D03*
Y227500D03*
X635800Y453000D03*
X628300Y579000D03*
Y588500D03*
Y584000D03*
X627800Y606900D03*
Y612900D03*
X652764Y432538D03*
X644800Y444500D03*
X648300Y448500D03*
X673966Y94544D03*
X691016Y137784D03*
X704300Y63500D03*
X698800Y863500D03*
X722832Y100532D03*
X709800Y576500D03*
Y582000D03*
Y572000D03*
X724300Y864000D03*
X731548Y189500D03*
X724800Y455500D03*
X736264Y558538D03*
Y563538D03*
X737800Y553500D03*
X740268Y768784D03*
X732768D03*
Y763984D03*
X725768Y806284D03*
Y801984D03*
X753800Y82500D03*
Y88500D03*
Y94500D03*
Y99500D03*
X749764Y471538D03*
X752300Y571000D03*
Y575500D03*
X758800Y51500D03*
Y55500D03*
Y59500D03*
Y63500D03*
X762800Y138500D03*
Y134000D03*
X762700Y144300D03*
X775800Y649000D03*
X776300Y668000D03*
X796800Y471000D03*
X795800Y546500D03*
Y553500D03*
Y561000D03*
X801800Y851000D03*
X821300Y873000D03*
X835300Y858000D03*
X869800Y414000D03*
Y404500D03*
X865800Y467500D03*
X856800Y711000D03*
X872800Y101500D03*
X873800Y467500D03*
X917300Y70500D03*
X908800D03*
X983574Y204578D03*
Y209578D03*
Y214578D03*
X994300Y496500D03*
X1029800Y133000D03*
X1028074Y214078D03*
X1025016Y866968D03*
X1037800Y119500D03*
Y128500D03*
X1045800Y713000D03*
X1062768Y227284D03*
X1060268Y223284D03*
X1064300Y733500D03*
Y741500D03*
X1075268Y200784D03*
X1099300Y428000D03*
X1125800Y278000D03*
X1129800Y618000D03*
X1138800Y274500D03*
X1137800Y618000D03*
X1139768Y858284D03*
X1181300Y237000D03*
Y244000D03*
Y248000D03*
X1192477Y238000D03*
Y242500D03*
Y247500D03*
Y252500D03*
X1192468Y264060D03*
Y268560D03*
X1186300Y359000D03*
Y363500D03*
X1200300Y605500D03*
X1188800Y875500D03*
X1214584Y432532D03*
X1213800Y444000D03*
X1213270Y568510D03*
X1214800Y735500D03*
Y731000D03*
X1222300Y718500D03*
Y735500D03*
Y731000D03*
X1221800Y831500D03*
X1247477Y241500D03*
Y245500D03*
X1244300Y268500D03*
Y272500D03*
X1248300Y431500D03*
Y427500D03*
X1240300Y593000D03*
Y598000D03*
X1245800Y661000D03*
X1244300Y762000D03*
X1253788Y221500D03*
Y226000D03*
Y230500D03*
X1250300Y643000D03*
Y647000D03*
Y639000D03*
Y635000D03*
Y651000D03*
Y657000D03*
X1257800Y661000D03*
Y657000D03*
Y651000D03*
X1250300Y667000D03*
X1257800Y667500D03*
X1250300Y680000D03*
Y688000D03*
Y707500D03*
Y703500D03*
Y711500D03*
X1259300Y783000D03*
X1261900Y835100D03*
X1312917Y586412D03*
Y595412D03*
Y612412D03*
Y599912D03*
X1327300Y298000D03*
Y293000D03*
X1343917Y567412D03*
X1338917Y619412D03*
X1358800Y106000D03*
X1354300Y456000D03*
X1369917Y589912D03*
Y585412D03*
Y597912D03*
Y602412D03*
Y611412D03*
Y606912D03*
G54D147*
X1062000Y108750D03*
Y132250D03*
G54D129*
X747750Y698500D03*
X766250D03*
X842218Y691284D03*
X860718D03*
G54D45*
X127654Y298153D03*
X190500Y884200D03*
X212500Y801700D03*
X203500Y884200D03*
X220500D03*
X274000Y910200D03*
X269000D03*
X295500Y124700D03*
X306400Y69600D03*
X301400D03*
X302159Y424878D03*
X332500Y935800D03*
X353000Y71200D03*
X348000Y70700D03*
Y81700D03*
X392000Y39700D03*
X659462Y489664D03*
X687968Y771184D03*
X727968Y769184D03*
X784274Y475778D03*
X775500Y705200D03*
X806274Y454278D03*
X1018500Y496200D03*
X1026500Y141700D03*
X1052100Y176800D03*
X1095000Y752200D03*
X1175177Y226200D03*
X1190500Y227700D03*
X1263700Y467400D03*
X1324000Y50200D03*
X1347000Y78200D03*
X1343000Y456200D03*
X1362500Y438200D03*
Y449200D03*
G54D184*
G01X503895Y328340D02*
X503704Y328532D01*
G02X503640Y328685I153J154D01*
G01X502872Y329453D01*
G03X502155Y329750I-717J-717D01*
G01X498459D01*
G02X497855Y330000I0J854D01*
G01X497055D01*
G02X496463Y330050I1J3537D01*
G02X494554Y331036I592J3487D01*
G01X493504Y332086D01*
G01X506638Y336433D02*
X506594D01*
G03X505783Y336769I-811J-811D01*
G01X505586D01*
G02X503424I-1081J1081D01*
G03X501666Y337498I-1759J-1758D01*
G01X496499D01*
G02X496118Y337656I0J539D01*
G01X495242Y338222D01*
X493504Y339960D01*
G01X504850Y329295D02*
G03X504500Y329440I-350J-350D01*
G01X504095D01*
X503545Y329990D01*
G03X502290Y330510I-1255J-1255D01*
G01X499455D01*
G02X498708Y330820I1J1057D01*
G01X497441Y332086D01*
G01X506638Y337783D02*
X506009D01*
G03X505205Y337450I0J-1137D01*
G01X505055Y337300D01*
G02X503955I-550J550D01*
G03X501666Y338248I-2289J-2289D01*
G01X497255D01*
G02X496823Y338427I0J611D01*
G01X496550Y338700D01*
G02X496779Y339298I784J43D01*
G01X497441Y339960D01*
G54D82*
X303250Y81500D03*
X818024Y465078D03*
X1027750Y155000D03*
X1249750Y445000D03*
G54D139*
X846774Y401578D03*
X1035216Y884468D03*
X1116468Y870284D03*
G54D175*
X1369720Y117145D03*
Y110415D03*
X1390004Y117145D03*
Y110415D03*
G54D157*
X1245921Y768500D03*
X1243953D03*
X1241984D03*
X1240016D03*
X1238047D03*
X1236079D03*
Y782500D03*
X1238047D03*
X1240016D03*
X1241984D03*
X1243953D03*
X1245921D03*
G54D28*
X45270Y901388D03*
X47770D03*
X50270D03*
Y921988D03*
X47770D03*
X45270D03*
X62637Y729959D03*
X65197D03*
Y752049D03*
X62637D03*
X66612Y808104D03*
X64052D03*
X61492D03*
X58932D03*
Y820904D03*
X61492D03*
X64052D03*
X66612D03*
X67453Y853207D03*
Y875297D03*
X52770Y901388D03*
X55270D03*
X57770D03*
X60270D03*
X62770D03*
X65270D03*
Y921988D03*
X62770D03*
X60270D03*
X57770D03*
X55270D03*
X52770D03*
X67757Y729959D03*
X70317D03*
X72872D03*
X75432D03*
X77992D03*
X80552D03*
X83112D03*
Y752049D03*
X80552D03*
X77992D03*
X75432D03*
X72872D03*
X70317D03*
X67757D03*
X70013Y853207D03*
X72573D03*
X75133D03*
X77688D03*
X80248D03*
X82808D03*
Y875297D03*
X80248D03*
X77688D03*
X75133D03*
X72573D03*
X70013D03*
X67770Y901388D03*
X70270D03*
X72770D03*
Y921988D03*
X70270D03*
X67770D03*
X85672Y729959D03*
X88227D03*
X90787D03*
X93347D03*
X95907D03*
Y752049D03*
X93347D03*
X90787D03*
X88227D03*
X85672D03*
X85368Y853207D03*
X87928D03*
X90488D03*
X93043D03*
X95603D03*
X98163D03*
Y875297D03*
X95603D03*
X93043D03*
X90488D03*
X87928D03*
X85368D03*
X100723Y853207D03*
Y875297D03*
X104054Y901420D03*
X106554D03*
X109054D03*
X111554D03*
X114054D03*
X116554D03*
Y922020D03*
X114054D03*
X111554D03*
X109054D03*
X106554D03*
X104054D03*
X119054Y901420D03*
X121554D03*
X124054D03*
X126554D03*
X129054D03*
X131554D03*
Y922020D03*
X129054D03*
X126554D03*
X124054D03*
X121554D03*
X119054D03*
X341250Y921700D03*
X343750D03*
X346250D03*
Y942300D03*
X343750D03*
X341250D03*
X348750Y921700D03*
X351250D03*
X353750D03*
X356250D03*
X358750D03*
X361250D03*
Y942300D03*
X358750D03*
X356250D03*
X353750D03*
X351250D03*
X348750D03*
X363750Y921700D03*
X366250D03*
X368750D03*
Y942300D03*
X366250D03*
X363750D03*
X393250Y922200D03*
X395750D03*
Y942800D03*
X393250D03*
X398250Y922200D03*
X400750D03*
X403250D03*
X405750D03*
X408250D03*
X410750D03*
Y942800D03*
X408250D03*
X405750D03*
X403250D03*
X400750D03*
X398250D03*
X413250Y922200D03*
X415750D03*
X418250D03*
X420750D03*
Y942800D03*
X418250D03*
X415750D03*
X413250D03*
X558495Y339988D03*
X555935D03*
X553375D03*
X550815D03*
Y356168D03*
X553375D03*
X555935D03*
X558495D03*
X994660Y513600D03*
X997220D03*
X999780D03*
X1002340D03*
Y526400D03*
X999780D03*
X997220D03*
X994660D03*
X1008660Y513600D03*
X1011220D03*
X1013780D03*
X1016340D03*
Y526400D03*
X1013780D03*
X1011220D03*
X1008660D03*
X1182660Y373910D03*
Y390090D03*
X1190340Y373910D03*
X1187780D03*
X1185220D03*
Y390090D03*
X1187780D03*
X1190340D03*
G54D64*
X215110Y848450D03*
Y868550D03*
X228890Y848450D03*
Y868550D03*
G54D46*
X129600Y839160D03*
Y841720D03*
Y844280D03*
Y846840D03*
X142400Y844280D03*
Y841720D03*
Y839160D03*
Y846840D03*
X331623Y454943D03*
Y457503D03*
Y460063D03*
Y462623D03*
X331123Y476943D03*
Y479503D03*
Y482063D03*
Y484623D03*
X344423Y462623D03*
Y460063D03*
Y457503D03*
Y454943D03*
X343923Y482063D03*
Y479503D03*
Y476943D03*
Y484623D03*
X368900Y882420D03*
Y884980D03*
Y887540D03*
Y890100D03*
Y892660D03*
Y895220D03*
Y897780D03*
Y900340D03*
Y902900D03*
Y905460D03*
Y908020D03*
Y910580D03*
X391100Y892660D03*
Y890100D03*
Y887540D03*
Y884980D03*
Y882420D03*
Y910580D03*
Y908020D03*
Y905460D03*
Y902900D03*
Y900340D03*
Y897780D03*
Y895220D03*
X433765Y276060D03*
Y278620D03*
Y281180D03*
Y283740D03*
X449945D03*
Y281180D03*
Y278620D03*
Y276060D03*
X639874Y577738D03*
Y580298D03*
Y582858D03*
Y585418D03*
X652674Y580298D03*
Y577738D03*
Y585418D03*
Y582858D03*
X723600Y573160D03*
Y575720D03*
Y578280D03*
Y580840D03*
X736400D03*
Y578280D03*
Y575720D03*
Y573160D03*
X745400Y894120D03*
Y891560D03*
Y889000D03*
Y886440D03*
Y883880D03*
Y881325D03*
Y896675D03*
X765694Y573128D03*
Y575688D03*
Y578248D03*
Y580808D03*
X767600Y881325D03*
Y883880D03*
Y886440D03*
Y889000D03*
Y891560D03*
Y894120D03*
Y896675D03*
X778494Y580808D03*
Y578248D03*
Y575688D03*
Y573128D03*
G54D73*
X235500Y887728D03*
G54D55*
X181055Y565550D03*
X178496D03*
X181055Y573450D03*
X178496D03*
X183614Y565550D03*
Y573450D03*
X390988Y248050D03*
X388429D03*
X385870D03*
X390988Y255950D03*
X388429D03*
X385870D03*
G54D37*
X71804Y797520D03*
X175500Y910300D03*
X171500D03*
X190800Y470600D03*
X186800D03*
X238455Y569400D03*
X309500Y91800D03*
X328555Y510300D03*
X324555D03*
X347023Y509583D03*
X373500Y18300D03*
X377000D03*
X367500Y873300D03*
X380500Y18300D03*
X594500Y243800D03*
X651964Y444338D03*
X685748Y103300D03*
X683055Y266300D03*
X687055D03*
X706500Y863300D03*
X711500Y71800D03*
X714055Y266300D03*
X718055D03*
X724000Y482300D03*
X729748Y184300D03*
X738117Y548268D03*
X742517D03*
X743000Y575300D03*
X771000Y459300D03*
X806274Y442378D03*
X792774Y478878D03*
X849500Y436300D03*
X857500Y652800D03*
X904500Y71300D03*
X984260Y198807D03*
X988660D03*
X1097500Y792800D03*
X1118300Y756800D03*
X1110468Y850584D03*
X1122800Y756800D03*
X1150258Y756994D03*
X1156768Y757084D03*
X1164200Y757000D03*
X1173000Y390300D03*
X1209470Y568810D03*
X1226500Y435800D03*
X1242100Y825400D03*
X1254000Y695800D03*
X1250500D03*
X1273000Y719800D03*
X1358617Y565712D03*
X1371617D03*
X1367617D03*
G54D166*
X1317000Y329150D03*
X1322500D03*
G54D19*
X26504Y845220D03*
Y849720D03*
X33504Y885720D03*
X58504Y830720D03*
X59504Y872720D03*
Y877720D03*
Y868220D03*
Y882220D03*
X78004Y885720D03*
X92504Y815220D03*
X104504Y844220D03*
X102504Y882720D03*
X119854Y316453D03*
Y320953D03*
X141700Y283500D03*
X139700Y312000D03*
X146700Y666500D03*
X141004Y791720D03*
Y783720D03*
X155500Y474300D03*
X176000Y457800D03*
X185255Y530000D03*
X193700Y840000D03*
Y844000D03*
Y856500D03*
X190200Y865500D03*
X194200Y878500D03*
X240700Y419000D03*
Y431000D03*
X246700Y835500D03*
X247200Y863500D03*
X264359Y425678D03*
Y430178D03*
Y434678D03*
X272700Y884500D03*
X324200Y93500D03*
X320723Y464283D03*
Y459783D03*
X320693Y454373D03*
X321723Y479783D03*
Y475283D03*
X316223Y507683D03*
X347200Y884500D03*
Y878500D03*
Y893000D03*
X354700Y884500D03*
Y878500D03*
Y893000D03*
Y889000D03*
X379255Y312500D03*
Y317000D03*
Y321500D03*
Y326000D03*
Y348500D03*
Y353000D03*
Y366500D03*
Y371000D03*
X364755Y385000D03*
Y376000D03*
Y380500D03*
Y371000D03*
X379255Y375500D03*
X365015Y400500D03*
X364755Y394000D03*
Y389500D03*
X378475Y403780D03*
X378505Y408500D03*
Y417500D03*
Y413000D03*
Y426500D03*
Y422000D03*
Y431000D03*
Y435500D03*
X380223Y387783D03*
X405700Y880500D03*
X424700Y268000D03*
X426455Y287200D03*
Y275200D03*
X442240Y106000D03*
Y110000D03*
X435240Y117500D03*
X442200Y244000D03*
X449700Y106000D03*
Y110000D03*
Y114500D03*
X461200Y277500D03*
Y273000D03*
X466129Y165500D03*
Y172500D03*
Y180500D03*
X465700Y197000D03*
X465629Y189500D03*
X465700Y286500D03*
X463200Y282000D03*
X472755Y293800D03*
X600200Y209500D03*
Y223000D03*
Y227500D03*
X639200Y453000D03*
X631700Y579000D03*
Y588500D03*
Y584000D03*
X631200Y606900D03*
Y612900D03*
X656164Y432538D03*
X648200Y444500D03*
X651700Y448500D03*
X677366Y94544D03*
X707700Y63500D03*
X694416Y137784D03*
X702200Y863500D03*
X713200Y576500D03*
Y582000D03*
Y572000D03*
X726232Y100532D03*
X734948Y189500D03*
X728200Y455500D03*
X739664Y558538D03*
Y563538D03*
X736168Y768784D03*
Y763984D03*
X729168Y806284D03*
Y801984D03*
X727700Y864000D03*
X757200Y82500D03*
Y88500D03*
Y94500D03*
Y99500D03*
X753164Y471538D03*
X741200Y553500D03*
X755700Y571000D03*
Y575500D03*
X743668Y768784D03*
X762200Y51500D03*
Y55500D03*
Y59500D03*
Y63500D03*
X766200Y138500D03*
Y134000D03*
X766100Y144300D03*
X779200Y649000D03*
X779700Y668000D03*
X800200Y471000D03*
X799200Y546500D03*
Y553500D03*
Y561000D03*
X805200Y851000D03*
X838700Y858000D03*
X824700Y873000D03*
X869200Y467500D03*
X860200Y711000D03*
X876200Y101500D03*
X873200Y414000D03*
Y404500D03*
X877200Y467500D03*
X920700Y70500D03*
X912200D03*
X986974Y204578D03*
Y209578D03*
Y214578D03*
X997700Y496500D03*
X1033200Y133000D03*
X1031474Y214078D03*
X1028416Y866968D03*
X1041200Y119500D03*
Y128500D03*
X1049200Y713000D03*
X1066168Y227284D03*
X1063668Y223284D03*
X1067700Y733500D03*
Y741500D03*
X1078668Y200784D03*
X1102700Y428000D03*
X1129200Y278000D03*
X1133200Y618000D03*
X1142200Y274500D03*
X1141200Y618000D03*
X1143168Y858284D03*
X1195877Y238000D03*
X1184700Y237000D03*
X1195877Y242500D03*
X1184700Y244000D03*
X1195877Y247500D03*
X1184700Y248000D03*
X1195877Y252500D03*
X1195868Y264060D03*
Y268560D03*
X1189700Y359000D03*
Y363500D03*
X1192200Y875500D03*
X1217200Y444000D03*
X1216670Y568510D03*
X1203700Y605500D03*
X1217984Y432532D03*
X1225700Y718500D03*
X1218200Y735500D03*
Y731000D03*
X1225700Y735500D03*
Y731000D03*
X1225200Y831500D03*
X1247700Y268500D03*
Y272500D03*
X1243700Y593000D03*
Y598000D03*
X1249200Y661000D03*
X1247700Y762000D03*
X1257188Y221500D03*
Y226000D03*
Y230500D03*
X1250877Y241500D03*
Y245500D03*
X1251700Y431500D03*
Y427500D03*
X1253700Y643000D03*
Y647000D03*
Y639000D03*
Y635000D03*
Y651000D03*
Y657000D03*
X1261200Y661000D03*
Y657000D03*
Y651000D03*
X1253700Y667000D03*
X1261200Y667500D03*
X1253700Y680000D03*
Y688000D03*
Y707500D03*
Y703500D03*
Y711500D03*
X1262700Y783000D03*
X1265300Y835100D03*
X1330700Y298000D03*
Y293000D03*
X1316317Y586412D03*
Y595412D03*
Y612412D03*
Y599912D03*
X1347317Y567412D03*
X1342317Y619412D03*
X1362200Y106000D03*
X1357700Y456000D03*
X1373317Y589912D03*
Y585412D03*
Y597912D03*
Y602412D03*
Y611412D03*
Y606912D03*
G54D148*
X1077000Y238000D03*
Y260000D03*
G54D91*
X326385Y218372D03*
X328585D03*
X326385Y221872D03*
X328585D03*
X404829Y241900D03*
X407029D03*
X404829Y245400D03*
X407029D03*
X519423Y324783D03*
X521623D03*
X519423Y327283D03*
X521623D03*
X525423Y330283D03*
Y332783D03*
X514923Y332283D03*
X517123D03*
X514923Y334783D03*
X517123D03*
X515900Y343500D03*
X518100D03*
X515900Y346000D03*
X518100D03*
X515900Y348500D03*
X518100D03*
X515900Y351000D03*
X518100D03*
X515900Y353500D03*
X518100D03*
X515900Y356000D03*
X518100D03*
X515900Y359500D03*
X518100D03*
X515900Y362000D03*
X518100D03*
X527623Y330283D03*
Y332783D03*
G54D185*
G01X61362Y669714D02*
Y664278D01*
X60304Y663220D01*
G01X59787Y669714D02*
X55310D01*
X55304Y669720D01*
G01X61362Y696000D02*
Y697162D01*
X58804Y699720D01*
G01X61362Y691914D02*
Y696000D01*
G01X59787Y691914D02*
Y695287D01*
X60500Y696000D01*
X61362D01*
G01X62937Y691914D02*
Y697353D01*
X64304Y698720D01*
G01X77107Y669714D02*
Y663023D01*
X76804Y662720D01*
G01X75532Y669714D02*
Y663992D01*
X76804Y662720D01*
G01X77107Y691914D02*
Y696417D01*
X73804Y699720D01*
G01X96162Y669714D02*
Y664578D01*
X95304Y663720D01*
G01X94587Y669714D02*
X89810D01*
X89804Y669720D01*
G01X96162Y691914D02*
Y687078D01*
X95304Y686220D01*
G01X94587Y691914D02*
Y686937D01*
X95304Y686220D01*
G01X97737Y691914D02*
Y698653D01*
G01X111907Y669714D02*
Y664323D01*
X111304Y663720D01*
G01X110332Y669714D02*
Y664692D01*
X111304Y663720D01*
G01X111907Y691914D02*
Y698617D01*
G01X234614Y891272D02*
Y895386D01*
X231500Y898500D01*
G01X324555Y510250D02*
Y512220D01*
X323395Y513380D01*
Y517900D01*
G01X328555Y510250D02*
Y510960D01*
X324970Y514545D01*
Y517900D01*
G01X321023Y548533D02*
X323395Y546161D01*
Y540100D01*
G01X325023Y548533D02*
X324970Y548480D01*
Y540100D01*
G01X326545D02*
Y535390D01*
X325775Y534620D01*
X321675D01*
X321555Y534500D01*
G01X339140Y517900D02*
Y512500D01*
G01X340715Y517900D02*
Y514075D01*
X339140Y512500D01*
G01X349313Y517994D02*
Y521092D01*
X348511Y521894D01*
X346965D01*
X343555Y518484D01*
Y517000D01*
G01X340715Y540100D02*
Y545840D01*
G01X347023Y509533D02*
X347738Y510248D01*
Y517994D01*
G01Y540194D02*
Y546175D01*
X347213Y546700D01*
G01X349313Y540194D02*
Y545392D01*
X348005Y546700D01*
X347213D01*
G01X350888Y540194D02*
Y545953D01*
X351815Y546880D01*
G01X363583Y134645D02*
Y133759D01*
X365183Y132159D01*
Y130833D01*
X365133Y130783D01*
Y129133D01*
G01X365058Y517994D02*
Y513003D01*
X364055Y512000D01*
G01X363483Y517994D02*
Y512572D01*
X364055Y512000D01*
G01X365058Y540194D02*
Y543003D01*
X367555Y545500D01*
G01X388780Y188189D02*
Y188649D01*
X387280Y190149D01*
Y192859D01*
X387209Y192930D01*
G01X410827Y140945D02*
X409310Y142462D01*
Y144950D01*
X408543Y145717D01*
X406167D01*
X406110Y145660D01*
G01X410827Y213385D02*
X412442Y215000D01*
X415511D01*
X417126Y213385D01*
G01X439173Y140945D02*
X437628Y139400D01*
X434419D01*
X432874Y140945D01*
G01X496155Y321700D02*
X495455Y322400D01*
Y326198D01*
X493504Y328149D01*
G01X489567Y351771D02*
X489771D01*
X491500Y353500D01*
G01X489567Y367519D02*
X489074D01*
X487555Y366000D01*
Y361611D01*
X487643Y361523D01*
G01X1138320Y710066D02*
Y711581D01*
X1137145Y712756D01*
G01X1253100Y445000D02*
X1259252D01*
G01D02*
X1259968Y444284D01*
G01X1339047Y430394D02*
Y426047D01*
G01X1341016Y430444D02*
Y426016D01*
G01X1342984Y430444D02*
Y426016D01*
G54D176*
G01X65197Y729959D02*
Y735079D01*
X64272Y736004D01*
G01X75432Y758844D02*
Y752049D01*
G01X70013Y853207D02*
Y849205D01*
X70248Y848970D01*
Y847987D01*
X70909Y847325D01*
G01X72770Y901388D02*
Y906488D01*
G01X106654Y798720D02*
X100804D01*
X99804Y799720D01*
G01X99054Y882720D02*
X98163Y881829D01*
Y875297D01*
G01X103304Y928220D02*
X104054Y927470D01*
Y922020D01*
G01X122954Y798720D02*
X129304D01*
G01X129600Y844280D02*
X123720D01*
X122500Y845500D01*
G01X131554Y901420D02*
Y895470D01*
X132804Y894220D01*
G01X162992Y303465D02*
Y297106D01*
X162595Y296709D01*
G01X161417Y313347D02*
Y319209D01*
X159917Y320709D01*
X159774D01*
G01X160000Y465500D02*
Y466000D01*
X163315Y469315D01*
X166700D01*
G01X172441Y303465D02*
Y297120D01*
X172285Y296964D01*
G01X181889Y303465D02*
Y297303D01*
G01X180315Y313347D02*
Y321209D01*
G01X170866Y313347D02*
Y320280D01*
X171295Y320709D01*
G01X175900Y469315D02*
X179285D01*
X182800Y465800D01*
G01X175900Y471285D02*
X182785D01*
X182800Y471300D01*
G01X181055Y565050D02*
Y561000D01*
X180555Y560500D01*
G01X197637Y303465D02*
Y296963D01*
X197245Y296571D01*
G01X196063Y313347D02*
Y319209D01*
G01X201805Y527440D02*
X196495D01*
X195555Y526500D01*
X189385D01*
X189355Y526470D01*
G01X201805Y539940D02*
X196535D01*
X195725Y540750D01*
G01X207086Y303465D02*
Y297418D01*
G01X205511Y313347D02*
Y320709D01*
G01X214960Y313347D02*
Y321044D01*
G01X208305Y532560D02*
Y536320D01*
G01Y545060D02*
Y548670D01*
G01Y558060D02*
Y562640D01*
G01X205250Y864750D02*
X207250D01*
X208579Y863421D01*
X212250D01*
G01X219047Y868250D02*
Y874000D01*
X218500Y874547D01*
G01X216535Y303465D02*
Y297469D01*
X217295Y296709D01*
G01X239000Y853000D02*
X234484Y857516D01*
X231750D01*
G01X236500Y866000D02*
Y865000D01*
X234921Y863421D01*
X231750D01*
G01Y861453D02*
X237953D01*
G01X243750Y851500D02*
X240500D01*
X239000Y853000D01*
G01X317514Y76258D02*
X315242D01*
X314500Y77000D01*
X314498D01*
X313198Y78300D01*
X309700D01*
X309500Y78500D01*
G01X301329Y336000D02*
X297929D01*
G01X301329Y332000D02*
X297929D01*
G01X298373Y497608D02*
X306063D01*
X306155Y497700D01*
G01X298373Y505483D02*
X304572D01*
X305155Y504900D01*
G01X305555Y525200D02*
X305523Y525168D01*
X298373D01*
G01Y542883D02*
X304972D01*
X305255Y542600D01*
G01X334330Y78227D02*
X332227D01*
X331500Y77500D01*
X322500D01*
X321258Y76258D01*
X317514D01*
G01X321773Y483783D02*
X321890Y483900D01*
X325855D01*
X327692Y482063D01*
X331123D01*
G01X334330Y74290D02*
X336710D01*
X337900Y73100D01*
G01X341000Y97750D02*
Y98000D01*
X337500Y101500D01*
Y102000D01*
G01X343005Y449840D02*
X344423Y451258D01*
Y454943D01*
G01X343005Y449840D02*
Y446290D01*
X343095Y446200D01*
G01X339505Y449840D02*
Y456710D01*
X340355Y457560D01*
X344366D01*
X344423Y457503D01*
G01X331123Y484623D02*
X336562D01*
X338595Y482590D01*
G01X360433Y131496D02*
Y134645D01*
G01X363583Y131496D02*
X360433D01*
G01X357394D02*
X360433D01*
G01X357284Y134645D02*
X355085D01*
X353740Y133300D01*
G01X363583Y144094D02*
X362009Y142520D01*
G01X363583Y140945D02*
Y140946D01*
X362009Y142520D01*
G01X363583Y150393D02*
X362009Y148819D01*
G01X363583Y147244D02*
Y147245D01*
X362009Y148819D01*
G01X360433Y153543D02*
X362009Y155119D01*
G01X363583Y156693D02*
X362009Y155119D01*
G01X363583Y153543D02*
Y153545D01*
X362009Y155119D01*
G01X363583Y159842D02*
Y159857D01*
X362034Y161406D01*
G01X363583Y162992D02*
X362040Y161449D01*
Y161412D01*
X362034Y161406D01*
G01X360433Y162992D02*
X360448D01*
X362034Y161406D01*
G01X357284Y162992D02*
X352721D01*
X351929Y162200D01*
G01X357284Y185039D02*
X355531D01*
X353085Y187485D01*
G01X357284Y178740D02*
X356300D01*
X355040Y180000D01*
G01X360433Y178740D02*
X360075D01*
X359687Y179128D01*
X358029D01*
X357641Y178740D01*
X357284D01*
G01Y172441D02*
X355084D01*
G01X357284Y200787D02*
X356327D01*
X354540Y199000D01*
G01X369882Y134645D02*
X369881D01*
X368307Y133071D01*
G01X373032Y134645D02*
Y134647D01*
X374606Y136221D01*
G01X373032Y137795D02*
X374606Y136221D01*
G01X379331Y137795D02*
X380906Y136220D01*
G01X376181Y137795D02*
X376180D01*
X374606Y136221D01*
G01X366733Y134645D02*
X368307Y133071D01*
G01X363583Y137795D02*
X366733Y134645D01*
G01X373032Y131496D02*
Y131508D01*
X371482Y133058D01*
G01X373032Y140945D02*
Y140946D01*
X371458Y142520D01*
G01X373032Y144094D02*
X371458Y142520D01*
G01X369882Y144094D02*
X369884D01*
X371458Y142520D01*
G01X379331Y147244D02*
X377757Y145670D01*
G01X363583Y175590D02*
X363601D01*
X365186Y177175D01*
G01X366733Y185039D02*
Y185017D01*
X368290Y183460D01*
X368320D01*
G01X363583Y178740D02*
X363867D01*
X365186Y177421D01*
Y177175D01*
G01X369882Y191338D02*
X368340Y192880D01*
Y192900D01*
X368336Y192904D01*
G01X366733Y194488D02*
X366752D01*
X368336Y192904D01*
G01X368750Y921700D02*
X371200D01*
X371938Y922438D01*
G01X380906Y136220D02*
X382481Y134645D01*
G01X391929D02*
Y134646D01*
X390354Y136221D01*
G01X391929Y137795D02*
X391928D01*
X390354Y136221D01*
G01X382481Y137795D02*
X380906Y136220D01*
G01X385630Y137795D02*
X385272D01*
X384848Y137371D01*
X383190D01*
X382766Y137795D01*
X382481D01*
G01X388780D02*
X388421D01*
X388002Y137376D01*
X386344D01*
X385925Y137795D01*
X385630D01*
G01X390354Y136221D02*
X388780Y137795D01*
G01X391929Y140945D02*
X390355Y139371D01*
G01X382481Y140945D02*
Y140931D01*
X380920Y139370D01*
G01X391929Y131496D02*
Y129311D01*
X392240Y129000D01*
G01X382481Y131496D02*
Y130229D01*
X383680Y129030D01*
G01X395079Y147244D02*
X393505Y145670D01*
G01X388780Y147244D02*
X387206Y145670D01*
G01X385630Y147244D02*
X384056Y145670D01*
G01X391929Y147244D02*
X390355Y145670D01*
G01X385630Y172441D02*
Y172420D01*
X384110Y170900D01*
X384053D01*
X384041Y170888D01*
G01X395079Y194488D02*
Y194460D01*
X393519Y192900D01*
G01X388429Y247550D02*
Y240571D01*
X390500Y238500D01*
X391000D01*
G01X410827Y134645D02*
X407677Y137795D01*
G01X412429Y136210D02*
X412392D01*
X410827Y134645D01*
G01Y137795D02*
X410835Y137787D01*
X410852D01*
X412429Y136210D01*
G01X401378Y134645D02*
X401395D01*
X402950Y133090D01*
Y133050D01*
G01X404528Y137795D02*
X401378Y134645D01*
G01Y137795D02*
X401341D01*
X399783Y136237D01*
G01X410827Y131496D02*
Y131213D01*
X413540Y128500D01*
G01X401378Y131496D02*
Y130602D01*
X402800Y129180D01*
G01X413977Y144094D02*
X412403Y142520D01*
G01D02*
X410829Y144094D01*
X410827D01*
G01X404528Y147244D02*
X402954Y145670D01*
G01X398229Y147244D02*
X396655Y145670D01*
G01X407029Y245400D02*
X409929D01*
G01X407029Y241900D02*
Y242500D01*
X409929Y245400D01*
G01X420276Y144094D02*
X418702Y142520D01*
G01X426575Y144094D02*
X425001Y142520D01*
G01X418702D02*
X417127Y140945D01*
X417126D01*
G01X425001Y142520D02*
X423426Y140945D01*
X423425D01*
G01X420276D02*
X421851Y142520D01*
G01X423425Y144094D02*
X421851Y142520D01*
G01X413977Y140945D02*
X415552Y142520D01*
G01X417126Y144094D02*
X415552Y142520D01*
G01X426575Y140945D02*
X426576D01*
X428151Y142520D01*
G01X429725Y144094D02*
X428151Y142520D01*
G01X414763Y375394D02*
X412794Y377363D01*
G01X430511Y410827D02*
X428523Y412815D01*
Y416683D01*
G01X426574Y422638D02*
Y428481D01*
X423555Y431500D01*
G01X435290Y117500D02*
X435929D01*
X436104Y117325D01*
X438789D01*
X438964Y117500D01*
X447000D01*
X447500Y118000D01*
X450929D01*
G01X432874Y144094D02*
X431300Y142520D01*
G01X429725Y140945D02*
X431300Y142520D01*
G01X439173Y144094D02*
X437599Y142520D01*
G01X436024Y140945D02*
X437599Y142520D01*
G01X432874Y140945D02*
X432875D01*
X434450Y142520D01*
G01X436024Y144094D02*
X434450Y142520D01*
G01X440000Y239750D02*
Y240000D01*
X442250Y242250D01*
Y244000D01*
G01D02*
X442000Y244250D01*
Y244322D01*
X438500Y247822D01*
Y250000D01*
G01X433750Y268500D02*
Y276045D01*
X433765Y276060D01*
G01X439800Y284100D02*
X440055Y283845D01*
Y278555D01*
X437560Y276060D01*
X433765D01*
G01X449945Y283740D02*
X444295D01*
X444255Y283700D01*
G01X438385Y339960D02*
X440353Y341928D01*
G01X442322Y343897D02*
X440353Y341928D01*
G01X446259Y410827D02*
X444323Y412763D01*
Y416883D01*
G01X438385Y410827D02*
X436485Y412727D01*
Y416645D01*
X436523Y416683D01*
G01X442322Y422638D02*
Y426557D01*
X442535Y426770D01*
G01X434448Y422638D02*
Y426008D01*
X434723Y426283D01*
G01X462250Y185000D02*
X458429D01*
G01X458071Y351771D02*
X460040Y349802D01*
G01X462008Y351771D02*
Y351770D01*
X460040Y349802D01*
G01X454134Y351771D02*
X454133D01*
X450196Y355708D01*
G01X458071Y422638D02*
Y425096D01*
X458685Y425710D01*
G01X450196Y422638D02*
Y424931D01*
X450725Y425460D01*
G01X473819Y339960D02*
Y338993D01*
X473951Y338861D01*
Y337121D01*
X473819Y336989D01*
Y336023D01*
G01X469882Y332086D02*
Y331119D01*
X470014Y330987D01*
Y329247D01*
X469882Y329115D01*
Y328149D01*
G01X475788Y341928D02*
X473820Y339960D01*
X473819D01*
G01X465945Y343897D02*
X467053D01*
X467085Y343865D01*
X468743D01*
X468775Y343897D01*
X469882D01*
G01X473819D02*
X469882D01*
G01Y347834D02*
Y346726D01*
X469914Y346694D01*
Y345036D01*
X469882Y345004D01*
Y343897D01*
G01X465945Y422638D02*
Y424630D01*
X466655Y425340D01*
G01X493504Y328149D02*
X489567Y332086D01*
G01X493504Y414764D02*
X495473Y416733D01*
G01X493504Y418701D02*
X495473Y420670D01*
G01X493504Y422638D02*
X495473Y424607D01*
G01X511500Y348000D02*
X506755D01*
X506589Y347834D01*
X501378D01*
G01X497441Y414764D02*
X499410Y416733D01*
G01X501378Y418701D02*
X503347Y420670D01*
G01X497441Y422638D02*
X499410Y424607D01*
G01X497441Y418701D02*
X499410Y420670D01*
G01X558495Y339988D02*
X560067D01*
X563555Y336500D01*
Y333000D01*
G01X550815Y356168D02*
X547500Y359483D01*
Y360168D01*
G01X563805Y328500D02*
Y331195D01*
X563555Y331445D01*
Y333000D01*
G01X652674Y577738D02*
X648490D01*
X647252Y576500D01*
G01X652674Y580298D02*
X657702D01*
X680000Y558000D01*
X711028D01*
X730000Y539028D01*
Y536500D01*
G01X669025Y446821D02*
Y441725D01*
G01Y466107D02*
Y470525D01*
X669462Y470962D01*
Y472500D01*
G01X670993Y466107D02*
Y468993D01*
X673000Y471000D01*
Y474426D01*
X673010Y474436D01*
G01X682805Y446821D02*
Y444195D01*
X686500Y440500D01*
X687500D01*
G01X708216Y118331D02*
X701949D01*
G01X708216Y128174D02*
X703204D01*
X701828Y129550D01*
G01X708216Y126205D02*
X699043D01*
X697248Y128000D01*
G01X708216Y130142D02*
X705126D01*
X703738Y131530D01*
Y132883D01*
X703053Y133568D01*
G01X698818Y764644D02*
Y761634D01*
G01X696818Y800144D02*
X703328D01*
G01X715118Y772324D02*
Y776134D01*
G01X713118Y807824D02*
X714508D01*
X717468Y810784D01*
G01X726282Y100532D02*
X728606Y102856D01*
Y107784D01*
G01X746716Y123034D02*
X743982Y120300D01*
X735216D01*
G01X730574Y134784D02*
Y138326D01*
X732248Y140000D01*
G01X726637Y134784D02*
Y140889D01*
X727248Y141500D01*
G01X733000Y193000D02*
X733500Y193500D01*
Y196965D01*
G01X747000Y210000D02*
X735300D01*
X733500Y208200D01*
Y205035D01*
G01X730060Y464572D02*
X735928D01*
X736000Y464500D01*
G01X747800Y56165D02*
Y50200D01*
G01X749300Y67500D02*
X747800Y66000D01*
Y63840D01*
G01X745400Y881325D02*
Y877600D01*
G01X774938Y685354D02*
X770646D01*
G01X767600Y896675D02*
X783675D01*
X784000Y897000D01*
G01X789727Y444972D02*
Y444273D01*
X791500Y442500D01*
G01X787758Y457134D02*
Y464000D01*
X784000Y467758D01*
G01X780058Y692754D02*
X783746D01*
G01X792880Y448125D02*
X798875D01*
G01X792830Y450094D02*
X799406D01*
G01X792830Y452062D02*
X794867D01*
X797750Y454945D01*
Y455750D01*
G01X841656Y391835D02*
X830335D01*
G01X837031Y396460D02*
X830540D01*
G01X837031Y401578D02*
X829578D01*
G01X837031Y399019D02*
X830519D01*
G01X837031Y404137D02*
X832637D01*
X832500Y404000D01*
G01X851892Y385858D02*
X852750Y385000D01*
G01X851892Y391835D02*
Y385858D01*
G01X858800Y639500D02*
X855000D01*
X854000Y640500D01*
G01X856517Y401578D02*
X862922D01*
G01X861960Y396460D02*
X856517D01*
G01X861981Y399019D02*
X856517D01*
G01X862000Y396500D02*
X861960Y396460D01*
G01X862000Y399000D02*
X861981Y399019D01*
G01X866200Y636940D02*
X871060D01*
X872000Y636000D01*
G01X866200Y639500D02*
X871000D01*
G01X865250Y665060D02*
X870500D01*
G01X932250Y62060D02*
X936060D01*
X937000Y63000D01*
G01X950850Y449715D02*
X942215D01*
X941200Y448700D01*
G01X960050Y449715D02*
X965735D01*
X968085Y452065D01*
G01X965600Y455790D02*
Y453460D01*
X963825Y451685D01*
X960050D01*
G01X1003750Y464440D02*
X1000940D01*
X998000Y461500D01*
G01X1010250Y469560D02*
Y473400D01*
G01X1007500Y487500D02*
Y485500D01*
X1007750Y485250D01*
Y480500D01*
G01X1045031Y145641D02*
Y138031D01*
G01Y164927D02*
Y172047D01*
X1045968Y172984D01*
G01X1046999Y164927D02*
Y168499D01*
X1048000Y169500D01*
X1053200D01*
X1056700Y173000D01*
G01X1077750Y661500D02*
X1077233Y661262D01*
X1076471Y660500D01*
X1074000D01*
G01X1110318Y265814D02*
X1103814D01*
X1102500Y264500D01*
G01X1149992Y772186D02*
X1150030D01*
X1151592Y773748D01*
G01X1140544Y794233D02*
Y794254D01*
X1142120Y795830D01*
G01X1146843Y794233D02*
Y794257D01*
X1145270Y795830D01*
G01X1153142Y772186D02*
Y772198D01*
X1151592Y773748D01*
G01X1173000Y390250D02*
X1173160Y390090D01*
X1182660D01*
G01X1171791Y697008D02*
Y696971D01*
X1173365Y695397D01*
G01X1171791Y681260D02*
X1170740D01*
X1169800Y682200D01*
G01X1171791Y693859D02*
X1171827D01*
X1173365Y695397D01*
G01X1171791Y684410D02*
X1169801Y682420D01*
Y682201D01*
X1169800Y682200D01*
G01X1181070Y777000D02*
X1177070Y773000D01*
X1171225D01*
X1168890Y775335D01*
G01Y797382D02*
X1169528D01*
X1170950Y795960D01*
G01X1190340Y373910D02*
X1195590D01*
X1197000Y372500D01*
G01X1233050Y772547D02*
X1228547D01*
G01X1233050Y778453D02*
X1228547D01*
G01X1236079Y768500D02*
X1231000D01*
G01X1236079Y782500D02*
X1233000D01*
G01X1235540Y840850D02*
X1230650D01*
X1230500Y841000D01*
G01X1245921Y768500D02*
X1247950D01*
X1248950Y769500D01*
G01D02*
Y772547D01*
G01X1245921Y782500D02*
X1248900D01*
X1248950Y782450D01*
G01X1242100Y825350D02*
X1240660Y826790D01*
Y829000D01*
G01X1250600Y835350D02*
X1249600Y834350D01*
X1240660D01*
G01D02*
Y829000D01*
G01X1265531Y434641D02*
Y427031D01*
X1265000Y426500D01*
G01X1265531Y453927D02*
Y459469D01*
X1263968Y461032D01*
Y463032D01*
G01X1263700Y467200D02*
Y463300D01*
X1263968Y463032D01*
G01X1267499Y453927D02*
Y464815D01*
X1268468Y465784D01*
G01X1288818Y645784D02*
X1283284D01*
X1282500Y645000D01*
G01X1288318Y677284D02*
X1282716D01*
X1282276Y677724D01*
Y677976D01*
X1282300Y678000D01*
G01X1305118Y645784D02*
X1312000D01*
G01X1304618Y677284D02*
X1311000D01*
G01X1308250Y864000D02*
X1307113Y865137D01*
Y870464D01*
X1307468Y870819D01*
Y874634D01*
G01Y890934D02*
Y884532D01*
G01X1333317Y593412D02*
X1327617D01*
X1326617Y594412D01*
G01X1329468Y643634D02*
Y647532D01*
X1328000Y649000D01*
G01X1329468Y659934D02*
Y666468D01*
G01X1344953Y430394D02*
Y430047D01*
X1347000Y428000D01*
G01X1348056Y437484D02*
X1352784D01*
X1354000Y438700D01*
G01X1344500Y450500D02*
Y451000D01*
X1342984Y452516D01*
Y454484D01*
X1343000Y454500D01*
Y456000D01*
G01X1342984Y442556D02*
Y446984D01*
X1344500Y448500D01*
Y450500D01*
G01X1338711Y582112D02*
Y579711D01*
X1338443Y579443D01*
Y579156D01*
X1337799Y578512D01*
X1337512D01*
X1335317Y576317D01*
Y575412D01*
G01X1342648Y604712D02*
Y612412D01*
G01X1352491Y581762D02*
X1354067D01*
X1356817Y579012D01*
G01X1355917Y593412D02*
X1364117D01*
X1364617Y592912D01*
G01X1352491Y605062D02*
Y605786D01*
X1356117Y609412D01*
G01X1350523Y604712D02*
Y607818D01*
X1353117Y610412D01*
G54D56*
X181055Y569500D03*
X388429Y252000D03*
G54D47*
X146364Y290190D03*
X135364D03*
X305100Y36200D03*
Y27500D03*
Y44800D03*
X316100Y36200D03*
Y27500D03*
Y44800D03*
X829500Y452500D03*
X840500D03*
X869000Y379500D03*
X880000D03*
X1038000Y80500D03*
Y89500D03*
Y98500D03*
X1049000Y80500D03*
Y89500D03*
Y98500D03*
X1054000Y923500D03*
X1043000D03*
X1283500Y371000D03*
Y380000D03*
X1294500Y371000D03*
Y380000D03*
X1313000Y371000D03*
X1302000D03*
X1313000Y380000D03*
X1302000D03*
X1362000Y371500D03*
Y362500D03*
X1373000Y371500D03*
Y362500D03*
G54D92*
X339500Y35400D03*
Y57600D03*
G54D74*
X244000Y894000D03*
X249000D03*
X254000D03*
X259000D03*
X1050000Y260000D03*
X1045000D03*
X1060000D03*
X1055000D03*
G54D65*
X211950Y851610D03*
Y865390D03*
X232050Y851610D03*
Y865390D03*
G54D167*
X1332967Y585538D03*
Y601286D03*
X1356267Y585538D03*
Y601286D03*
G54D29*
X39804Y931420D03*
X97500Y931200D03*
X153200Y660600D03*
X179000Y851700D03*
X180000Y906200D03*
X190000D03*
X185000D03*
X212500Y790700D03*
X343000Y67700D03*
X520000Y146200D03*
X687968Y760184D03*
X727968Y758184D03*
X793500Y727700D03*
X809000Y338200D03*
X810000Y474200D03*
X904500Y76200D03*
X1065500Y158700D03*
X1056700Y173200D03*
X1107968Y250984D03*
X1268468Y465984D03*
X1287000Y447200D03*
X1360000Y423700D03*
X1357500Y460700D03*
G54D83*
X305750Y81500D03*
X820524Y465078D03*
X1030250Y155000D03*
X1252250Y445000D03*
G54D149*
X1081260Y418200D03*
X1085000Y426800D03*
X1088740Y418200D03*
G54D38*
X97804Y803820D03*
X458000Y286500D03*
X547555Y364500D03*
X1197000Y366000D03*
X1219968Y790784D03*
X1312468Y902784D03*
G54D158*
X1241000Y775500D03*
G54D186*
G01X23054Y840720D02*
Y834946D01*
X25780Y832220D01*
X35304D01*
G01X25500Y836000D02*
Y838970D01*
X26554Y840024D01*
Y840720D01*
G01D02*
Y845220D01*
G01X40054Y837095D02*
X37679Y834720D01*
X32304D01*
G01X26554Y845220D02*
Y849720D01*
G01Y845220D02*
X28554Y847220D01*
X33554D01*
G01X26550Y854200D02*
X27350Y855000D01*
X30500D01*
G01X33554Y849780D02*
Y851946D01*
X30500Y855000D01*
G01X37232Y877242D02*
X32282D01*
X28790Y880734D01*
G01X25304Y890470D02*
Y884220D01*
X28790Y880734D01*
G01X29804Y890470D02*
Y885970D01*
X30054Y885720D01*
G01D02*
X34659Y881115D01*
X37211D01*
G01X33554Y885720D02*
X36622D01*
X37372Y884970D01*
X37462D01*
X37758Y884674D01*
G01X34304Y890470D02*
X35054D01*
X38304Y887220D01*
X40304D01*
G01X25304Y899220D02*
Y893970D01*
G01X110234Y1008860D02*
Y984234D01*
X83800Y957800D01*
X47659D01*
X25304Y935445D01*
Y899220D01*
G01X115500Y983500D02*
Y983419D01*
X86581Y954500D01*
X49027D01*
X33829Y939302D01*
Y909798D01*
X34304Y909323D01*
Y897720D01*
G01D02*
Y893970D01*
G01X29804Y904220D02*
Y893970D01*
G01X111000Y981500D02*
X85650Y956150D01*
X48343D01*
X29804Y937611D01*
Y904220D01*
G01X124500Y515500D02*
X112000Y528000D01*
Y590500D01*
X50000Y652500D01*
Y659500D01*
G01X44804Y837220D02*
Y835470D01*
X47054Y833220D01*
X47554D01*
G01X48054Y842720D02*
Y833720D01*
X47554Y833220D01*
G01X40054Y844660D02*
Y837095D01*
G01X38804Y893970D02*
X39054Y893720D01*
X43658D01*
X46679Y890699D01*
Y863821D01*
X49000Y861500D01*
G01X47770Y901388D02*
Y893254D01*
X51043Y889981D01*
G01X42000Y884000D02*
Y885524D01*
X40304Y887220D01*
G01X56304Y888720D02*
X50304Y894720D01*
Y901354D01*
X50270Y901388D01*
G01D02*
Y904254D01*
X47804Y906720D01*
G01X43804Y907720D02*
X47770Y903754D01*
Y901388D01*
G01X38804Y898470D02*
Y893970D01*
G01Y898470D02*
X38554D01*
X36054Y900970D01*
Y910720D01*
G01X50270Y929186D02*
Y921988D01*
G01X145669Y1008860D02*
Y998508D01*
X147177Y997000D01*
Y988607D01*
X131570Y973000D01*
X122500D01*
X83000Y933500D01*
Y915500D01*
X77500Y910000D01*
X59898D01*
X50270Y919628D01*
Y921988D01*
G01X47770D02*
Y932436D01*
X47804Y932470D01*
G01X118000Y991500D02*
Y983277D01*
X86723Y952000D01*
X48861D01*
X36054Y939193D01*
Y910720D01*
G01X47804Y935970D02*
Y938220D01*
X52804Y943220D01*
G01X47804Y932470D02*
X52804Y937470D01*
Y938795D01*
G01X135500Y511000D02*
X114500Y532000D01*
Y591500D01*
X52000Y654000D01*
Y655500D01*
G01X62937Y669714D02*
Y649063D01*
X69500Y642500D01*
G01X66087Y669714D02*
Y652413D01*
X74500Y644000D01*
G01X66860Y648370D02*
X75500Y639730D01*
Y637950D01*
X123550Y589899D01*
Y588399D01*
X124000Y587949D01*
Y584050D01*
X125050Y583000D01*
G01X64512Y669714D02*
Y650718D01*
X66860Y648370D01*
G01X66087Y691914D02*
Y685383D01*
X71981Y679489D01*
X81414D01*
X88227Y686302D01*
Y729959D01*
G01X64512Y691914D02*
Y684907D01*
X71380Y678039D01*
X82981D01*
X90787Y685845D01*
Y729959D01*
G01X75532Y691914D02*
Y688961D01*
X76304Y688189D01*
X77808D01*
X79232Y689613D01*
Y698916D01*
X67304Y710844D01*
Y715720D01*
G01D02*
X66222Y716802D01*
Y724954D01*
X67757Y726489D01*
Y729959D01*
G01X58804Y717970D02*
X63304D01*
G01X62637Y729959D02*
Y722887D01*
X62804Y722720D01*
G01X63304Y717970D02*
X62804Y718470D01*
Y722720D01*
G01X67757Y729959D02*
Y736767D01*
X64904Y739620D01*
X62704D01*
G01X55304Y742720D02*
Y746220D01*
G01X110332Y691914D02*
X110304Y691886D01*
Y689091D01*
X111206Y688189D01*
X112608D01*
X114032Y689613D01*
Y716559D01*
X100953Y729638D01*
Y729639D01*
X92772Y737820D01*
X76704D01*
X65197Y749327D01*
Y752049D01*
G01D02*
X65272Y752124D01*
Y758504D01*
G01X64683Y762056D02*
X64772D01*
X67757Y759071D01*
Y752049D01*
G01X55304Y746220D02*
Y750470D01*
G01D02*
X58804D01*
X60383Y752049D01*
X62637D01*
G01X58772Y797754D02*
X57772Y798754D01*
Y801504D01*
G01X58932Y808104D02*
Y805004D01*
X57772Y803844D01*
Y801504D01*
G01X63272Y797754D02*
Y799504D01*
X61492Y801284D01*
Y803004D01*
G01D02*
Y808104D01*
G01X64052D02*
Y803004D01*
X64552Y802504D01*
X66272D01*
X66612Y802844D01*
G01D02*
Y808104D01*
G01X67772Y797754D02*
X66612Y798914D01*
Y802844D01*
G01X58932Y820904D02*
Y817348D01*
X57304Y815720D01*
G01X58554Y830720D02*
X58522Y830688D01*
Y825504D01*
X58932Y825094D01*
Y820904D01*
G01X61492D02*
Y815408D01*
X61304Y815220D01*
G01X61492Y820904D02*
Y829658D01*
X62554Y830720D01*
G01X57804Y834720D02*
X58554Y833970D01*
Y830720D01*
G01X62554D02*
X62522Y830752D01*
Y834002D01*
X61804Y834720D01*
G01X60804Y843720D02*
X61054Y843470D01*
X65804D01*
G01D02*
X69804D01*
G01X56054Y868220D02*
X52304D01*
G01X59554Y872720D02*
X64876D01*
X67453Y875297D01*
G01D02*
X65030Y877720D01*
X59554D01*
G01D02*
X57054Y875220D01*
X51804D01*
X51304Y875720D01*
G01X56054Y872720D02*
X52000D01*
G01X59554Y868220D02*
X67013D01*
X70013Y871220D01*
Y875297D01*
G01X52770Y901388D02*
Y895754D01*
X56079Y892445D01*
X85079D01*
X85495Y892029D01*
G01X80248Y875297D02*
Y877463D01*
X76366Y881345D01*
X76240D01*
X75865Y881720D01*
X71855D01*
X65355Y888220D01*
X56804D01*
X56304Y888720D01*
G01X77688Y875297D02*
Y877846D01*
X75314Y880220D01*
X71304D01*
X65304Y886220D01*
X54804D01*
X51043Y889981D01*
G01X59554Y882220D02*
X63304D01*
G01D02*
X66304D01*
X70013Y878511D01*
Y875297D01*
G01X56054Y882220D02*
X51304D01*
G01X56054Y877720D02*
X52804D01*
X51896Y878628D01*
Y878668D01*
G01X60804Y907720D02*
X57770Y904686D01*
Y901388D01*
G01D02*
Y897254D01*
X59320Y895704D01*
X87018D01*
X93043Y889679D01*
Y883220D01*
G01X90488Y888720D02*
Y890183D01*
X86417Y894254D01*
X56945D01*
X55270Y895929D01*
Y901388D01*
G01D02*
Y905686D01*
X56804Y907220D01*
G01X52304Y906720D02*
X52770Y906254D01*
Y901388D01*
G01X64804Y907720D02*
X64376D01*
X60270Y903614D01*
Y901388D01*
G01D02*
X60304Y901354D01*
Y899128D01*
X62278Y897154D01*
X88870D01*
X95603Y890421D01*
G01X57770Y932686D02*
Y921988D01*
G01X125984Y1008860D02*
Y982991D01*
X78400Y935407D01*
Y918790D01*
X74973Y915363D01*
X61137D01*
X57770Y918730D01*
Y921988D01*
G01X55270Y929186D02*
Y921988D01*
G01X129919Y1008860D02*
Y995419D01*
X128000Y993500D01*
Y982744D01*
X80000Y934744D01*
Y918339D01*
X75574Y913913D01*
X60087D01*
X55270Y918730D01*
Y921988D01*
G01X52770Y932686D02*
Y921988D01*
G01X133859Y1008860D02*
Y996859D01*
X129500Y992500D01*
Y982122D01*
X81500Y934122D01*
Y917788D01*
X76175Y912463D01*
X59486D01*
X52770Y919179D01*
Y921988D01*
G01X62770Y932686D02*
Y921988D01*
G01X118109Y1008860D02*
Y997391D01*
X119925Y995575D01*
Y981034D01*
X75500Y936609D01*
Y919992D01*
X73771Y918263D01*
X63237D01*
X62770Y918730D01*
Y921988D01*
G01X60270Y929186D02*
Y921988D01*
G01X122049Y1008860D02*
Y981107D01*
X76950Y936008D01*
Y919391D01*
X74372Y916813D01*
X62187D01*
X60270Y918730D01*
Y921988D01*
G01X69500Y642500D02*
X72647Y639353D01*
Y637147D01*
X121685Y588109D01*
Y587919D01*
G01X76000Y652500D02*
X84500Y644000D01*
Y637154D01*
X132075Y589579D01*
Y586202D01*
X133500Y584777D01*
Y582500D01*
G01X80926Y644426D02*
X82500Y642852D01*
Y637103D01*
X130625Y588978D01*
Y582652D01*
X136377Y576900D01*
X136500D01*
G01X69232Y669714D02*
Y656120D01*
X80926Y644426D01*
G01X70500Y651500D02*
X81000Y641000D01*
Y636552D01*
X129175Y588377D01*
Y580625D01*
X136500Y573300D01*
G01X74500Y644000D02*
X77500Y641000D01*
Y638001D01*
X125000Y590501D01*
Y589000D01*
X126500Y587500D01*
G01X70807Y669714D02*
Y657693D01*
X76000Y652500D01*
G01X67662Y669714D02*
Y654338D01*
X70500Y651500D01*
G01X79500Y656500D02*
X89000Y647000D01*
Y636756D01*
X136500Y589256D01*
Y580500D01*
G01X73957Y669714D02*
Y662043D01*
X79500Y656500D01*
G01X82000Y650500D02*
X86000Y646500D01*
Y637705D01*
X134000Y589705D01*
Y587000D01*
G01X72382Y669714D02*
Y660118D01*
X82000Y650500D01*
G01X75432Y729959D02*
Y725720D01*
X74479Y724767D01*
Y716000D01*
X74079Y715600D01*
Y710222D01*
X83582Y700719D01*
Y687810D01*
X79611Y683839D01*
X73784D01*
X70807Y686816D01*
Y691914D01*
G01X73957D02*
Y687768D01*
X74986Y686739D01*
X78409D01*
X80682Y689012D01*
Y699517D01*
X69804Y710395D01*
Y720854D01*
X68147Y722511D01*
G01X85672Y729959D02*
Y725325D01*
X86777Y724220D01*
Y686903D01*
X80813Y680939D01*
X72582D01*
X67662Y685859D01*
Y691914D01*
G01X69232D02*
Y686341D01*
X69342Y686230D01*
X73183Y682389D01*
X80212D01*
X85032Y687209D01*
Y722820D01*
X83112Y724740D01*
Y729959D01*
G01X72382Y691914D02*
X72358Y691890D01*
Y687316D01*
X74385Y685289D01*
X79010D01*
X82132Y688411D01*
Y700118D01*
X71846Y710404D01*
Y722426D01*
G01X70317Y729959D02*
Y723596D01*
X69232Y722511D01*
X68147D01*
G01X72872Y729959D02*
X72772Y729859D01*
Y723352D01*
X71846Y722426D01*
G01X76804Y717970D02*
X81304D01*
G01X80552Y729959D02*
Y723472D01*
X81304Y722720D01*
Y722220D01*
G01Y717970D02*
Y722220D01*
G01X75432Y735059D02*
Y729959D01*
G01X104032Y691914D02*
X104157Y691789D01*
Y687034D01*
X108802Y682389D01*
X115012D01*
X119832Y687209D01*
Y717761D01*
X119833Y717762D01*
Y718962D01*
X119832Y718963D01*
X106754Y732042D01*
X95176Y743620D01*
X85251D01*
X80552Y748319D01*
Y752049D01*
G01X70317D02*
Y749207D01*
X78804Y740720D01*
X93974D01*
X103853Y730841D01*
Y730840D01*
X116932Y717761D01*
Y688411D01*
X113810Y685289D01*
X110004D01*
X107182Y688111D01*
Y691914D01*
G01X83112Y729959D02*
Y733164D01*
X81173Y735103D01*
X80272D01*
G01X67757Y752049D02*
Y749716D01*
X78203Y739270D01*
X93373D01*
X102403Y730240D01*
Y730239D01*
X115482Y717160D01*
Y689012D01*
X113209Y686739D01*
X110605D01*
X108854Y688490D01*
Y691817D01*
X108757Y691914D01*
G01X72872Y752049D02*
Y749883D01*
X74431Y748324D01*
X80586Y742170D01*
X94575D01*
X105304Y731441D01*
Y731440D01*
X118382Y718362D01*
Y687810D01*
X114411Y683839D01*
X109403D01*
X105607Y687635D01*
Y691914D01*
G01X80552Y752049D02*
X80772Y752269D01*
Y764093D01*
X80624Y764241D01*
G01X68910Y760642D02*
X69207Y760345D01*
Y757785D01*
X70272Y756720D01*
Y752094D01*
X70317Y752049D01*
G01X68762Y764239D02*
X71329Y761672D01*
Y758695D01*
X72872Y757152D01*
Y752049D01*
G01X83112Y760720D02*
Y752049D01*
G01D02*
Y747810D01*
X85852Y745070D01*
X95777D01*
X121281Y719566D01*
X121283Y719563D01*
Y717161D01*
X121282Y717160D01*
Y686607D01*
X120434Y685759D01*
X120433D01*
X115613Y680939D01*
X108201D01*
X102581Y686559D01*
Y691795D01*
X102462Y691914D01*
G01X78304Y759720D02*
X78197Y759827D01*
Y766077D01*
X77804Y766470D01*
G01X77992Y752049D02*
Y759408D01*
X78304Y759720D01*
G01X73804Y769970D02*
X74304D01*
X77804Y766470D01*
G01X89054Y790220D02*
X87504D01*
X82804Y794920D01*
G01X71804Y801720D02*
Y797470D01*
G01D02*
X68056D01*
X67772Y797754D01*
G01X83304Y839970D02*
Y837696D01*
X84221Y836779D01*
Y836078D01*
G01X78804Y843470D02*
Y845720D01*
X80304Y847220D01*
G01X83304Y843470D02*
X78804D01*
G01X74304D02*
Y847220D01*
X72573Y848951D01*
Y853207D01*
G01X78804Y843470D02*
X74304D01*
G01X69804D02*
X67453Y845827D01*
Y853207D01*
G01X77688D02*
Y861553D01*
X84405Y868270D01*
X103905D01*
X110104Y874469D01*
Y891670D01*
X109054Y892720D01*
G01X75133Y853207D02*
Y861049D01*
X83804Y869720D01*
X103304D01*
X108654Y875070D01*
Y889220D01*
X106554Y891320D01*
Y895720D01*
G01X82808Y853207D02*
Y861224D01*
X86954Y865370D01*
X105107D01*
X114054Y874317D01*
Y892720D01*
G01X80248Y853207D02*
Y861164D01*
X85904Y866820D01*
X104506D01*
X111554Y873868D01*
Y896220D01*
G01X72573Y875297D02*
Y869989D01*
X72304Y869720D01*
G01X75133Y875297D02*
Y870891D01*
X76304Y869720D01*
G01X74554Y885720D02*
Y885365D01*
X76924Y882995D01*
X78925D01*
X82808Y879112D01*
Y875297D01*
G01X70304Y889720D02*
X74554D01*
G01D02*
Y885720D01*
G01X97737Y669714D02*
Y632263D01*
X111500Y618500D01*
G01X99312Y669714D02*
Y634188D01*
X121000Y612500D01*
G01X88227Y752049D02*
Y748797D01*
X89054Y747970D01*
X96979D01*
X124182Y720767D01*
Y720348D01*
X124183Y720346D01*
Y715959D01*
X124182Y715958D01*
Y685405D01*
X121636Y682859D01*
X121635D01*
X116814Y678038D01*
X114412D01*
X114411Y678039D01*
X106998D01*
X106150Y678887D01*
Y678888D01*
X99436Y685602D01*
Y691790D01*
X99312Y691914D01*
G01X92772Y714254D02*
Y710252D01*
X94804Y708220D01*
G01X96772Y714254D02*
Y712252D01*
X99804Y709220D01*
G01X96772Y717754D02*
X98304Y719286D01*
Y721720D01*
G01X95907Y729959D02*
Y725220D01*
X98304Y722823D01*
Y721720D01*
G01X92772Y717754D02*
Y721688D01*
X93347Y722263D01*
G01D02*
Y729959D01*
G01X83849Y735513D02*
Y735427D01*
X85672Y733604D01*
Y729959D01*
G01X88227D02*
Y734504D01*
X87772Y734959D01*
Y735059D01*
G01X90787Y729959D02*
Y733777D01*
X92050Y735040D01*
X92365D01*
G01X85672Y752049D02*
Y747979D01*
X87131Y746520D01*
X96378D01*
X122410Y720488D01*
X122732Y720165D01*
Y720005D01*
X122733Y720003D01*
Y716560D01*
X122732Y716559D01*
Y686006D01*
X121035Y684309D01*
X121034D01*
X116213Y679488D01*
X115013D01*
X115012Y679489D01*
X107600D01*
X101011Y686078D01*
Y691790D01*
X100887Y691914D01*
G01X85304Y768720D02*
X88227Y765797D01*
Y752049D01*
G01X85672Y763504D02*
Y752049D01*
G01X90787D02*
Y766237D01*
X90304Y766720D01*
G01X103804Y759470D02*
X99542D01*
X99536Y759476D01*
G01D02*
X95907Y755847D01*
Y752049D01*
G01X96772Y771254D02*
X96022Y770504D01*
X92522D01*
G01D02*
X90304Y768286D01*
Y766720D01*
G01X89054Y798220D02*
X85204D01*
G01X106654Y800690D02*
X102734D01*
X99604Y803820D01*
X97804D01*
G01X92554Y806720D02*
X94904D01*
X97804Y803820D01*
G01X96704Y809720D02*
X94054D01*
X92554Y811220D01*
G01X106654Y802655D02*
X105869D01*
X98804Y809720D01*
X96704D01*
G01X92554Y811220D02*
Y815220D01*
G01X92304Y843470D02*
X95554Y846720D01*
X96304D01*
G01X92304Y843470D02*
X87804D01*
G01D02*
X87554D01*
X85664Y845360D01*
Y847236D01*
X85763Y847335D01*
Y848931D01*
X85503Y849191D01*
Y853072D01*
X85368Y853207D01*
G01X96804Y840720D02*
X100304Y844220D01*
X101054D01*
G01X98163Y853207D02*
X98304Y853348D01*
Y855514D01*
X102360Y859570D01*
X107511D01*
X124054Y876113D01*
Y892220D01*
G01X95603Y853207D02*
Y859019D01*
X97604Y861020D01*
X106910D01*
X121554Y875664D01*
Y895220D01*
X121600Y895266D01*
G01X93043Y853207D02*
Y860209D01*
X95304Y862470D01*
X106309D01*
X119054Y875215D01*
Y892720D01*
G01X90488Y853207D02*
Y861404D01*
X93004Y863920D01*
X105708D01*
X116554Y874766D01*
Y895720D01*
G01X93043Y883220D02*
Y875297D01*
G01X90488Y888720D02*
Y875297D01*
G01X87928D02*
Y889596D01*
X85495Y892029D01*
G01X95603Y875297D02*
Y890421D01*
G01X116404Y320953D02*
X118453Y323002D01*
X118955D01*
X123406Y327453D01*
G01X111500Y618500D02*
X138425Y591575D01*
Y572425D01*
X136500Y570500D01*
Y569700D01*
G01X104032Y669714D02*
Y639968D01*
X116000Y628000D01*
G01D02*
X152948Y591052D01*
Y587000D01*
G01X100887Y669714D02*
Y636113D01*
X106500Y630500D01*
G01D02*
X141325Y595675D01*
Y568825D01*
X140500Y568000D01*
G01X102462Y669714D02*
Y638038D01*
X119500Y621000D01*
G01X108757Y669714D02*
Y647743D01*
X141500Y615000D01*
G01X107182Y669714D02*
Y644818D01*
X133500Y618500D01*
G01X105607Y669714D02*
Y642393D01*
X112000Y636000D01*
G01D02*
X156900Y591100D01*
Y586500D01*
G01X103804Y759470D02*
Y755720D01*
G01X101054Y844220D02*
X100723Y844551D01*
Y853207D01*
G01X129600Y839160D02*
X121160D01*
X113222Y831222D01*
G01X129600Y841720D02*
X119220D01*
X112500Y835000D01*
G01X102554Y882720D02*
X100723Y880889D01*
Y875297D01*
G01X109054Y892720D02*
Y901420D01*
G01X114054Y892720D02*
Y901420D01*
G01X106004Y886970D02*
X102304D01*
G01D02*
X102554Y886720D01*
Y882720D01*
G01X106554Y895720D02*
Y901420D01*
G01X111554Y896220D02*
Y901420D01*
G01X109054Y932720D02*
Y922020D01*
G01X185039Y1008860D02*
Y999039D01*
X151500Y965500D01*
Y917000D01*
X140000Y905500D01*
X123000D01*
X109054Y919446D01*
Y922020D01*
G01X116554D02*
Y918946D01*
X125500Y910000D01*
X137000D01*
X146199Y919199D01*
Y967696D01*
X173229Y994726D01*
Y1008860D01*
G01X114054Y932470D02*
Y922020D01*
G01X177164Y1008860D02*
Y996162D01*
X147966Y966964D01*
Y918464D01*
X138002Y908500D01*
X124500D01*
X114054Y918946D01*
Y922020D01*
G01X111554Y929720D02*
Y922020D01*
G01X181104Y1008860D02*
Y997603D01*
X149733Y966232D01*
Y917732D01*
X139001Y907000D01*
X123949D01*
X111554Y919395D01*
Y922020D01*
G01X106554D02*
Y933470D01*
X108804Y935720D01*
Y938795D01*
G01X116600Y929924D02*
X116554Y929878D01*
Y922020D01*
G01X114174Y1008860D02*
Y998326D01*
X118000Y994500D01*
Y991500D01*
G01X131500Y324000D02*
X132000D01*
X136250Y319750D01*
X138000D01*
G01X123406Y327453D02*
Y330746D01*
G03X122906Y331953I-1707J0D01*
G01X121000Y612500D02*
X139875Y593625D01*
Y570352D01*
X136000Y566477D01*
Y566000D01*
G01X119500Y621000D02*
X144000Y596500D01*
Y572500D01*
G01X122954Y800690D02*
X128474D01*
X128489Y800705D01*
X129147D01*
X130962Y802520D01*
X133004D01*
G01X122954Y802655D02*
X128339D01*
X133104Y807420D01*
G01X129054Y901420D02*
Y892970D01*
X129100Y892924D01*
G01X124054Y892220D02*
Y901420D01*
G01X119054Y892720D02*
Y901420D01*
G01X126554D02*
Y895470D01*
G01X121554Y901420D02*
Y895312D01*
X121600Y895266D01*
G01X116554Y895720D02*
Y901420D01*
G01X121554Y922020D02*
Y918946D01*
X127500Y913000D01*
X135000D01*
X142665Y920665D01*
Y969160D01*
X165354Y991849D01*
Y1008860D01*
G01X121598Y929924D02*
X121554Y929880D01*
Y922020D01*
G01X131554Y929470D02*
Y922020D01*
G01X149604Y1008860D02*
Y986596D01*
X135243Y972235D01*
Y923741D01*
X133522Y922020D01*
X131554D01*
G01X129054Y932720D02*
Y922020D01*
G01X153544Y1008860D02*
Y987536D01*
X137364Y971356D01*
Y922862D01*
X132002Y917500D01*
X130000D01*
X129054Y918446D01*
Y922020D01*
G01X126554Y929882D02*
Y922020D01*
G01X157479Y1008860D02*
Y988972D01*
X139131Y970624D01*
Y922130D01*
X133001Y916000D01*
X129000D01*
X126554Y918446D01*
Y922020D01*
G01X124054D02*
Y918895D01*
X128449Y914500D01*
X134000D01*
X140898Y921398D01*
Y969892D01*
X161419Y990413D01*
Y1008860D01*
G01X124098Y932515D02*
X124054Y932471D01*
Y922020D01*
G01X119099Y932516D02*
X119054Y932471D01*
Y922020D01*
G01X169289Y1008860D02*
Y993285D01*
X144432Y968428D01*
Y919931D01*
X136001Y911500D01*
X126500D01*
X119054Y918946D01*
Y922020D01*
G01X183493Y554696D02*
X181618Y552821D01*
Y552395D01*
X181194Y551971D01*
X170604D01*
X165900Y556675D01*
X155760D01*
X148235Y549150D01*
Y532629D01*
X167364Y513500D01*
X201000D01*
X208000Y506500D01*
G01X167469Y588969D02*
Y589031D01*
X141500Y615000D01*
G01X133500Y618500D02*
X160500Y591500D01*
Y586500D01*
G01X138750Y666500D02*
Y661250D01*
X135000Y657500D01*
X133500D01*
G01X146750Y666500D02*
Y653750D01*
X150000Y650500D01*
G01X143250Y666500D02*
X138750D01*
G01X139625Y673250D02*
X138750Y672375D01*
Y666500D01*
G01X143500Y702750D02*
Y695960D01*
G01D02*
X150420D01*
X150460Y696000D01*
X152000D01*
X155500Y692500D01*
X171223D01*
X221805Y641918D01*
Y569750D01*
G01X141054Y795820D02*
Y791720D01*
G01D02*
X141334Y792000D01*
X145000D01*
G01X141054Y783720D02*
X147746Y790412D01*
X150225D01*
G01X141054Y803720D02*
X145804D01*
X146304Y804220D01*
G01X141054Y808220D02*
X146500D01*
G01X141054Y799720D02*
X146720D01*
X154500Y807500D01*
Y812500D01*
G01X137554Y803720D02*
Y799720D01*
G01D02*
X134754Y802520D01*
X133004D01*
G01X133104Y807420D02*
X133904Y808220D01*
X137554D01*
G01D02*
Y812720D01*
G01X141054D02*
X150680D01*
X150900Y812500D01*
G01X142400Y839160D02*
X144840D01*
X148425Y835575D01*
X158340D01*
X172000Y849235D01*
Y868000D01*
G01X142400Y841720D02*
X145901D01*
X150096Y837525D01*
X157532D01*
X168400Y848393D01*
Y868000D01*
G01X168300Y453550D02*
X164550D01*
X164300Y453800D01*
G01X165050Y457800D02*
X164300Y457050D01*
Y453800D01*
G01X153050Y486500D02*
X153000Y486450D01*
Y479500D01*
X151992Y478492D01*
Y474358D01*
X152050Y474300D01*
G01X155550Y469800D02*
X158700D01*
X159200Y470300D01*
G01X166700Y471285D02*
X160185D01*
X159200Y470300D01*
G01X155550Y474300D02*
X158300D01*
X159500Y475500D01*
G01X166700Y473255D02*
X163845D01*
X161600Y475500D01*
X159500D01*
G01X163305Y550500D02*
X163430Y550375D01*
Y543750D01*
G01X163305Y554750D02*
Y550500D01*
G01X166500Y650500D02*
X150000D01*
G01X159125Y673250D02*
X159250D01*
X162500Y670000D01*
G01X163000Y702750D02*
Y696460D01*
G01X224148Y577400D02*
Y641909D01*
X171907Y694150D01*
X171850D01*
X171500Y694500D01*
X164960D01*
X163000Y696460D01*
G01X200000Y401500D02*
Y404400D01*
X201600Y406000D01*
X207000D01*
X210121Y409121D01*
Y431879D01*
X206000Y436000D01*
X180000D01*
X170950Y445050D01*
Y448200D01*
X172800Y450050D01*
G01X200000Y411500D02*
Y409621D01*
X201500Y408121D01*
X206121D01*
X208000Y410000D01*
Y431000D01*
X204500Y434500D01*
X179000D01*
X169500Y444000D01*
Y448850D01*
X168300Y450050D01*
G01X172800Y453550D02*
X175750D01*
X176400Y454200D01*
G01X176050Y457800D02*
X176400Y457450D01*
Y454200D01*
G01X168550Y457800D02*
Y460900D01*
X169500Y461850D01*
Y462800D01*
G01X166700Y467345D02*
Y465600D01*
X169500Y462800D01*
G01X175900Y467345D02*
Y463000D01*
G01X172550Y457800D02*
Y459650D01*
X175900Y463000D01*
G01X171500Y478699D02*
X186651D01*
X190550Y474800D01*
G01X175900Y473255D02*
X179755D01*
X181300Y474800D01*
X182800D01*
G01X177555Y530000D02*
X181805D01*
G01D02*
Y525500D01*
G01D02*
X177055Y520750D01*
X175995D01*
G01X175993Y544096D02*
Y546938D01*
X177555Y548500D01*
X182555D01*
X183493Y547562D01*
Y544096D01*
G01X175993Y554696D02*
Y559938D01*
G01X178496Y565050D02*
X175105D01*
X173130Y567025D01*
Y657630D01*
X182500Y667000D01*
Y677500D01*
G01X198250Y796875D02*
X192125D01*
X170500Y818500D01*
Y835500D01*
G01X174000Y830500D02*
Y830000D01*
X186000Y818000D01*
G01X188189Y303465D02*
Y297315D01*
X188295Y297209D01*
G01X194488Y303465D02*
Y298402D01*
X193841Y297755D01*
G01X185039Y303465D02*
Y295209D01*
G01X191338Y303465D02*
Y295252D01*
X191295Y295209D01*
G01X183464Y313347D02*
Y321378D01*
X184295Y322209D01*
G01X192913Y313347D02*
Y321591D01*
X192795Y321709D01*
G01X186614Y313347D02*
Y319028D01*
G01X189763Y313347D02*
Y318177D01*
X190295Y318709D01*
G01X216500Y401500D02*
Y404250D01*
X218000Y405750D01*
X221432D01*
X226750Y411068D01*
Y432432D01*
X216932Y442250D01*
X194750D01*
X190750Y446250D01*
Y449000D01*
X191800Y450050D01*
G01X216500Y411500D02*
Y409600D01*
X218100Y408000D01*
X220500D01*
X224500Y412000D01*
Y431500D01*
X216000Y440000D01*
X193818D01*
X188500Y445318D01*
Y448850D01*
X187300Y450050D01*
G01Y453550D02*
Y457300D01*
G01X191800D02*
Y453550D01*
G01X187050Y474800D02*
X182800D01*
G01X201805Y532560D02*
X190495D01*
X188955Y534100D01*
G01X201805Y530000D02*
X195800D01*
G01D02*
X185305D01*
G01X185493Y537396D02*
Y539062D01*
X183493Y541062D01*
Y544096D01*
G01X188955Y534100D02*
X185659Y537396D01*
X185493D01*
G01X201805Y545060D02*
X193115D01*
G01X208305Y527440D02*
X206085D01*
X204930Y528595D01*
Y534365D01*
X203200Y536095D01*
X190100D01*
X188505Y537690D01*
Y543520D01*
X190045Y545060D01*
X193115D01*
G01X183493Y554696D02*
Y564929D01*
X183614Y565050D01*
G01D02*
X185105D01*
X186805Y566750D01*
X189555D01*
G01X195555Y558060D02*
X201805D01*
G01X207500Y710750D02*
Y711000D01*
X194500Y724000D01*
G01X190118Y729409D02*
Y728382D01*
X194500Y724000D01*
G01X198250Y810875D02*
X193125D01*
X186000Y818000D01*
G01X208000Y506500D02*
X220000Y494500D01*
X240145D01*
X243755Y490890D01*
G01X215153Y521183D02*
X211273D01*
G01X208305Y539940D02*
X213725D01*
X215835Y537830D01*
Y526530D01*
X217197Y525168D01*
X222673D01*
G01X201805Y558060D02*
X203915D01*
X204930Y557045D01*
Y543665D01*
X203765Y542500D01*
X201805D01*
G01X218305Y560000D02*
Y559750D01*
X215055Y556500D01*
G01X208305Y552940D02*
X211495D01*
X215055Y556500D01*
G01X218305Y564500D02*
X215055D01*
X214555Y564000D01*
G01X208305Y555500D02*
X211405D01*
X212555Y556650D01*
Y562000D01*
X214555Y564000D01*
G01X212000Y710750D02*
Y713500D01*
X204500Y721000D01*
G01X210118Y729409D02*
Y718882D01*
X212500Y716500D01*
G01X216500Y710750D02*
Y712500D01*
X212500Y716500D01*
G01X200118Y729409D02*
Y725382D01*
X204500Y721000D01*
G01X205750Y793000D02*
Y807000D01*
G01D02*
X206250Y807500D01*
X212500D01*
G01X212250Y812000D02*
Y807750D01*
X212500Y807500D01*
G01X217000D02*
X212500D01*
G01X298373Y507453D02*
X282008D01*
X271555Y497000D01*
X229055D01*
G01X222673Y501543D02*
X226632D01*
X228500Y499675D01*
X229807D01*
X230057Y499925D01*
X231653D01*
X231903Y499675D01*
X245580D01*
X245815Y499440D01*
X255145D01*
X258305Y502600D01*
X260535D01*
X260985Y503050D01*
Y506290D01*
X261435Y506740D01*
X262335D01*
X262785Y506290D01*
Y503050D01*
X263235Y502600D01*
X264135D01*
X264585Y503050D01*
Y508875D01*
X264879Y509169D01*
X266116D01*
X266385Y508900D01*
Y503050D01*
X266835Y502600D01*
X267735D01*
X268185Y503050D01*
Y509210D01*
X268535Y509560D01*
X269645D01*
X269985Y509220D01*
Y503050D01*
X270435Y502600D01*
X271205D01*
X271795Y502010D01*
Y500791D01*
X270444Y499440D01*
X260035D01*
X259055Y500420D01*
Y500500D01*
G01X222673Y507453D02*
X227620D01*
X228773Y506300D01*
X241976D01*
X242003Y506327D01*
G01X222673Y509418D02*
X225973D01*
X226255Y509700D01*
X234755D01*
G01X222673Y505483D02*
X227539D01*
X228197Y504825D01*
X237613D01*
X238063Y504375D01*
X244901D01*
X245205Y504679D01*
G01X222673Y503513D02*
X227458D01*
X227596Y503375D01*
X229262D01*
X229712Y502925D01*
Y501825D01*
X230162Y501375D01*
X231062D01*
X231512Y501825D01*
Y502925D01*
X231962Y503375D01*
X232862D01*
X233312Y502925D01*
Y501825D01*
X233762Y501375D01*
X234662D01*
X235112Y501825D01*
Y502492D01*
X235545Y502925D01*
X236870D01*
X237320Y502475D01*
Y501575D01*
X237770Y501125D01*
X238670D01*
X239120Y501575D01*
Y502475D01*
X239570Y502925D01*
X241020D01*
X242445Y501500D01*
X246478D01*
X246613Y501365D01*
G01X222673Y513358D02*
X225670D01*
X225812Y513500D01*
X237055D01*
G01X222673Y515323D02*
X225584D01*
X225795Y515534D01*
X239934D01*
X240384Y515084D01*
Y512700D01*
X240834Y512250D01*
X241734D01*
X242184Y512700D01*
Y515084D01*
X242634Y515534D01*
X243534D01*
X243984Y515084D01*
Y512700D01*
X244434Y512250D01*
X245334D01*
X245784Y512700D01*
Y515084D01*
X246234Y515534D01*
X248451D01*
X248901Y515084D01*
Y513450D01*
X249351Y513000D01*
X250251D01*
X250701Y513450D01*
Y515084D01*
X251151Y515534D01*
X252051D01*
X252501Y515084D01*
Y513450D01*
X252951Y513000D01*
X253851D01*
X254301Y513450D01*
Y515084D01*
X254751Y515534D01*
X255651D01*
X256370Y514815D01*
Y513475D01*
X256845Y513000D01*
X257785D01*
X258155Y513370D01*
Y515660D01*
X259145Y516650D01*
X264103D01*
X265733Y515020D01*
X270525D01*
X270975Y515470D01*
Y518170D01*
X271425Y518620D01*
X272385D01*
X272775Y518230D01*
Y515470D01*
X273225Y515020D01*
X277155D01*
X277795Y514380D01*
Y513650D01*
X277745D01*
X277245Y513150D01*
X261727D01*
X260288Y514589D01*
G01X222673Y511388D02*
X225751D01*
X225988Y511625D01*
X235553D01*
X236378Y510800D01*
X236746D01*
X237196Y510350D01*
Y508702D01*
X237646Y508252D01*
X238546D01*
X238996Y508702D01*
Y510350D01*
X239446Y510800D01*
X240346D01*
X240796Y510350D01*
Y508702D01*
X241246Y508252D01*
X242146D01*
X242596Y508702D01*
Y510350D01*
X243046Y510800D01*
X243946D01*
X244396Y510350D01*
Y508702D01*
X244846Y508252D01*
X245746D01*
X246196Y508702D01*
Y510350D01*
X246646Y510800D01*
X247475D01*
X247866Y510409D01*
Y508589D01*
X248185Y508270D01*
X249635D01*
X250085Y507820D01*
Y501310D01*
X250505Y500890D01*
X251340D01*
X251885Y501435D01*
Y507820D01*
X252335Y508270D01*
X253235D01*
X253685Y507820D01*
Y501680D01*
X254065Y501300D01*
X254954D01*
X255485Y501831D01*
Y507820D01*
X255935Y508270D01*
X256835D01*
X257285Y507820D01*
Y504960D01*
X257695Y504550D01*
X258645D01*
X259085Y504990D01*
Y507820D01*
X259535Y508270D01*
X261725D01*
X262720Y509265D01*
Y510865D01*
X262035Y511550D01*
X250805D01*
X250055Y510800D01*
G01X222673Y531073D02*
X247359D01*
X248057Y530375D01*
X249653D01*
X249819Y530541D01*
X251076D01*
X253595Y533060D01*
X261235D01*
X267145Y527150D01*
X267185D01*
X269075Y525260D01*
Y516840D01*
X268705Y516470D01*
X266335D01*
X265835Y516970D01*
Y521710D01*
X266285Y522160D01*
X267175D01*
X267625Y522610D01*
Y523510D01*
X267175Y523960D01*
X266285D01*
X264712Y525533D01*
Y526169D01*
X265074Y526531D01*
Y527167D01*
X264437Y527804D01*
X263801D01*
X263439Y527442D01*
X262803D01*
X262166Y528079D01*
Y528715D01*
X262528Y529077D01*
Y529713D01*
X261891Y530350D01*
X261255D01*
X260893Y529988D01*
X260257D01*
X259229Y531016D01*
X256055D01*
G01X222673Y529103D02*
X247278D01*
X247456Y528925D01*
X250254D01*
X250420Y529091D01*
X255929D01*
X256320Y528700D01*
X257355D01*
X260555Y525500D01*
G01X222673Y527138D02*
X234185D01*
G01X222673Y523198D02*
X225329D01*
X225654Y522873D01*
X227104D01*
X227554Y522423D01*
Y521163D01*
X228004Y520713D01*
X228904D01*
X229354Y521163D01*
Y522423D01*
X229804Y522873D01*
X230704D01*
X231154Y522423D01*
Y521163D01*
X231604Y520713D01*
X232504D01*
X232954Y521163D01*
Y522423D01*
X233668Y523137D01*
X237817D01*
X238267Y523587D01*
Y527000D01*
X238767Y527500D01*
X239567D01*
X240067Y527000D01*
Y523587D01*
X240517Y523137D01*
X241417D01*
X241867Y523587D01*
Y526800D01*
X242317Y527250D01*
X243217D01*
X243667Y526800D01*
Y523587D01*
X244117Y523137D01*
X245017D01*
X245467Y523587D01*
Y526800D01*
X245917Y527250D01*
X246817D01*
X247267Y526800D01*
Y523587D01*
X247717Y523137D01*
X248617D01*
X249067Y523587D01*
Y526800D01*
X249517Y527250D01*
X250967D01*
X251417Y526800D01*
Y525950D01*
X251867Y525500D01*
X252767D01*
X253217Y525950D01*
Y526800D01*
X253667Y527250D01*
X255955D01*
X259735Y523470D01*
X261375D01*
X261955Y522890D01*
Y521810D01*
X261315Y521170D01*
X255646D01*
X253679Y523137D01*
G01X222673Y517293D02*
X241986D01*
X242436Y517743D01*
Y521237D01*
X242886Y521687D01*
X243786D01*
X244236Y521237D01*
Y517743D01*
X244686Y517293D01*
X245586D01*
X246036Y517743D01*
Y521237D01*
X246486Y521687D01*
X247386D01*
X247836Y521237D01*
Y517743D01*
X248286Y517293D01*
X249186D01*
X249636Y517743D01*
Y521237D01*
X250086Y521687D01*
X250986D01*
X251436Y521237D01*
Y517743D01*
X251886Y517293D01*
X253336D01*
X253786Y517743D01*
Y519100D01*
X254236Y519550D01*
X255136D01*
X255586Y519100D01*
Y517743D01*
X256036Y517293D01*
X257318D01*
X259270Y519245D01*
X260605D01*
G01X222673Y519263D02*
X236618D01*
X237355Y520000D01*
X239055D01*
X239555Y519500D01*
G01X222673Y525168D02*
X227949D01*
X228319Y524798D01*
G01X222673Y521228D02*
X222628Y521183D01*
X215153D01*
G01X222673Y540913D02*
X271668D01*
X271905Y541150D01*
X272571D01*
G01X222673Y538948D02*
X274778D01*
X278367Y535359D01*
Y535140D01*
G01X222673Y536978D02*
X268577D01*
X269555Y536000D01*
G01X222673Y535008D02*
X262647D01*
X263155Y534500D01*
X263555D01*
G01X222673Y533043D02*
X248278D01*
X248855Y532466D01*
Y532300D01*
G01X222673Y544853D02*
X243986D01*
X244436Y545303D01*
Y558460D01*
X244886Y558910D01*
X245786D01*
X246236Y558460D01*
Y557010D01*
X246686Y556560D01*
X247835D01*
X248285Y556110D01*
Y555210D01*
X247835Y554760D01*
X246686D01*
X246236Y554310D01*
Y553410D01*
X246686Y552960D01*
X247835D01*
X248285Y552510D01*
Y551610D01*
X247835Y551160D01*
X246686D01*
X246236Y550710D01*
Y545303D01*
X246686Y544853D01*
X265455D01*
G01X222673Y542883D02*
X267248D01*
X268515Y544150D01*
Y546560D01*
X268615Y546660D01*
X268625D01*
X269105Y547140D01*
X290525D01*
X292105Y545560D01*
Y544090D01*
X291335Y543320D01*
X272747D01*
X271451Y544616D01*
G01X222673Y548788D02*
X239693D01*
X241020Y550115D01*
Y560355D01*
X242485Y561820D01*
X249585D01*
X249855Y561550D01*
Y561544D01*
X251299Y560100D01*
Y549516D01*
X252055Y548760D01*
G01X222673Y546823D02*
X240038D01*
X242470Y549255D01*
Y559445D01*
X243395Y560370D01*
X248735D01*
X249735Y559370D01*
Y547836D01*
X250748Y546823D01*
X253578D01*
X255755Y549000D01*
X257555D01*
G01X221805Y560000D02*
X224148Y562343D01*
Y577400D01*
G01X221805Y564500D02*
Y569750D01*
G01X230000Y680500D02*
Y689000D01*
X247275Y706275D01*
Y708025D01*
X250000Y710750D01*
G01X221000D02*
Y723000D01*
G01X270000Y870000D02*
X272500Y867500D01*
Y843551D01*
X250074Y821125D01*
X227875D01*
X223500Y825500D01*
G01X224000Y829250D02*
Y826000D01*
X223500Y825500D01*
G01X270000Y865500D02*
Y843809D01*
X249266Y823075D01*
X229925D01*
X228000Y825000D01*
G01Y829250D02*
Y825000D01*
G01X220000Y829250D02*
X219750D01*
X215250Y833750D01*
G01X228000Y832750D02*
X228890Y833640D01*
Y838890D01*
G01X232000Y832750D02*
X228000D01*
G01X228890Y838890D02*
Y848450D01*
G01X220000Y832750D02*
X224000D01*
G01D02*
Y838500D01*
G01D02*
Y841500D01*
X226921Y844421D01*
Y848750D01*
G01X240750Y423000D02*
Y419000D01*
G01D02*
X250500D01*
G01X245000Y427000D02*
X240750D01*
G01X245000D02*
X247586D01*
X258733Y415853D01*
X302267D01*
X305047Y418633D01*
X338906D01*
X359508Y398031D01*
X363312D01*
X363406Y398125D01*
X395969D01*
X402952Y391142D01*
G01X240750Y427000D02*
Y431000D01*
G01X234623Y565933D02*
Y562623D01*
X234000Y562000D01*
G01Y558500D02*
Y562000D01*
G01X240118Y729409D02*
Y706618D01*
X238500Y705000D01*
G01X232000Y829250D02*
Y825000D01*
G01X250500Y419000D02*
X251500D01*
X256500Y414000D01*
X302500D01*
X305683Y417183D01*
X338305D01*
X358907Y396581D01*
X385581D01*
X385675Y396675D01*
X394766D01*
X402952Y388489D01*
Y387205D01*
G01X298373Y546823D02*
X295352D01*
X293175Y549000D01*
X280615D01*
X280165Y549450D01*
Y555310D01*
X279715Y555760D01*
X278815D01*
X278365Y555310D01*
Y549450D01*
X277915Y549000D01*
X277015D01*
X276565Y549450D01*
Y555310D01*
X276115Y555760D01*
X275215D01*
X274765Y555310D01*
Y549450D01*
X274315Y549000D01*
X261255D01*
G01X250118Y729409D02*
Y710868D01*
X250000Y710750D01*
G01X298373Y513358D02*
X281317D01*
X280496Y514179D01*
X279997D01*
G01X298373Y511388D02*
X294208D01*
X294171Y511425D01*
X291428D01*
X291103Y511100D01*
X264655D01*
G01X298373Y535008D02*
X289280D01*
X287487Y533215D01*
X277870D01*
X276155Y531500D01*
X275555D01*
G01X298373Y521228D02*
X286866D01*
X285961Y522133D01*
X282305D01*
X281997Y521825D01*
X275055D01*
G01X298373Y531073D02*
X278210D01*
X276712Y529575D01*
X268205D01*
X266055Y531725D01*
G01X298373Y538948D02*
X289120D01*
X288947Y538775D01*
X279401D01*
X278676Y539500D01*
G01X296000Y91250D02*
Y94200D01*
X296200Y94400D01*
G01X298373Y501543D02*
X295288D01*
X292525Y498780D01*
G01X292045Y504897D02*
X293429Y503513D01*
X298373D01*
G01Y509418D02*
X294248D01*
X294166Y509500D01*
X293273D01*
G01X298373Y515323D02*
X283795D01*
X282685Y516433D01*
Y516580D01*
X282626Y516639D01*
G01X298373Y527138D02*
X293261D01*
X291530Y525407D01*
G01X298373Y517293D02*
X285877D01*
X284630Y518540D01*
Y518681D01*
X283103Y520208D01*
G01X298373Y519263D02*
X290729D01*
X290687Y519305D01*
X286588D01*
G01X298373Y529103D02*
X292358D01*
X292255Y529000D01*
X291755D01*
G01X298373Y523198D02*
X287881D01*
X286555Y524524D01*
G01X298373Y540913D02*
X293168D01*
X292955Y540700D01*
X282555D01*
G01X298373Y536978D02*
X283166D01*
X283038Y536850D01*
G01X298373Y533043D02*
X292555D01*
G01X302000Y97500D02*
Y94300D01*
G01X300500Y91250D02*
Y93000D01*
X301800Y94300D01*
X302000D01*
G01X302555Y476000D02*
Y469076D01*
X314573Y457058D01*
X315872D01*
X315922Y457108D01*
X318098D01*
X320773Y459783D01*
G01Y464283D02*
Y465782D01*
X319055Y467500D01*
X310055D01*
X305055Y472500D01*
G01X312773Y507683D02*
X308090Y503000D01*
X303568D01*
X303055Y503513D01*
X298373D01*
G01X334415Y540100D02*
Y545360D01*
X334597D01*
X338305Y549068D01*
Y566318D01*
X327373Y577250D01*
X317750D01*
X313000Y582000D01*
G01X328000Y285000D02*
X355200D01*
X357500Y282700D01*
X378745D01*
X384250Y277195D01*
Y271195D01*
X384354Y271091D01*
Y265174D01*
X387500Y262028D01*
Y261000D01*
G01X320743Y454373D02*
Y450373D01*
G01D02*
X327053D01*
X331623Y454943D01*
G01Y462623D02*
X322433D01*
X320773Y464283D01*
G01Y459783D02*
X321053Y460063D01*
X331623D01*
G01Y457503D02*
X327058D01*
X325224Y455669D01*
G01X320743Y454373D02*
X323928D01*
X325224Y455669D01*
G01X321773Y475283D02*
X324970D01*
X325855Y476168D01*
Y476988D01*
X325873Y477006D01*
G01X321773Y479783D02*
X324838D01*
X325655Y480600D01*
X325848D01*
X325854Y480606D01*
G01X326545Y517900D02*
Y526318D01*
X334727Y534500D01*
X341055D01*
G01X328120Y517900D02*
Y525842D01*
X334778Y532500D01*
X342004D01*
X342454Y532950D01*
X343105D01*
X344655Y534500D01*
G01X329695Y517900D02*
Y524694D01*
X330491Y525490D01*
G01X329695Y540100D02*
Y534650D01*
G01X329055Y552750D02*
Y548500D01*
G01X328120Y540100D02*
Y547565D01*
X329055Y548500D01*
G01Y556250D02*
Y569500D01*
G01X355055Y552750D02*
X328305Y579500D01*
X319555D01*
X317758Y581297D01*
G01X331270Y540100D02*
Y547568D01*
X331280Y547578D01*
Y548676D01*
X333055Y550451D01*
Y568386D01*
X326441Y575000D01*
X321780D01*
G01X357183Y540194D02*
Y545500D01*
X358000Y546317D01*
Y553555D01*
X327368Y584187D01*
X316243D01*
X314930Y585500D01*
G01X341000Y116290D02*
Y119040D01*
X340000Y120040D01*
G01X336679Y241500D02*
X334804Y239625D01*
Y236196D01*
X344929Y226071D01*
Y191998D01*
X355038Y181889D01*
X357284D01*
G01X344679Y237500D02*
X348500Y233679D01*
Y189771D01*
X354771Y183500D01*
X357724D01*
X359335Y181889D01*
X360433D01*
G01X332829Y262600D02*
X333429Y262000D01*
Y255000D01*
X336929Y251500D01*
Y241750D01*
X336679Y241500D01*
G01X351555Y465480D02*
X332575D01*
X330555Y467500D01*
G01X344423Y460063D02*
X348032D01*
X360095Y448000D01*
X367555D01*
X372330Y443225D01*
Y434370D01*
X373275Y433425D01*
X374189D01*
X374616Y432997D01*
X376074D01*
X376111Y432960D01*
X376370D01*
X376505Y432825D01*
X376506D01*
X376930Y432401D01*
Y432400D01*
X378331Y431000D01*
X378555D01*
G01X344423Y462623D02*
X348690D01*
X354988Y456325D01*
G01X343923Y479503D02*
X349575D01*
G01X343923Y476943D02*
X348242D01*
X349635Y475550D01*
X349815D01*
G01X355273Y482783D02*
X354553Y482063D01*
X343923D01*
G01X347055Y468450D02*
X345555D01*
X344535Y467430D01*
X338985D01*
G01D02*
Y467405D01*
G01X331123Y479503D02*
X336985D01*
X338985Y477503D01*
Y467430D01*
G01X330555Y467500D02*
Y471932D01*
X331123Y472500D01*
Y476943D01*
G01X343923Y484623D02*
X350055D01*
G01X361908Y517994D02*
Y522647D01*
X356555Y528000D01*
X345055D01*
X344055Y529000D01*
G01X355613Y517994D02*
Y520845D01*
X354383Y522075D01*
X351336D01*
X350130Y523281D01*
Y523431D01*
X348561Y525000D01*
X344803D01*
X343728Y523925D01*
X342214D01*
X342139Y524000D01*
X340055D01*
G01X360333Y517994D02*
Y521605D01*
X355438Y526500D01*
X343721D01*
X342971Y525750D01*
G01X332840Y517900D02*
Y521285D01*
X343055Y531500D01*
X345255D01*
X348255Y534500D01*
G01X331270Y517900D02*
Y523215D01*
X334055Y526000D01*
G01X332840Y540100D02*
Y546785D01*
X334555Y548500D01*
G01X336055Y552000D02*
Y550000D01*
X334555Y548500D01*
G01X358758Y540194D02*
Y544809D01*
X361000Y547051D01*
Y563555D01*
X346402Y578153D01*
Y653004D01*
G01X339888Y586388D02*
Y611888D01*
G01D02*
Y647500D01*
X342500Y650112D01*
Y653000D01*
G01X335500Y868000D02*
X339000Y871500D01*
Y872000D01*
X340500Y873500D01*
Y873600D01*
G01X347250Y878500D02*
X344000Y875250D01*
X342250D01*
X340600Y873600D01*
X340500D01*
G01X336000Y871500D02*
X335500Y872000D01*
Y881500D01*
G01X351250Y889000D02*
X350250Y888000D01*
X334329D01*
X331829Y885500D01*
G01X347250Y884500D02*
Y883250D01*
X345500Y881500D01*
X335500D01*
G01X343750Y921700D02*
Y924025D01*
X342350Y925425D01*
X340249D01*
X339825Y925001D01*
Y911175D01*
X346750Y904250D01*
X357505D01*
X359625Y902130D01*
X362500D01*
X365830Y905460D01*
X368900D01*
G01X346250Y921700D02*
Y926500D01*
X345875Y926875D01*
X339648D01*
X338375Y925602D01*
Y910574D01*
X346149Y902800D01*
X356904D01*
X359024Y900680D01*
X363899D01*
X366119Y902900D01*
X368900D01*
G01Y900340D02*
X365610D01*
X364500Y899230D01*
X358423D01*
X356303Y901350D01*
X345500D01*
X339850Y907000D01*
X338000D01*
G01X348750Y921700D02*
Y926250D01*
X346025Y928975D01*
X338804D01*
X337889Y928060D01*
X337888D01*
X336350Y926522D01*
Y908650D01*
X338000Y907000D01*
G01X368900Y897780D02*
X357822D01*
X355702Y899900D01*
X343600D01*
X341000Y902500D01*
G01X351250Y921700D02*
Y926250D01*
X347000Y930500D01*
X338000D01*
X334900Y927400D01*
Y906601D01*
X338000Y903501D01*
X339999D01*
X341000Y902500D01*
G01X353750Y921700D02*
Y926250D01*
X348000Y932000D01*
X337000D01*
X333450Y928450D01*
Y906000D01*
X341000Y898450D01*
X355101D01*
X358331Y895220D01*
X362780D01*
G01X368900Y892660D02*
X358840D01*
X354500Y897000D01*
X338500D01*
X336000Y899500D01*
G01X356250Y921700D02*
Y926250D01*
X349000Y933500D01*
X336000D01*
X332000Y929500D01*
Y903500D01*
X336000Y899500D01*
G01X338000Y952750D02*
X338870D01*
X346250Y946265D01*
Y942300D01*
G01D02*
Y938750D01*
X359000Y926000D01*
X371100D01*
G01X343750Y942300D02*
Y944748D01*
X340300Y948198D01*
Y948500D01*
G01X342500Y952750D02*
Y953000D01*
X348500Y947000D01*
Y942550D01*
X348750Y942300D01*
G01X337300Y949500D02*
X339300D01*
X340300Y948500D01*
G01X347000Y116179D02*
Y120040D01*
G01X360433Y175590D02*
X360471D01*
X362036Y177155D01*
G01X357284Y175590D02*
X357320D01*
X358858Y177128D01*
G01X366733Y175590D02*
X365043Y173900D01*
X358958D01*
X358848Y174010D01*
G01X360433Y191338D02*
Y191375D01*
X358879Y192929D01*
G01X357284Y191338D02*
X355622Y193000D01*
X352839D01*
X351320Y194520D01*
G01X363583Y188189D02*
X363545D01*
X361987Y189747D01*
G01X360433Y194488D02*
X358871Y196050D01*
X358850D01*
G01X357284Y194488D02*
X356262D01*
X355090Y195660D01*
G01X360433Y188189D02*
X359158D01*
X357833Y189514D01*
X355723D01*
X355139Y190099D01*
G01X357284Y188189D02*
X354680D01*
X353759Y189110D01*
X352895D01*
X351731Y190274D01*
G01X352929Y242000D02*
Y235571D01*
X359000Y229500D01*
X364429D01*
X368532Y225397D01*
Y219161D01*
X369358Y218335D01*
X370665D01*
X371707Y217292D01*
Y215986D01*
X372483Y215210D01*
X373617D01*
X373907Y215500D01*
X375146D01*
X376181Y216535D01*
G01X357429Y237500D02*
Y235071D01*
X361500Y231000D01*
X364929D01*
X371606Y224323D01*
Y218812D01*
X373032Y217386D01*
Y216535D01*
G01X361929Y242000D02*
Y235500D01*
X373032Y224397D01*
Y222834D01*
G01X352929Y246750D02*
Y242000D01*
G01X357429Y246750D02*
Y237500D01*
G01X361929Y246750D02*
Y242000D01*
G01X354988Y456325D02*
X361313Y450000D01*
X373555D01*
X378555Y445000D01*
Y435500D01*
G01X356273Y463783D02*
X354302D01*
X352605Y465480D01*
X351555D01*
G01X355273Y478283D02*
X354053Y479503D01*
X349575D01*
G01X355273Y473783D02*
X351402D01*
X349815Y475370D01*
Y475550D01*
G01X355273Y482783D02*
Y486783D01*
G01X347055Y468450D02*
X356185D01*
G01X355273Y486783D02*
X353113Y484623D01*
X350055D01*
G01X350888Y517994D02*
Y501167D01*
X352888Y499167D01*
X358888D01*
X360955Y497100D01*
Y496403D01*
X361155Y496203D01*
G01X358758Y517994D02*
Y513539D01*
X358219Y513000D01*
X356555D01*
G01X354038Y517994D02*
Y508517D01*
X355555Y507000D01*
X357055D01*
G01X352463Y517994D02*
Y505592D01*
X356055Y502000D01*
G01X352463Y540194D02*
Y537000D01*
X352055Y536592D01*
Y532500D01*
X352555Y532000D01*
X358539D01*
X358797Y532258D01*
G01X357183Y517994D02*
Y522372D01*
X355555Y524000D01*
X353055D01*
X353015Y524040D01*
X352095D01*
G01X360333Y540194D02*
Y544333D01*
X362500Y546500D01*
Y565555D01*
X351900Y576155D01*
Y650978D01*
X350000Y652878D01*
G01X361908Y540194D02*
Y535147D01*
X362555Y534500D01*
G01X354038Y540194D02*
Y534017D01*
X354055Y534000D01*
G01X351055Y550500D02*
X352305Y549250D01*
X355055D01*
G01D02*
X355613Y548692D01*
Y540194D01*
G01X366500Y549500D02*
Y564313D01*
X360500Y570313D01*
Y588500D01*
G01X361500Y880500D02*
Y882000D01*
X364480Y884980D01*
X368900D01*
G01X354750Y878500D02*
X359500D01*
X361500Y880500D01*
G01X354750Y884500D02*
X358500D01*
G01X368900Y887540D02*
X362540D01*
X359500Y884500D01*
X358500D01*
G01X354750Y893000D02*
Y889000D01*
G01X360900Y890100D02*
X368900D01*
G01X354750Y889000D02*
X358000D01*
X359100Y890100D01*
X360900D01*
G01X347250Y893000D02*
X349125Y894875D01*
X353625D01*
X354750Y893750D01*
Y893000D01*
G01X351250Y878500D02*
X347250D01*
G01X351250Y884500D02*
X347250D01*
G01X355500Y910750D02*
X356324D01*
X358099Y908975D01*
X360666D01*
X363725Y912034D01*
Y912182D01*
X364998Y913455D01*
X366455D01*
X369000Y916000D01*
X369224D01*
X369341Y916117D01*
G01X351000Y910750D02*
Y910500D01*
X353975Y907525D01*
X363222D01*
X363480Y907783D01*
G01X346500Y910750D02*
Y910500D01*
X351300Y905700D01*
X358106D01*
X359306Y904500D01*
X362000D01*
G01X359500Y910750D02*
X359750D01*
X365000Y916000D01*
X365500D01*
G01X346500Y914250D02*
X348750Y916500D01*
Y921700D01*
G01X351000Y914250D02*
X351250Y914500D01*
Y921700D01*
G01X355500Y914250D02*
X353750Y916000D01*
Y921700D01*
G01X359500Y914250D02*
X356250Y917500D01*
Y921700D01*
G01X369500Y936500D02*
Y937000D01*
X368500Y938000D01*
X360000D01*
X358750Y939250D01*
Y942300D01*
G01X360500Y952750D02*
X358750Y952000D01*
Y942300D01*
G01X356000Y952750D02*
X356250Y953500D01*
Y942300D01*
G01D02*
Y939250D01*
X359000Y936500D01*
X363500D01*
X368000Y932000D01*
G01X351500Y952750D02*
X353750Y951500D01*
Y942300D01*
G01D02*
Y939250D01*
X358500Y934500D01*
X361000D01*
X363000Y932500D01*
Y931500D01*
G01X347000Y952750D02*
X351250Y949500D01*
Y942300D01*
G01D02*
Y939250D01*
X359000Y931500D01*
G01X348750Y942300D02*
Y938750D01*
X358725Y928775D01*
X361298D01*
X361523Y929000D01*
X370000D01*
X371000Y930000D01*
G01X354333Y1008860D02*
Y978850D01*
X354972Y977305D01*
X360753Y971524D01*
X363614D01*
G01X358268Y1008860D02*
Y998647D01*
X360493Y996422D01*
Y994578D01*
X357774Y991859D01*
Y978167D01*
X359147Y976794D01*
X359232Y976588D01*
X359333Y976346D01*
X361000Y974679D01*
Y974000D01*
G01X361178Y982250D02*
Y980308D01*
X360024Y979154D01*
Y979100D01*
G01X361178Y991000D02*
Y985750D01*
G01X362203Y1008860D02*
Y997470D01*
X362443Y997230D01*
Y993265D01*
X361178Y992000D01*
Y991000D01*
G01X369882Y178740D02*
X368429Y177287D01*
X368396D01*
X368312Y177203D01*
X368309D01*
X368308Y177202D01*
G01X374560Y177210D02*
Y177212D01*
X373032Y178740D01*
G01Y175590D02*
Y175628D01*
X371485Y177175D01*
G01X373032Y188189D02*
X374606Y189763D01*
G01X373032Y191338D02*
X374606Y192912D01*
G01X370929Y242000D02*
Y232500D01*
X377929Y225500D01*
Y221087D01*
X379331Y219685D01*
G01X366429Y238000D02*
Y234000D01*
X374429Y226000D01*
Y221437D01*
X376181Y219685D01*
G01X375429Y237500D02*
Y230402D01*
X379331Y226500D01*
Y222834D01*
G01X378429Y242000D02*
Y230252D01*
X380681Y228000D01*
Y217885D01*
X379331Y216535D01*
G01X375429Y246750D02*
Y237500D01*
G01X370929Y246750D02*
Y242000D01*
G01X366429Y246750D02*
Y238000D01*
G01X366600Y285800D02*
X379817D01*
X387304Y278313D01*
Y266396D01*
X390100Y263600D01*
G01X386555Y299250D02*
X378715D01*
X377855Y300110D01*
G01X364805Y371000D02*
Y367838D01*
X367645Y364998D01*
Y363450D01*
X367665Y363430D01*
G01X364805Y380500D02*
X368055D01*
G01X364805Y376000D02*
X368055D01*
X368555Y376500D01*
G01X374000Y392500D02*
X376000D01*
X377625Y390875D01*
X386487D01*
X389387Y393775D01*
X391300D01*
X392075Y393000D01*
X394386D01*
X398308Y389078D01*
Y387912D01*
X402952Y383268D01*
G01X364805Y389500D02*
X368055D01*
X368555Y389000D01*
G01X364805Y394000D02*
X367015D01*
X367613Y393402D01*
X368165D01*
G01X364805Y385000D02*
X368555D01*
G01X387000Y404275D02*
Y402395D01*
X385380Y400775D01*
X382633D01*
X382408Y401000D01*
X369500D01*
G01X365065Y400500D02*
X365565Y401000D01*
X369500D01*
G01X375055Y413000D02*
X370815D01*
X370275Y413540D01*
G01X365055Y414500D02*
X369315D01*
X370275Y413540D01*
G01X378555Y417500D02*
X391000D01*
G01X378525Y403780D02*
X379805Y402500D01*
X383055D01*
X383555Y403000D01*
G01X378555Y413000D02*
X382500D01*
G01X378555Y408500D02*
X384004D01*
X384504Y408000D01*
G01X375025Y403780D02*
X372705D01*
X371555Y404930D01*
Y406380D01*
X371710Y406535D01*
G01X365055Y405270D02*
Y405555D01*
X366035Y406535D01*
X371710D01*
G01X365055Y419000D02*
X365480Y418575D01*
X368480D01*
X369555Y417500D01*
G01D02*
X375055D01*
G01X365055Y410000D02*
X370429D01*
X370524Y409905D01*
X370528D01*
G01X370575Y409952D02*
X370528Y409905D01*
G01X375055Y408500D02*
X374460D01*
X373055Y409905D01*
X370528D01*
G01X378555Y431000D02*
X379055Y430500D01*
X404555D01*
G01X378555Y422000D02*
X380555D01*
X384505Y425950D01*
X403255D01*
G01X378555Y426500D02*
X380655D01*
X382555Y428400D01*
X405555D01*
X405655Y428300D01*
X406555D01*
G01X378555Y435500D02*
X381055Y433000D01*
X405055D01*
X408280Y429775D01*
Y426470D01*
X407132Y425322D01*
Y422881D01*
X406889Y422638D01*
G01X375055Y464000D02*
X371155D01*
X370155Y463000D01*
G01D02*
Y459865D01*
X379383Y450948D01*
X385463D01*
G01X363483Y540194D02*
Y544483D01*
X366500Y547500D01*
Y549500D01*
G01X371500Y873250D02*
Y879500D01*
X373000Y881000D01*
Y883500D01*
X371520Y884980D01*
X368900D01*
G01X371500Y869750D02*
Y867000D01*
X371000Y866500D01*
G01X376000Y873250D02*
Y884000D01*
X372460Y887540D01*
X368900D01*
G01X376000Y869750D02*
Y866082D01*
X376041Y866041D01*
G01X368900Y905460D02*
X374960D01*
X375500Y906000D01*
G01X368900Y902900D02*
X374100D01*
X375500Y901500D01*
G01X368900Y895220D02*
X362780D01*
G01X373000Y915000D02*
X370949D01*
X367954Y912005D01*
X365599D01*
X365175Y911581D01*
Y909325D01*
X366480Y908020D01*
X368900D01*
G01X418250Y922200D02*
Y917500D01*
X417200Y916450D01*
Y910149D01*
X417000Y909949D01*
Y909900D01*
X414550Y907450D01*
X403499D01*
X396899Y914050D01*
X387550D01*
X381520Y908020D01*
X368900D01*
G01X417323Y1008860D02*
Y997323D01*
X406500Y986500D01*
Y977500D01*
X391500Y962500D01*
X386500D01*
X374500Y950500D01*
Y929400D01*
X371100Y926000D01*
G01X380000Y922250D02*
X375500D01*
G01D02*
Y926500D01*
X376500Y927500D01*
X377000D01*
G01X380500Y915000D02*
X378000Y912500D01*
X370500D01*
X368900Y910900D01*
Y910580D01*
G01X415750Y922200D02*
Y910750D01*
X413900Y908900D01*
X404100D01*
X397500Y915500D01*
X386500D01*
X381580Y910580D01*
X368900D01*
G01X380000Y918750D02*
Y918500D01*
X376500Y915000D01*
X373000D01*
G01X407250Y915500D02*
X405750Y917000D01*
X404000D01*
X402525Y918475D01*
X392249D01*
X389862Y920862D01*
Y928638D01*
X386000Y932500D01*
X383275D01*
X377775Y938000D01*
Y948466D01*
X388809Y959500D01*
X392602D01*
X410000Y976898D01*
Y983500D01*
G01X413388Y1008860D02*
Y995888D01*
X404500Y987000D01*
Y978000D01*
X390500Y964000D01*
X385500D01*
X373000Y951500D01*
Y931000D01*
X372000Y930000D01*
X371000D01*
G01X407250Y911500D02*
X406000D01*
X402500Y915000D01*
X401000D01*
X399000Y917000D01*
X391500D01*
X388000Y920500D01*
Y925325D01*
X376325Y937000D01*
Y949067D01*
X388258Y961000D01*
X392051D01*
X408000Y976949D01*
Y984223D01*
X409202Y985425D01*
X411075D01*
X413000Y983500D01*
X413600D01*
G01X409448Y1008860D02*
Y994448D01*
X403000Y988000D01*
Y979000D01*
X389500Y965500D01*
X384500D01*
X379500Y960500D01*
X376500D01*
X376000Y960000D01*
G01X366143Y1008860D02*
Y982535D01*
X368426Y980252D01*
X369200D01*
G01X370078Y1008860D02*
Y982134D01*
X371150Y981061D01*
Y979268D01*
X372500Y977918D01*
G01X377250Y982250D02*
X373678D01*
G01X384500Y243000D02*
X383831Y242331D01*
Y221035D01*
X382481Y219685D01*
G01X400000Y237500D02*
Y236500D01*
X396150Y232650D01*
Y226743D01*
X396404Y226489D01*
Y222285D01*
X395079Y220960D01*
Y219685D01*
G01X391929D02*
Y220474D01*
X393429Y221974D01*
Y229500D01*
G01X390988Y247550D02*
Y243512D01*
X394000Y240500D01*
Y238500D01*
X395500Y237000D01*
G01X397500Y249000D02*
Y248611D01*
X397654Y248457D01*
Y248129D01*
X397655Y248128D01*
Y239155D01*
X395500Y237000D01*
G01X381429Y237500D02*
Y230604D01*
X382481Y229552D01*
Y222834D01*
G01X386500Y237500D02*
X385630Y236630D01*
Y222834D01*
G01X399500Y240500D02*
Y239299D01*
X398375Y238174D01*
Y236875D01*
X395154Y233654D01*
Y222909D01*
X395079Y222834D01*
G01X379929Y246750D02*
X381429Y245250D01*
Y237500D01*
G01X385870Y247550D02*
Y244370D01*
X384500Y243000D01*
G01X388429Y256450D02*
Y260071D01*
X387500Y261000D01*
G01X386555Y302750D02*
X384055Y305250D01*
Y311500D01*
G01X391055Y302750D02*
X388055Y305750D01*
Y307500D01*
G01X395555Y302750D02*
X392555Y305750D01*
Y309500D01*
G01X402800Y282700D02*
X395200Y290300D01*
Y290960D01*
X395104Y291056D01*
G01X384055Y311500D02*
Y312500D01*
X389500Y317945D01*
Y319150D01*
G01X388055Y307500D02*
Y310900D01*
X391500Y314345D01*
Y316363D01*
X392000Y316863D01*
Y317140D01*
X392589Y317729D01*
G01X379305Y312500D02*
Y317000D01*
G01X384055D02*
Y317250D01*
X391325Y324520D01*
G01X379305Y317000D02*
X384055D01*
G01X392555Y309500D02*
X398055Y315000D01*
Y319315D01*
X406889Y328149D01*
G01X394055Y335000D02*
X393055Y336000D01*
X390555D01*
X387055Y339500D01*
X384055D01*
G01X386755Y326100D02*
Y325755D01*
X384000Y323000D01*
G01X379305Y321500D02*
X382500D01*
X384000Y323000D01*
G01X386555Y333000D02*
X385555Y332000D01*
X382585D01*
X382455Y331870D01*
G01X379305Y335000D02*
X379325D01*
X382455Y331870D01*
G01X379305Y330500D02*
Y326000D01*
G01X388829Y328323D02*
X388152Y329000D01*
X384348D01*
X384160Y328812D01*
G01X379305Y326000D02*
X380266D01*
X380449Y326183D01*
X381531D01*
X384160Y328812D01*
G01X384055Y339500D02*
X379305D01*
G01Y344000D02*
X385905D01*
X391555Y338350D01*
G01X406889Y347834D02*
X405109D01*
X403584Y346309D01*
X402320D01*
X401858Y346771D01*
X396593D01*
X396564Y346800D01*
X393061D01*
G01X406889Y351771D02*
X405086Y349968D01*
X401423D01*
X400126Y348671D01*
X397381D01*
X395552Y350500D01*
X393755D01*
G01X402952Y347834D02*
X402839Y347721D01*
X396987D01*
X396033Y348675D01*
X392998D01*
X392346Y349327D01*
X390230D01*
G01X383555Y353000D02*
X393409Y343146D01*
X400055D01*
G01X379305Y348500D02*
X384055D01*
X385055Y347500D01*
G01D02*
X386555Y346000D01*
X388055D01*
X396055Y338000D01*
G01X379305Y375500D02*
X383447D01*
X392991Y365956D01*
Y365797D01*
G01X406889Y363582D02*
X405737D01*
X403605Y361450D01*
X401870D01*
X401245Y360825D01*
X398122D01*
X393150Y365797D01*
X392991D01*
G01X406889Y359645D02*
X405144Y357900D01*
X400330D01*
X399880Y357450D01*
Y356394D01*
X399430Y355944D01*
X398530D01*
X398080Y356394D01*
Y357450D01*
X397630Y357900D01*
X396730D01*
X396280Y357450D01*
Y356394D01*
X395830Y355944D01*
X394930D01*
X394480Y356394D01*
Y357450D01*
X394030Y357900D01*
X392580D01*
X391628Y358852D01*
G01X379305Y362000D02*
X383175D01*
X391055Y354120D01*
X400885D01*
G01X402952Y359645D02*
X395270D01*
X395190Y359725D01*
X394915D01*
G01X379305Y357500D02*
Y353000D01*
G01D02*
X383555D01*
G01X379305Y366500D02*
Y371000D01*
G01X384055D02*
X387515Y367540D01*
Y365500D01*
G01X406889Y375394D02*
X405145D01*
X403620Y373869D01*
X397766D01*
X395654Y375981D01*
X393543D01*
X387640Y381884D01*
Y383995D01*
X387265Y384370D01*
G01X402952Y379331D02*
X400665D01*
X394935Y385061D01*
Y385150D01*
G01X402952Y375394D02*
X400915Y377431D01*
X394144D01*
X389090Y382485D01*
Y385127D01*
X388022Y386195D01*
X386441D01*
X385904Y385658D01*
X383254D01*
X382803Y385207D01*
G01X406889Y379331D02*
X405386D01*
X403861Y377806D01*
X402320D01*
X401745Y378381D01*
X400271D01*
X396037Y382615D01*
X393558D01*
X391273Y384900D01*
X391215D01*
G01X379305Y371000D02*
X384055D01*
G01X380500Y393000D02*
X386561D01*
X388786Y395225D01*
X394165D01*
X399258Y390132D01*
Y388742D01*
X402320Y385680D01*
X403945D01*
X406357Y383268D01*
X406889D01*
G01X383555Y403000D02*
Y403555D01*
X386100Y406100D01*
X387756D01*
X388825Y405031D01*
Y401325D01*
X388500Y401000D01*
Y400575D01*
G01X380273Y387783D02*
X385023D01*
G01D02*
X385446D01*
X389695Y392032D01*
X390231D01*
X390313Y391950D01*
X390543D01*
G01X388023Y412283D02*
X389479Y410827D01*
X402952D01*
G01X391000Y417500D02*
X393055D01*
X397416Y413139D01*
X404576D01*
X406889Y410827D01*
G01X382500Y413000D02*
X383055D01*
X387055Y409000D01*
X404779D01*
X406889Y406890D01*
G01X402952D02*
X402292Y407550D01*
X385454D01*
X385004Y408000D01*
X384504D01*
G01X393055Y447400D02*
X390555Y449899D01*
Y455500D01*
G01X386055Y454500D02*
X387555Y456000D01*
Y459700D01*
G01X380555Y464000D02*
X382855Y461700D01*
X385555D01*
X387555Y459700D01*
G01X391555Y464000D02*
X393155D01*
X394155Y463000D01*
Y460000D01*
G01D02*
Y457323D01*
X394130Y457298D01*
Y455702D01*
X394155Y455677D01*
Y452000D01*
X393155Y451000D01*
X393055D01*
G01X386055Y464000D02*
X388379D01*
X390555Y461824D01*
Y455500D01*
G01X398000Y873750D02*
X393500D01*
G01X391100Y884980D02*
X393520D01*
X395500Y883000D01*
Y878000D01*
X395000Y877500D01*
G01X393500Y873750D02*
Y876000D01*
X395000Y877500D01*
G01X384500Y873750D02*
X389000D01*
G01X391100Y882420D02*
Y879600D01*
X389000Y877500D01*
G01Y873750D02*
Y877500D01*
G01X391100Y887540D02*
X393460D01*
X396000Y885000D01*
X398000D01*
G01X391100Y890100D02*
X394900D01*
X396500Y888500D01*
G01X391100Y892660D02*
X396940D01*
X397600Y892000D01*
G01X391100Y895220D02*
X395965D01*
X396600Y895855D01*
G01X391100Y897780D02*
X394405D01*
X396330Y899705D01*
G01X391100Y900340D02*
X394242D01*
X395532Y901630D01*
X399370D01*
X399500Y901500D01*
G01X391100Y902900D02*
X394400D01*
X395500Y904000D01*
X396500D01*
G01X391100Y905460D02*
X394460D01*
X395000Y906000D01*
X397353D01*
X397578Y905775D01*
X400174D01*
X402174Y903775D01*
X407500D01*
G01X391100Y908020D02*
X398480D01*
X398500Y908000D01*
G01X384000Y922250D02*
Y926500D01*
G01Y918750D02*
Y918500D01*
X380500Y915000D01*
G01X392000Y955250D02*
X388500D01*
G01X388750Y951750D02*
X392000D01*
G01D02*
X395750Y948000D01*
Y942800D01*
G01X405513Y1008860D02*
Y993013D01*
X401500Y989000D01*
Y980000D01*
X388500Y967000D01*
X383000D01*
X379500Y963500D01*
G01X381888Y1008860D02*
Y991234D01*
X387061Y986061D01*
G01X385828Y1008860D02*
Y995672D01*
X389500Y992000D01*
G01X425000Y245500D02*
X423175Y243675D01*
X417581D01*
X417081Y243175D01*
X416175D01*
X406352Y233352D01*
Y221577D01*
X407677Y220252D01*
Y219685D01*
G01X410400Y242116D02*
Y241400D01*
X403203Y234203D01*
Y217860D01*
X404528Y216535D01*
G01Y219685D02*
X405767D01*
X407092Y218360D01*
X408226D01*
X409429Y219563D01*
Y233741D01*
X415497Y239809D01*
X419014D01*
X419205Y240000D01*
G01X407677Y216535D02*
Y216528D01*
X406099Y214950D01*
G01X410827Y219685D02*
Y219898D01*
X412429Y221500D01*
Y229529D01*
X417925Y235025D01*
Y235568D01*
X420407Y238050D01*
X420444D01*
X422203Y239809D01*
X427411D01*
X432102Y244500D01*
X434000D01*
G01X410827Y216535D02*
Y216486D01*
X410327Y215986D01*
X410270D01*
X409249Y214965D01*
G01X404528Y222834D02*
Y232928D01*
X413714Y242114D01*
Y242814D01*
X416200Y245300D01*
G01X410827Y222834D02*
Y231222D01*
X412767Y233162D01*
G01X407677Y222834D02*
Y233333D01*
X415103Y240759D01*
X416683D01*
X417649Y241725D01*
X417682D01*
X418182Y242225D01*
X424872D01*
X429429Y246782D01*
Y252900D01*
G01X396929Y253750D02*
Y249571D01*
X397500Y249000D01*
G01X410400Y242116D02*
Y242300D01*
X412654Y244554D01*
Y245254D01*
X415704Y248304D01*
Y254451D01*
X415454Y254701D01*
Y256099D01*
X415704Y256349D01*
Y262451D01*
X415280Y262875D01*
X414875D01*
X412500Y265250D01*
G01X420429Y261150D02*
Y264571D01*
X411000Y274000D01*
X410500D01*
X403500Y281000D01*
Y282000D01*
X402800Y282700D01*
G01X421250Y268000D02*
X420525Y268725D01*
X418850D01*
X406004Y281571D01*
Y288848D01*
X408656Y291500D01*
G01X405555Y302750D02*
Y307000D01*
X406055Y307500D01*
G01X409555Y302750D02*
X410555Y303578D01*
X411555Y304578D01*
Y309500D01*
G01X401855Y293500D02*
X399755Y295600D01*
Y295700D01*
G01X400555Y299250D02*
X399755Y298450D01*
Y295700D01*
G01X400555Y302750D02*
Y308500D01*
X401555Y309500D01*
G01X408656Y291500D02*
X409155Y291999D01*
Y295345D01*
X409000Y295500D01*
G01X409555Y299250D02*
X409000Y298695D01*
Y295500D01*
G01X405555Y299250D02*
Y293500D01*
G01X404000Y290500D02*
Y291945D01*
X405555Y293500D01*
G01X406055Y307500D02*
Y311828D01*
X407876Y313649D01*
Y317344D01*
X409055Y318523D01*
Y326378D01*
X410826Y328149D01*
G01X411555Y309500D02*
Y313850D01*
X411044Y314361D01*
Y323994D01*
X410826Y324212D01*
G01X397055Y307500D02*
Y310500D01*
X403476Y316921D01*
Y320799D01*
X406889Y324212D01*
G01X401555Y309500D02*
Y311500D01*
X404926Y314871D01*
Y318871D01*
X406555Y320500D01*
G01X410826Y336023D02*
X408857Y334054D01*
G01X402952Y336023D02*
X400983Y334054D01*
G01X406889Y339960D02*
X404487Y337558D01*
X401543D01*
X397983Y333998D01*
G01X410826Y332086D02*
X408857Y330117D01*
G01X402952Y328149D02*
Y327712D01*
X400523Y325283D01*
G01X402952Y343897D02*
X401028Y345821D01*
X398230D01*
X397555Y345146D01*
G01X402952Y351771D02*
X402681Y351500D01*
X399259D01*
X398055Y350296D01*
G01X402952Y339960D02*
X402275Y339283D01*
X398555D01*
G01X410826Y347834D02*
X408857Y345865D01*
G01X406889Y343897D02*
X406752D01*
X404965Y342110D01*
Y342120D01*
G01X402952Y367519D02*
X396484D01*
X395855Y366890D01*
G01X406889Y367519D02*
X405232Y365862D01*
X398317D01*
X397155Y364700D01*
Y364176D01*
X397117Y364138D01*
G01X410826Y363582D02*
X409035Y361791D01*
Y361790D01*
X408925Y361680D01*
G01X402952Y363582D02*
X401820Y362450D01*
X400395D01*
G01X402952Y355708D02*
X402473D01*
X400885Y354120D01*
G01X406889Y355708D02*
X405021Y353840D01*
X404935D01*
G01X410826Y355708D02*
X408857Y353739D01*
G01X402952Y371456D02*
X400467D01*
X399923Y372000D01*
G01X406889Y371456D02*
X404920Y369487D01*
G01X410826Y379331D02*
X408438Y381718D01*
X402345D01*
X396561Y387502D01*
Y388526D01*
X396490Y388597D01*
G01X410826Y371456D02*
X408857Y369487D01*
G01X410826Y387205D02*
X408857Y389174D01*
G01X402952Y399016D02*
X400983Y400985D01*
G01X406889Y395079D02*
X404920Y397048D01*
G01X406889Y399016D02*
X404920Y400985D01*
G01X406889Y387205D02*
X404920Y389174D01*
G01X410826Y395079D02*
X408857Y397048D01*
G01X402952Y395079D02*
X400983Y397048D01*
G01X406889Y391142D02*
X404920Y393111D01*
G01X402952Y402953D02*
X400983Y404922D01*
G01X406889Y402953D02*
X404920Y404922D01*
G01X410826Y402953D02*
X408857Y404922D01*
G01X410826Y410827D02*
X408857Y412796D01*
G01X406889Y414764D02*
X404920Y416733D01*
G01X402952Y414764D02*
Y415103D01*
X401322Y416733D01*
X400983D01*
G01X410826Y418701D02*
X408857Y420670D01*
G01X406889Y418701D02*
Y419166D01*
X405385Y420670D01*
X404920D01*
G01X402952Y418701D02*
Y425647D01*
X403255Y425950D01*
G01X402250Y880500D02*
Y885000D01*
G01D02*
X398000D01*
G01X395750Y922200D02*
Y930450D01*
X401375Y936075D01*
X425958D01*
X433325Y928708D01*
Y908213D01*
X413612Y888500D01*
X396500D01*
G01X398250Y922200D02*
Y930250D01*
X402625Y934625D01*
X425357D01*
X431875Y928107D01*
Y908814D01*
X413561Y890500D01*
X399342D01*
X397821Y892021D01*
X397621D01*
X397600Y892000D01*
G01X411500Y893000D02*
X400000D01*
X397780Y895220D01*
X397235D01*
X396600Y895855D01*
G01X400750Y922200D02*
Y928850D01*
X405075Y933175D01*
X424756D01*
X430425Y927506D01*
Y909415D01*
X414010Y893000D01*
X411500D01*
G01X396330Y899705D02*
X400535Y895500D01*
X406000D01*
G01X403250Y922200D02*
Y925901D01*
X409074Y931725D01*
X424155D01*
X428975Y926905D01*
Y910016D01*
X414459Y895500D01*
X406000D01*
G01X411000Y898500D02*
X402500D01*
X399500Y901500D01*
G01X405750Y922200D02*
Y926350D01*
X409675Y930275D01*
X423554D01*
X427525Y926304D01*
Y910617D01*
X415408Y898500D01*
X411000D01*
G01X408250Y922200D02*
Y926700D01*
X410375Y928825D01*
X422953D01*
X426075Y925703D01*
Y912821D01*
X414254Y901000D01*
X402723D01*
X399723Y904000D01*
X396500D01*
G01X410750Y922200D02*
Y926200D01*
X411925Y927375D01*
X422352D01*
X424625Y925102D01*
Y913423D01*
X414977Y903775D01*
X407500D01*
G01X413250Y922200D02*
Y925250D01*
X413925Y925925D01*
X421751D01*
X423175Y924501D01*
Y914024D01*
X415151Y906000D01*
X402000D01*
X400298Y907702D01*
X398798D01*
X398500Y908000D01*
G01X410750Y915500D02*
Y922200D01*
G01Y911500D02*
X413000Y913750D01*
Y921950D01*
X413250Y922200D01*
G01X403250Y942800D02*
Y949000D01*
G01X410750Y942800D02*
Y948624D01*
X414215Y952089D01*
G01X408250Y949500D02*
Y942800D01*
G01X405750D02*
Y952000D01*
X405704Y952046D01*
G01X398250Y955000D02*
Y942800D01*
G01X400750Y952000D02*
Y942800D01*
G01X403250Y949000D02*
Y957250D01*
X405546Y959546D01*
X416046D01*
G01X410500Y954500D02*
X410250D01*
X408250Y952500D01*
Y949500D01*
G01X405704Y952046D02*
X405750Y952092D01*
Y954250D01*
X408500Y957000D01*
X413500D01*
G01X416000Y964000D02*
X415000Y965000D01*
X403000D01*
X398250Y960250D01*
Y955000D01*
G01X420000Y964000D02*
X418000Y962000D01*
X403500D01*
X400750Y959250D01*
Y952000D01*
G01X410000Y983500D02*
X415500Y978000D01*
Y971500D01*
X421925Y965075D01*
Y957076D01*
X414500Y949651D01*
Y948500D01*
G01X410500Y987500D02*
X412500D01*
X418500Y981500D01*
Y975102D01*
X424825Y968777D01*
Y954825D01*
X418500Y948500D01*
G01X417126Y134645D02*
X415801Y133320D01*
Y122739D01*
X421040Y117500D01*
Y112779D01*
X432269Y101550D01*
X432579D01*
X433929Y100200D01*
Y100000D01*
G01X426575Y131496D02*
X426200Y131121D01*
Y127379D01*
X426286Y127293D01*
Y124362D01*
X425725Y123801D01*
Y120086D01*
X430811Y115000D01*
X440000D01*
G01X427000Y111000D02*
X424870D01*
X422040Y113830D01*
Y117915D01*
X417126Y122829D01*
Y131496D01*
G01X442290Y106000D02*
X439290Y103000D01*
X432870D01*
X428185Y107685D01*
Y109815D01*
X427000Y111000D01*
G01X420276Y131496D02*
X419965Y131185D01*
Y126309D01*
X420590Y125684D01*
Y121119D01*
X423000Y118709D01*
Y117500D01*
X424500Y116000D01*
G01X434540Y109750D02*
X432815Y111475D01*
X430025D01*
X427500Y114000D01*
X426500D01*
X424500Y116000D01*
G01X423500Y122000D02*
Y122920D01*
X425336Y124756D01*
Y126899D01*
X425250Y126985D01*
Y132810D01*
X426575Y134135D01*
Y134645D01*
G01X442290Y110000D02*
X442101D01*
X439176Y112925D01*
X430835D01*
X423500Y120260D01*
Y122000D01*
G01X431790Y117500D02*
X430610D01*
X428375Y119735D01*
G01D02*
Y122635D01*
G01X420276Y134645D02*
Y133547D01*
X418826Y132097D01*
Y130895D01*
X418940Y130781D01*
Y125000D01*
G01X417126Y137795D02*
X415552Y136221D01*
G01X423425Y134645D02*
Y134085D01*
X421626Y132286D01*
Y130936D01*
X421590Y130900D01*
Y128500D01*
G01X420276Y137795D02*
X418702Y136221D01*
G01X428375Y122635D02*
Y132197D01*
X429725Y133547D01*
Y134645D01*
G01X426575Y137795D02*
X425000Y136220D01*
G01X428116Y136218D02*
X428151Y136253D01*
Y136411D01*
X429535Y137795D01*
X429725D01*
G01X423425D02*
X421851Y136221D01*
G01X423425Y131496D02*
Y126476D01*
X423686Y126215D01*
G01X417126Y147244D02*
X418700Y148818D01*
G01X426575Y147244D02*
X428149Y148818D01*
G01X413977Y147244D02*
X415551Y148818D01*
G01X423425Y147244D02*
X424999Y148818D01*
G01X420276Y147244D02*
X421850Y148818D01*
G01X423425Y216535D02*
X423463D01*
X424909Y217981D01*
Y218057D01*
X424979Y218127D01*
G01X426147Y230982D02*
X426500Y230629D01*
Y227273D01*
X426504Y227269D01*
Y224932D01*
X426500Y224928D01*
Y224633D01*
X425225Y223358D01*
Y222296D01*
X423425Y220496D01*
Y219685D01*
G01X420714Y225190D02*
X421601Y224303D01*
Y221010D01*
X420276Y219685D01*
G01X426575Y216535D02*
X428028Y217988D01*
Y218030D01*
X428047Y218049D01*
G01X413977Y216535D02*
X415551Y218109D01*
G01X417126Y216535D02*
X418691Y218100D01*
X418729D01*
G01X417970Y231884D02*
X414704Y228618D01*
Y227296D01*
X415302Y226698D01*
Y221047D01*
X413977Y219722D01*
Y219685D01*
G01X420276Y216535D02*
X421850Y218109D01*
G01X418729Y221268D02*
X418709D01*
X417126Y219685D01*
G01X415100Y235900D02*
Y235495D01*
X412767Y233162D01*
G01X428172Y221320D02*
X429686Y222834D01*
X429725D01*
G01X423425D02*
Y225475D01*
X422630Y226270D01*
Y227232D01*
G01X429250Y236500D02*
Y235750D01*
X426500Y233000D01*
X425500D01*
X424500Y232000D01*
Y229200D01*
X422630Y227330D01*
Y227232D01*
G01X420276Y222834D02*
X418500Y224610D01*
Y226905D01*
X419000Y227405D01*
G01X438750Y244000D02*
X436506D01*
X433931Y241425D01*
X430875D01*
X428309Y238859D01*
X424359D01*
X422600Y237100D01*
X420801D01*
X418875Y235174D01*
Y233375D01*
X417970Y232470D01*
Y231884D01*
G01X424929Y257650D02*
Y253150D01*
G01D02*
X425284D01*
X427654Y250780D01*
Y248154D01*
X425000Y245500D01*
G01X420429Y257650D02*
Y253150D01*
G01D02*
X417704Y250425D01*
Y246804D01*
X416200Y245300D01*
G01X419205Y240000D02*
X419600D01*
X420359Y240759D01*
X425457D01*
X430879Y246181D01*
Y249356D01*
X433929Y252406D01*
Y257650D01*
G01X424750Y268000D02*
X426500D01*
X426925Y268425D01*
X429800D01*
X431725Y266500D01*
X434452D01*
X436654Y264298D01*
Y252654D01*
X434000Y250000D01*
Y244500D01*
G01X429429Y261150D02*
Y265500D01*
X428429Y266500D01*
X428100D01*
G01X426505Y287200D02*
Y283200D01*
G01D02*
X428525Y281180D01*
X433765D01*
G01X427555Y291750D02*
X428493Y290812D01*
Y285507D01*
X430260Y283740D01*
X433765D01*
G01X426505Y275200D02*
Y279200D01*
G01Y275200D02*
X426555Y275150D01*
Y271500D01*
G01X426505Y279200D02*
X427441D01*
X428021Y278620D01*
X433765D01*
G01X414763Y324212D02*
Y316865D01*
X415955Y315673D01*
Y310651D01*
X416981Y309625D01*
X417436D01*
X418680Y308381D01*
Y305801D01*
X422481Y302000D01*
X427555D01*
X432055Y297500D01*
X433500D01*
G01X418555Y302750D02*
X414055D01*
G01D02*
X415555Y306500D01*
X416555Y307500D01*
G01X418555Y299250D02*
X416187Y295382D01*
Y294711D01*
G01X426505Y287200D02*
Y287250D01*
X423880Y289875D01*
X421554D01*
X421429Y290000D01*
X418755D01*
G01X426470Y299463D02*
X424880Y297873D01*
Y295575D01*
X423055Y293750D01*
G01D02*
X425055Y291750D01*
X427555D01*
G01X430511Y328149D02*
X428224Y325862D01*
Y318552D01*
X427965Y318293D01*
G01X416555Y307500D02*
Y308000D01*
X414505Y310050D01*
Y315072D01*
X413238Y316339D01*
Y325021D01*
X414763Y326546D01*
Y328149D01*
G01X419913Y318051D02*
X420314D01*
X420432Y317933D01*
X421773D01*
X422273Y318433D01*
Y323848D01*
X422637Y324212D01*
G01X417650Y316400D02*
Y316658D01*
X417629Y316679D01*
Y317870D01*
X418107Y318348D01*
Y319003D01*
X420523Y321419D01*
Y326035D01*
X422637Y328149D01*
G01X418700Y324212D02*
Y321235D01*
X418575Y321110D01*
Y321109D01*
X417624Y320158D01*
X417623D01*
X416487Y319022D01*
X416482D01*
G01X426574Y324212D02*
X425773Y323411D01*
Y319033D01*
X424740Y318000D01*
X424555D01*
G01X425755Y309800D02*
Y311255D01*
X428050Y313550D01*
X430933D01*
X438385Y321002D01*
Y324212D01*
G01X432500Y301000D02*
X430000Y303500D01*
X428000D01*
X423000Y308500D01*
Y312045D01*
X425455Y314500D01*
X430539D01*
X436523Y320484D01*
Y326283D01*
X438385Y328145D01*
Y328149D01*
G01X426574D02*
X424187Y325762D01*
Y323569D01*
X424023Y323405D01*
Y320783D01*
G01X426574Y336023D02*
X424605Y334054D01*
G01X426574Y332086D02*
X424605Y330117D01*
G01X418700Y332086D02*
X416731Y330117D01*
G01X418700Y328149D02*
X417023Y326472D01*
Y321856D01*
X416950Y321783D01*
G01X418700Y336023D02*
X416731Y334054D01*
G01X422637Y339960D02*
X420668Y337991D01*
G01X426574Y339960D02*
X424605Y337991D01*
G01X414763Y339960D02*
X412794Y337991D01*
G01X422637Y343897D02*
X420668Y341928D01*
G01X426574Y351771D02*
X424605Y349802D01*
G01X422637Y351771D02*
X420668Y349802D01*
G01X418700Y339960D02*
X416731Y337991D01*
G01X422637Y347834D02*
X420668Y345865D01*
G01X418700Y343897D02*
X416731Y341928D01*
G01X426574Y343897D02*
X424605Y341928D01*
G01X422637Y359645D02*
X420668Y357676D01*
G01X414763Y355708D02*
X412794Y353739D01*
G01X420668D02*
X422637Y355708D01*
G01X414763Y363582D02*
X412794Y361613D01*
G01X418700Y367519D02*
X416731Y365550D01*
G01X426574Y367519D02*
X424605Y365550D01*
G01X422637Y367519D02*
X420668Y365550D01*
G01X418700Y363582D02*
X416731Y361613D01*
G01X426574Y359645D02*
X424605Y357676D01*
G01X422637Y363582D02*
X420668Y361613D01*
G01X416555Y357500D02*
X418700Y359645D01*
G01X414763Y379331D02*
X412794Y381300D01*
G01X430511Y375394D02*
X430106D01*
X428500Y377000D01*
G01X418700Y379331D02*
X416731Y381300D01*
G01X418700Y375394D02*
X416731Y377363D01*
G01X426574Y375394D02*
X426601D01*
X428445Y373550D01*
G01X418700Y371456D02*
X416731Y369487D01*
G01X422637Y375394D02*
X420668Y377363D01*
G01X422637Y371456D02*
X420668Y369487D01*
G01X414763Y371456D02*
X412794Y369487D01*
G01X422637Y383268D02*
X421168D01*
X420668Y383768D01*
Y385237D01*
G01X418700Y383268D02*
X416731Y385237D01*
G01X426574Y379331D02*
X424605Y381300D01*
G01X422637Y379331D02*
X420668Y381300D01*
G01X418700Y387205D02*
X416731Y389174D01*
G01X414763Y395079D02*
X412794Y397048D01*
G01X422637Y387205D02*
X420668Y389174D01*
G01X418700Y391142D02*
X416731Y393111D01*
G01X418700Y395079D02*
X416731Y397048D01*
G01X422637Y391142D02*
X420668Y393111D01*
G01X426574Y395079D02*
X424605Y397048D01*
G01X422637Y395079D02*
X420668Y397048D01*
G01X418700Y399016D02*
X416731Y400985D01*
G01X426574Y387205D02*
X424605Y389174D01*
G01X414763Y387205D02*
X412794Y389174D01*
G01X418700Y410827D02*
Y411355D01*
X417259Y412796D01*
X416731D01*
G01X414763Y410827D02*
Y411292D01*
X413259Y412796D01*
X412794D01*
G01X414763Y402953D02*
X412794Y404922D01*
G01X414763Y418701D02*
X412794Y420670D01*
G01X413250Y942800D02*
Y947250D01*
X414500Y948500D01*
G01X420750Y942800D02*
Y947250D01*
X422075Y948575D01*
Y948607D01*
X422098Y948630D01*
G01X427250Y945500D02*
X425500D01*
X424000Y944000D01*
Y941324D01*
X421751Y939075D01*
X418925D01*
X418250Y939750D01*
Y942800D01*
G01D02*
Y948250D01*
X418500Y948500D01*
G01X413600Y983500D02*
Y982900D01*
X417000Y979500D01*
Y972500D01*
X423375Y966125D01*
Y956475D01*
X416425Y949525D01*
Y946925D01*
X415750Y946250D01*
Y942800D01*
G01X427250Y941500D02*
X423275Y937525D01*
X417475D01*
X415750Y939250D01*
Y942800D01*
G01X421258Y1008860D02*
Y979242D01*
X426450Y974050D01*
Y952950D01*
X422130Y948630D01*
X422098D01*
G01X438429Y100500D02*
X434429D01*
X433929Y100000D01*
G01X446500Y120500D02*
X434506D01*
X433630Y121375D01*
X431866D01*
X430915Y122326D01*
Y124044D01*
X430674Y124285D01*
Y124286D01*
X429723Y125237D01*
Y125283D01*
X429690Y125316D01*
Y126684D01*
X429725Y126719D01*
Y131496D01*
G01X446250Y114500D02*
X440500D01*
X440000Y115000D01*
G01X446250Y106000D02*
X442290D01*
G01X446250Y110000D02*
X442290D01*
G01X432874Y131496D02*
Y126800D01*
X432990Y126684D01*
Y126603D01*
X432998Y126595D01*
Y125227D01*
X432874Y125103D01*
Y123334D01*
X432540Y123000D01*
G01X439173Y137795D02*
X437599Y136221D01*
G01X436024Y137795D02*
X434450Y136221D01*
G01X463000Y117500D02*
X460500Y120000D01*
Y120500D01*
X458125Y122875D01*
X438866D01*
X436024Y125717D01*
Y131496D01*
G01X439173D02*
Y128835D01*
X439281Y128727D01*
Y128377D01*
X440040Y127618D01*
Y125000D01*
X439540Y124500D01*
G01X432874Y137795D02*
X431438Y136359D01*
Y136316D01*
X431407Y136285D01*
G01X442323Y134645D02*
Y134483D01*
X440623Y132783D01*
Y129917D01*
X440931Y129609D01*
Y129061D01*
G01X432874Y134645D02*
Y134034D01*
X431340Y132500D01*
Y125919D01*
X431348Y125911D01*
G01X436024Y134645D02*
Y133984D01*
X434674Y132634D01*
Y125366D01*
X435040Y125000D01*
Y123600D01*
X435640Y123000D01*
G01X445473Y134645D02*
Y134533D01*
X444023Y133083D01*
Y130612D01*
X446705Y127930D01*
X447249D01*
X448669Y126510D01*
G01X442323Y137795D02*
X443280D01*
X444830Y136245D01*
X445924D01*
X447023Y135146D01*
Y134193D01*
X450209Y131007D01*
Y129230D01*
G01X442323Y131496D02*
Y130003D01*
X442581Y129745D01*
Y128377D01*
X442323Y128119D01*
Y126000D01*
G01X439173Y134645D02*
Y134633D01*
X437723Y133183D01*
Y130895D01*
X437740Y130878D01*
Y128066D01*
X437945Y127861D01*
Y127159D01*
G01X440765Y145670D02*
Y142499D01*
X440914Y142350D01*
Y142317D01*
X442286Y140945D01*
X442323D01*
G01Y150393D02*
X443905Y148811D01*
X443928D01*
G01X442323Y153543D02*
X442346D01*
X443890Y151999D01*
X443891D01*
G01X442323Y144094D02*
X442361D01*
X443890Y142565D01*
G01X442323Y147244D02*
Y147236D01*
X443909Y145650D01*
G01X442323Y156693D02*
X443886Y155130D01*
X443924D01*
X443936Y155118D01*
G01X442323Y162992D02*
X443885Y161430D01*
X443899D01*
G01X442323Y169291D02*
X442325D01*
X443879Y167737D01*
X443882D01*
G01X442323Y166141D02*
Y166106D01*
X443899Y164530D01*
G01X442323Y159842D02*
Y159826D01*
X443871Y158278D01*
G01X442323Y172441D02*
X443910Y174028D01*
Y174041D01*
G01X442323Y178740D02*
Y178764D01*
X443879Y180320D01*
G01X442323Y175590D02*
X442339D01*
X443887Y177138D01*
G01X442323Y185039D02*
Y185034D01*
X440769Y183480D01*
G01X442323Y181889D02*
Y181894D01*
X443909Y183480D01*
X443919D01*
G01X442323Y194488D02*
X443897Y192914D01*
G01X442323Y200787D02*
X443898Y199212D01*
G01X442323Y203937D02*
X443897Y202363D01*
G01X442323Y197637D02*
X443897Y196063D01*
G01X442323Y207086D02*
X443897Y205512D01*
G01X442323Y213385D02*
X443897Y211811D01*
G01X442323Y210236D02*
X443897Y208662D01*
G01X434334Y226789D02*
Y226616D01*
X434524Y226426D01*
Y221405D01*
X436024Y219905D01*
Y219685D01*
G01X442323D02*
Y220673D01*
X443748Y222098D01*
Y225704D01*
X443113Y226339D01*
G01X439980Y232126D02*
Y231703D01*
X439742Y231465D01*
Y224421D01*
X440498Y223665D01*
Y218169D01*
X439173Y216844D01*
Y216535D01*
G01X442323D02*
X443064D01*
X444764Y218235D01*
X446039D01*
X446923Y219119D01*
Y220394D01*
X451929Y225400D01*
Y229800D01*
G01X432874Y219685D02*
X432061D01*
X432010Y219736D01*
X431548D01*
X430671Y220613D01*
Y221906D01*
X431050Y222285D01*
Y223383D01*
X430671Y223762D01*
Y229692D01*
X430171Y230192D01*
X429444D01*
G01X437112Y232239D02*
X438154Y231197D01*
Y225891D01*
X437848Y225585D01*
Y221081D01*
X439173Y219756D01*
Y219685D01*
G01X429725Y216535D02*
X431301Y218111D01*
X431336D01*
G01X432874Y216535D02*
X434448Y218109D01*
G01X436024Y216535D02*
X437598Y218109D01*
G01X436024Y222834D02*
Y228995D01*
X436529Y229500D01*
G01X434209Y232474D02*
Y231820D01*
X436529Y229500D01*
G01X440000Y236250D02*
X433500D01*
G01D02*
X432000Y234750D01*
Y232748D01*
X429444Y230192D01*
G01X442323Y222834D02*
Y223512D01*
X441379Y224456D01*
Y229700D01*
G01X432874Y222834D02*
Y224311D01*
X432374Y224811D01*
X432366D01*
X432320Y224857D01*
X432307D01*
G01X429429Y257650D02*
Y252900D01*
G01X438000Y300500D02*
X434406Y304094D01*
Y306094D01*
X436530Y308218D01*
Y311530D01*
X440585Y315585D01*
X446234D01*
X447420Y316771D01*
Y316907D01*
X448546Y318033D01*
Y326306D01*
X450196Y327956D01*
Y328149D01*
G01X444177Y299000D02*
X443997D01*
X440397Y295400D01*
X440100D01*
X439250Y294550D01*
X439200D01*
G01X433500Y297500D02*
X436500D01*
X439200Y294800D01*
Y294550D01*
G01X439055Y309900D02*
X443790Y314635D01*
X446628D01*
X448370Y316377D01*
Y316513D01*
X449546Y317689D01*
Y323562D01*
X450196Y324212D01*
G01X429355Y306100D02*
X429655D01*
X431130Y307575D01*
X433836D01*
X435080Y308819D01*
Y311580D01*
X441260Y317760D01*
X442449D01*
X446259Y321570D01*
Y324212D01*
G01X442155Y306000D02*
X446055D01*
X448355Y308300D01*
Y310319D01*
X456421Y318385D01*
Y325681D01*
X458071Y327331D01*
Y328149D01*
G01X437155Y305300D02*
Y306792D01*
X438138Y307775D01*
X439936D01*
X441180Y309019D01*
Y310681D01*
X444184Y313685D01*
X447022D01*
X449320Y315983D01*
Y316119D01*
X452609Y319408D01*
Y324844D01*
X454134Y326369D01*
Y328149D01*
G01X432955Y309700D02*
Y311400D01*
X440265Y318710D01*
X442055D01*
X444523Y321178D01*
Y326283D01*
X446259Y328019D01*
Y328149D01*
G01X434448D02*
Y327208D01*
X432523Y325283D01*
Y319283D01*
X431023Y317783D01*
Y317283D01*
G01X429500Y311000D02*
X430000D01*
X439500Y320500D01*
Y322000D01*
X440523Y323023D01*
Y326523D01*
X442149Y328149D01*
X442322D01*
G01Y336023D02*
X440353Y334054D01*
G01X434448Y332086D02*
X434141D01*
X432523Y330468D01*
Y330283D01*
G01X446259Y336023D02*
Y335704D01*
X444555Y334000D01*
G01X442322Y324212D02*
Y321987D01*
X441335Y321000D01*
G01X438385Y336023D02*
X436416Y334054D01*
G01X434448Y339960D02*
X432528Y341880D01*
X432365D01*
G01X430511Y351771D02*
X428542Y349802D01*
G01X430511Y343897D02*
X428542Y341928D01*
G01X430511Y339960D02*
X428542Y337991D01*
G01X446259Y339960D02*
X444290Y337991D01*
G01X434448Y336023D02*
Y336037D01*
X432605Y337880D01*
G01X442322Y339960D02*
X442025D01*
X440555Y338000D01*
G01X430511Y367519D02*
X428542Y365550D01*
G01X430511Y359645D02*
X430200D01*
X428542Y357987D01*
Y357676D01*
G01X430511Y379331D02*
X428542Y381300D01*
G01X430511Y391142D02*
X430413D01*
X428555Y393000D01*
G01X430511Y387205D02*
X428542Y389174D01*
G01X446500Y120500D02*
X452500D01*
X454750Y118250D01*
Y117500D01*
G01D02*
Y116000D01*
X455000Y115750D01*
Y113250D01*
G01X459500D02*
X463000Y116750D01*
Y117500D01*
G01X462500Y126500D02*
X459092D01*
X449247Y136345D01*
X447495D01*
X446045Y137795D01*
X445473D01*
G01X465500Y122500D02*
X463625Y124375D01*
X458892D01*
X448622Y134645D01*
G01X466000Y130000D02*
X457007D01*
X449212Y137795D01*
X448622D01*
G01X466000Y137000D02*
X461970D01*
X452370Y146600D01*
X449266D01*
X448622Y147244D01*
G01X445473Y131496D02*
X447389Y129580D01*
G01X445473Y144094D02*
X445946D01*
X447540Y142500D01*
X449429D01*
X453245Y138684D01*
X453487D01*
X454676Y137495D01*
G01X448622Y140945D02*
X448938D01*
X453026Y136857D01*
Y136811D01*
X454837Y135000D01*
X456429D01*
G01X445473Y140945D02*
X446595D01*
X448040Y139500D01*
X448968D01*
X452026Y136442D01*
Y136396D01*
X455922Y132500D01*
X457929D01*
G01X462429Y133500D02*
Y134168D01*
X450997Y145600D01*
X448356D01*
X446712Y147244D01*
X445473D01*
G01Y150393D02*
X445647D01*
X446997Y149043D01*
X450886D01*
X451679Y148250D01*
G01X461685Y150386D02*
Y151815D01*
X460019Y153481D01*
Y153825D01*
X457631Y156213D01*
Y157648D01*
X453779Y161500D01*
X448040D01*
X446548Y162992D01*
X445473D01*
G01X466500Y144500D02*
X464232D01*
X458402Y150330D01*
X458385D01*
X457419Y151296D01*
X456436D01*
X453239Y154493D01*
X452936D01*
X452386Y155043D01*
X448362D01*
X446712Y156693D01*
X445473D01*
G01Y159842D02*
X446712D01*
X448062Y158492D01*
X454099D01*
X455223Y157368D01*
Y156915D01*
X455224Y156914D01*
Y156106D01*
X455731Y155599D01*
Y154302D01*
G01X460300Y141100D02*
Y141629D01*
X459951Y141978D01*
Y143812D01*
X452089Y151674D01*
X451255D01*
X450779Y152150D01*
X448105D01*
X446712Y153543D01*
X445473D01*
G01X463500Y141500D02*
Y142888D01*
X452845Y153543D01*
X448622D01*
G01Y150393D02*
X451870D01*
X454679Y147584D01*
Y146750D01*
X454929Y146500D01*
G01X448622Y144094D02*
X450169D01*
X453929Y140334D01*
G01X448622Y162992D02*
X449117D01*
X449269Y162840D01*
X453783D01*
X458581Y158042D01*
Y156772D01*
X460578Y154775D01*
X460776D01*
X463899Y151652D01*
Y147680D01*
X463969Y147610D01*
G01X448622Y159842D02*
X448964Y159500D01*
X454435D01*
X456681Y157254D01*
Y155819D01*
X459069Y153431D01*
Y151980D01*
G01X462500Y169000D02*
Y169500D01*
X458775Y173225D01*
X456204D01*
X455189Y174240D01*
X448062D01*
X446712Y175590D01*
X445473D01*
G01X459283Y169140D02*
X457295D01*
X453994Y172441D01*
X448622D01*
G01X462679Y165500D02*
Y165750D01*
X459289Y169140D01*
X459283D01*
G01X445473Y166141D02*
X445899D01*
X447698Y164342D01*
X449182D01*
X449684Y163840D01*
X454127D01*
X460967Y157000D01*
X461500D01*
G01X466500Y155500D02*
X466186D01*
X462036Y159650D01*
X459661D01*
X451370Y167941D01*
X448062D01*
X446712Y169291D01*
X445473D01*
G01X457934Y164526D02*
X457474D01*
X452709Y169291D01*
X448622D01*
G01X457934Y164526D02*
X460860Y161600D01*
X462844D01*
X466044Y158400D01*
X467600D01*
G01X448622Y166141D02*
X450758D01*
X451329Y165570D01*
G01X453599Y156693D02*
X448622D01*
G01X465600Y162000D02*
X465429D01*
X463879Y163550D01*
X461688D01*
X460729Y164509D01*
Y164878D01*
X458692Y166915D01*
X458088D01*
X453912Y171091D01*
X447449D01*
X446099Y172441D01*
X445473D01*
G01X458529Y189761D02*
X458500D01*
X458461Y189800D01*
X457329D01*
X451218Y183689D01*
X447851D01*
X446501Y185039D01*
X445473D01*
G01X458929Y180500D02*
X462679D01*
G01X448622Y178740D02*
X451950D01*
X452710Y179500D01*
Y179571D01*
X454339Y181200D01*
X455769D01*
X456469Y180500D01*
X458929D01*
G01X445473Y181889D02*
X446712D01*
X448062Y180539D01*
X452334D01*
X454795Y183000D01*
X459132D01*
X459457Y182675D01*
X463425D01*
X465750Y185000D01*
G01X458429Y175590D02*
X448622D01*
G01X462679Y172500D02*
X462429D01*
X459339Y175590D01*
X458429D01*
G01X448622Y185039D02*
X450668D01*
X456304Y190675D01*
Y190683D01*
X457607Y191986D01*
X457615D01*
X462250Y196621D01*
Y197000D01*
G01X470000Y188500D02*
X469000Y187500D01*
X457880D01*
X452269Y181889D01*
X448622D01*
G01X462679Y176900D02*
X462189Y177390D01*
X448062D01*
X446712Y178740D01*
X445473D01*
G01X462179Y189500D02*
X461879Y189800D01*
X458568D01*
X458529Y189761D01*
G01X448622Y191338D02*
X450196Y189764D01*
G01X448622Y200787D02*
X453342D01*
X454329Y199800D01*
G01X448622Y203937D02*
X452911D01*
X452929Y203919D01*
Y203900D01*
G01X448622Y194488D02*
X452141D01*
X452329Y194300D01*
G01X445473Y200787D02*
X445510D01*
X447063Y199234D01*
G01X464570Y215750D02*
X464684Y215636D01*
Y212841D01*
X465184Y212341D01*
X471879D01*
X472329Y211891D01*
Y210991D01*
X471879Y210541D01*
X465184D01*
X464684Y210041D01*
Y209241D01*
X465184Y208741D01*
X471879D01*
X472329Y208291D01*
Y207391D01*
X471879Y206941D01*
X465184D01*
X464684Y206441D01*
Y204841D01*
X464184Y204341D01*
X462188D01*
X461688Y203841D01*
Y199928D01*
X461188Y199428D01*
X460388D01*
X459888Y199928D01*
Y204725D01*
X459438Y205175D01*
X456355D01*
X456005Y205525D01*
X447704D01*
X446143Y207086D01*
X445473D01*
G01Y191338D02*
X447047Y189764D01*
G01X448622Y197637D02*
X451292D01*
G01X445473Y203937D02*
X446712D01*
X448362Y202287D01*
X452208D01*
X452245Y202250D01*
X453613D01*
X453650Y202287D01*
X455616D01*
X455729Y202400D01*
X456479D01*
G01X445473Y194488D02*
X446712D01*
X448062Y193138D01*
X451157D01*
X451645Y192650D01*
X454979D01*
X455129Y192800D01*
X455929D01*
G01X445473Y197637D02*
X446492D01*
X448142Y195987D01*
X455516D01*
X456229Y196700D01*
G01X457500Y199500D02*
Y197971D01*
X456229Y196700D01*
G01X445473Y213385D02*
X446712D01*
X448062Y212035D01*
X449146D01*
X449947Y212836D01*
Y213921D01*
X450447Y214421D01*
X451787D01*
X452287Y213921D01*
Y213113D01*
X452787Y212613D01*
X455763D01*
X456263Y213113D01*
Y215100D01*
X455763Y215600D01*
X453829D01*
G01X448622Y216535D02*
X449481D01*
X452246Y219300D01*
X453729D01*
G01X445473Y219685D02*
Y220744D01*
X446929Y222200D01*
Y223864D01*
X448840Y225775D01*
G01X448622Y219685D02*
Y220693D01*
X455429Y227500D01*
G01X448622Y210236D02*
Y210585D01*
X449122Y211085D01*
X450258D01*
X451008Y211835D01*
X451893D01*
X452393Y211335D01*
Y210236D01*
G01X445473D02*
X445493D01*
X447143Y208586D01*
X453077D01*
X455914Y211423D01*
X455983D01*
X458029Y213469D01*
G01X461000Y215000D02*
X459560D01*
X458029Y213469D01*
G01X448622Y213385D02*
Y214184D01*
X452088Y217650D01*
X457679D01*
X457798Y217769D01*
G01X445473Y216535D02*
X446173Y217235D01*
X446489D01*
X447439Y218185D01*
X449173D01*
X455495Y224507D01*
X456929D01*
G01X457729Y206800D02*
X458966D01*
X462207Y210041D01*
Y211320D01*
X461707Y211820D01*
X457724D01*
X453391Y207487D01*
X451439D01*
X451038Y207086D01*
X448622D01*
G01X461500Y224500D02*
X456936D01*
X456929Y224507D01*
G01X445892Y225995D02*
X445473Y225576D01*
Y222834D01*
G01X461250Y277500D02*
X463305Y275445D01*
Y264605D01*
X461100Y262400D01*
Y260050D01*
G01X461250Y273000D02*
Y265695D01*
X459055Y263500D01*
G01X457750Y273000D02*
X457500Y272750D01*
Y269400D01*
G01X457750Y277500D02*
Y273000D01*
G01Y277500D02*
X456310Y276060D01*
X449945D01*
G01X456170Y281419D02*
X456500D01*
X457081Y282000D01*
X459750D01*
G01X449945Y278620D02*
X453620D01*
X456170Y281170D01*
Y281419D01*
G01X459750Y282000D02*
X462250Y284500D01*
Y286500D01*
G01X458000D02*
X452680Y281180D01*
X449945D01*
G01X458555Y296750D02*
X461500Y299695D01*
Y309945D01*
X465055Y313500D01*
G01X459000Y302000D02*
Y302497D01*
X458763Y303286D01*
X454930Y307119D01*
Y312649D01*
X460071Y317790D01*
Y322275D01*
X462008Y324212D01*
G01X448000Y304500D02*
X449855Y306355D01*
Y310404D01*
X458071Y318620D01*
Y324212D01*
G01X445855Y309200D02*
X446303Y309648D01*
Y310952D01*
X454134Y318783D01*
Y324212D01*
G01X460055Y312000D02*
X461675Y313620D01*
Y316420D01*
X465295Y320040D01*
Y323562D01*
X465945Y324212D01*
G01X457055Y308000D02*
Y313359D01*
X464295Y320599D01*
Y326499D01*
X465945Y328149D01*
G01X452055Y308500D02*
Y311189D01*
X459071Y318205D01*
Y323019D01*
X459621Y323569D01*
Y324881D01*
X462008Y327268D01*
Y328149D01*
G01X454134Y336023D02*
Y335894D01*
X452223Y333983D01*
G01X450196Y336023D02*
X448227Y334054D01*
G01X462008Y336023D02*
Y336022D01*
X460040Y334054D01*
G01X458071Y336023D02*
Y336022D01*
X456103Y334054D01*
G01X458071Y339960D02*
X460040Y337991D01*
G01X458071Y347834D02*
X457721D01*
X455825Y349730D01*
Y349840D01*
G01X454134Y339960D02*
Y339851D01*
X455985Y338000D01*
X456055D01*
G01X450196Y339960D02*
Y339859D01*
X452055Y338000D01*
G01X452165Y349470D02*
X452498D01*
X454134Y347834D01*
G01X461500Y157000D02*
X466464Y152036D01*
Y151000D01*
G01X466500Y155500D02*
X467679Y154321D01*
X470145Y151444D01*
Y141855D01*
X471000Y141000D01*
G01X462500Y169000D02*
X470679D01*
X473404Y166275D01*
X477154D01*
X480429Y163000D01*
Y151000D01*
X481429Y150000D01*
G01X465750Y185000D02*
X470800D01*
X473200Y182600D01*
X474899D01*
X475216Y182917D01*
G01X466000Y176500D02*
X463079D01*
X462679Y176900D01*
G01X462250Y197000D02*
X465750Y200500D01*
X477929D01*
X495929Y182500D01*
Y164500D01*
G01X465750Y286500D02*
X467950Y284300D01*
Y260650D01*
X466700Y259400D01*
G01X463250Y282000D02*
X466000Y279250D01*
Y263545D01*
X464055Y261600D01*
Y256500D01*
G01X467300Y320100D02*
X465055Y317855D01*
Y313500D01*
G01X465945Y336023D02*
Y336022D01*
X463977Y334054D01*
G01X469882Y336023D02*
Y336022D01*
X467914Y334054D01*
G01X469882Y339960D02*
X471851Y337991D01*
G01X465945Y339960D02*
X467914Y337991D01*
G01X462008Y347834D02*
X462009D01*
X463875Y349700D01*
X463945D01*
G01X462008Y339960D02*
X463977Y337991D01*
G01X501378Y410827D02*
X505922Y415371D01*
G01X511200Y412600D02*
X508693D01*
X505922Y415371D01*
G01X501378Y414764D02*
X504972Y418358D01*
Y418917D01*
X506028Y419973D01*
X506163D01*
G01X511255Y420200D02*
X506390D01*
X506163Y419973D01*
G01X555118Y1008860D02*
Y915060D01*
X562000Y908178D01*
Y666000D01*
X506000Y610000D01*
G01X535824Y168150D02*
Y174500D01*
X535324Y175000D01*
X524500D01*
X524000Y174500D01*
Y172500D01*
X524500Y172000D01*
X528500D01*
G01X524635Y212188D02*
X533028D01*
X533441Y211775D01*
G01X537500Y154750D02*
X544000D01*
G01X537500D02*
X537250D01*
X535824Y156176D01*
Y168150D01*
G01X538500Y160000D02*
Y161000D01*
X537789Y161711D01*
Y168150D01*
G01D02*
Y176321D01*
X537289Y176821D01*
X533146D01*
X532696Y177271D01*
Y178171D01*
X533146Y178621D01*
X537289D01*
X537789Y179121D01*
Y179921D01*
X537289Y180421D01*
X533146D01*
X532696Y180871D01*
Y181771D01*
X533146Y182221D01*
X537289D01*
X537789Y182721D01*
Y183521D01*
X537289Y184021D01*
X533146D01*
X532696Y184471D01*
Y185371D01*
X533146Y185821D01*
X537289D01*
X537789Y186321D01*
Y187121D01*
X537289Y187621D01*
X533146D01*
X532696Y188071D01*
Y188971D01*
X533146Y189421D01*
X537289D01*
X537789Y189921D01*
Y190721D01*
X537289Y191221D01*
X535746D01*
X535246Y191721D01*
Y192521D01*
X535746Y193021D01*
X537289D01*
X537789Y193521D01*
Y197565D01*
X537479Y197875D01*
G01X539759Y168150D02*
Y179105D01*
X539714Y179150D01*
G01X541729Y168150D02*
Y180677D01*
X541229Y181177D01*
X539939D01*
X539439Y181677D01*
Y183327D01*
X539889Y183777D01*
X541599D01*
X542049Y184227D01*
Y185127D01*
X541599Y185577D01*
X539889D01*
X539439Y186027D01*
Y201120D01*
X539939Y201620D01*
X544775D01*
X545275Y201120D01*
Y197425D01*
X544775Y196925D01*
X541877D01*
X541377Y196425D01*
Y195295D01*
X541877Y194795D01*
X542482D01*
X543350Y193927D01*
Y188988D01*
X542862Y188500D01*
X542500D01*
G01X537789Y243850D02*
Y240549D01*
X534259Y237019D01*
Y212593D01*
X533441Y211775D01*
G01X543699Y243850D02*
Y239199D01*
X541800Y237300D01*
X539073D01*
G01X554000Y154750D02*
Y155000D01*
X556500Y157500D01*
Y158500D01*
G01X549000Y154750D02*
Y161000D01*
X547634Y162366D01*
Y168150D01*
G01X559000Y154750D02*
Y162086D01*
X561414Y164500D01*
Y168150D01*
G01X556500Y158500D02*
Y162026D01*
X557474Y163000D01*
Y168150D01*
G01D02*
Y176025D01*
X565025Y183576D01*
Y201632D01*
X557275Y209382D01*
Y214918D01*
G01X549604Y168150D02*
Y180270D01*
X554150Y184816D01*
Y187173D01*
X554149Y187174D01*
Y192649D01*
X555500Y194000D01*
G01X552000Y161000D02*
X551569Y161431D01*
Y168150D01*
G01D02*
Y179901D01*
X555800Y184132D01*
Y186357D01*
X558172Y188729D01*
Y189365D01*
X556438Y191099D01*
Y191735D01*
X557075Y192372D01*
X557711D01*
X559445Y190638D01*
X560081D01*
X561403Y191960D01*
Y192974D01*
X560377Y194000D01*
X559500D01*
G01X543600Y161020D02*
Y168051D01*
X543699Y168150D01*
G01D02*
Y182461D01*
X544279Y183041D01*
X544880D01*
X545275Y183436D01*
Y184723D01*
X544880Y185118D01*
X544231D01*
X543731Y185618D01*
Y187008D01*
X544425Y187702D01*
Y187729D01*
X545000Y188304D01*
Y195000D01*
G01X545664Y168150D02*
Y172680D01*
X545349Y172995D01*
Y180820D01*
X546925Y182396D01*
Y190794D01*
X547375Y191244D01*
X548421D01*
X548871Y191694D01*
Y192594D01*
X548421Y193044D01*
X547375D01*
X546925Y193494D01*
Y194394D01*
X547375Y194844D01*
X548421D01*
X548871Y195294D01*
Y196194D01*
X548421Y196644D01*
X547375D01*
X546925Y197094D01*
Y198744D01*
X547425Y199244D01*
X550275D01*
X550775Y198744D01*
Y188275D01*
X550500Y188000D01*
G01X555509Y168150D02*
Y177343D01*
X556680Y178514D01*
Y179150D01*
X556402Y179428D01*
Y180064D01*
X557039Y180701D01*
X557675D01*
X557953Y180423D01*
X558589D01*
X559226Y181060D01*
Y181696D01*
X558948Y181974D01*
Y182610D01*
X559585Y183247D01*
X560221D01*
X560499Y182969D01*
X562084D01*
X563333Y184218D01*
Y187231D01*
X562833Y187731D01*
X561842D01*
X560500Y186389D01*
Y186000D01*
G01X549926Y204000D02*
Y204928D01*
X550426Y205428D01*
X555125D01*
X555625Y204928D01*
Y203699D01*
X555125Y203199D01*
X552925D01*
X552425Y202699D01*
Y201862D01*
X552925Y201362D01*
X557107D01*
X557607Y200862D01*
Y200062D01*
X557107Y199562D01*
X552925D01*
X552425Y199062D01*
Y198262D01*
X552925Y197762D01*
X560374D01*
X560874Y197262D01*
Y196462D01*
X560374Y195962D01*
X552925D01*
X552425Y195462D01*
Y185562D01*
X551497Y184634D01*
X550781D01*
X550323Y185092D01*
X549070D01*
X548650Y184672D01*
Y181787D01*
X547634Y180771D01*
Y168150D01*
G01X553539D02*
Y179537D01*
X558575Y184573D01*
Y186798D01*
X563100Y191323D01*
Y194000D01*
G01X559444Y168150D02*
Y175944D01*
X567823Y184323D01*
Y185084D01*
X568120Y185381D01*
Y185539D01*
X570075Y187494D01*
Y189798D01*
X571202Y190925D01*
X571229D01*
X572350Y192046D01*
Y203677D01*
X575425Y206752D01*
Y228505D01*
G01X553539Y243850D02*
Y236647D01*
X553675Y236511D01*
Y215913D01*
G01X551569Y243850D02*
Y232488D01*
X551575Y232482D01*
Y217413D01*
X550075Y215913D01*
G01X549604Y243850D02*
Y232119D01*
X549925Y231798D01*
Y220650D01*
X546916Y217641D01*
G01X557474Y243850D02*
Y236456D01*
X562125Y231805D01*
Y212555D01*
X564583Y210097D01*
Y206028D01*
G01X547634Y243850D02*
Y231366D01*
X548000Y231000D01*
G01X555509Y243850D02*
Y234919D01*
X559961Y230467D01*
Y209419D01*
G01X545664Y243850D02*
Y227385D01*
X547746Y225303D01*
G01X557055Y330750D02*
X558705D01*
X559955Y329500D01*
X560253D01*
G01X555935Y339988D02*
Y337120D01*
X556855Y336200D01*
X557755D01*
X557836Y336119D01*
X557859D01*
X558986Y334992D01*
Y334969D01*
X560355Y333600D01*
G01X553055Y330750D02*
X553617D01*
X557061Y334194D01*
G01X553375Y339988D02*
Y336880D01*
X556061Y334194D01*
X557061D01*
G01X549055Y330750D02*
X549805D01*
X553155Y334100D01*
Y334300D01*
G01X550815Y339988D02*
Y336640D01*
X553155Y334300D01*
G01X558955Y368150D02*
X562555Y364550D01*
Y364500D01*
G01X559555Y362500D02*
X561555Y364500D01*
X562555D01*
G01X558495Y356168D02*
Y361440D01*
X559555Y362500D01*
G01X555935Y356168D02*
Y363000D01*
G01D02*
X554555D01*
X553055Y364500D01*
G01X554955Y368150D02*
X554505D01*
X553055Y366700D01*
Y364500D01*
G01X547555D02*
X553375Y360180D01*
Y356168D01*
G01X554955Y371650D02*
X550150D01*
X548877Y370377D01*
X548786Y370240D01*
X548529Y369983D01*
X548390Y369890D01*
X548000Y369500D01*
G01X558955Y371650D02*
X564627D01*
X569555Y366722D01*
Y364000D01*
G01X590553Y1008860D02*
Y919868D01*
X594421Y916000D01*
Y668282D01*
X559500Y633361D01*
Y604500D01*
G01X571000Y154750D02*
X572629Y156379D01*
Y159500D01*
G01X564000Y154750D02*
X562231Y156519D01*
Y159650D01*
G01X572000Y189000D02*
Y186927D01*
X569473Y184400D01*
Y183519D01*
X567350Y181396D01*
Y181000D01*
X567319Y180969D01*
Y168150D01*
G01X567429Y159500D02*
X567319Y159610D01*
Y168150D01*
G01X569289D02*
Y178211D01*
X569000Y178500D01*
Y180712D01*
X571398Y183110D01*
Y183602D01*
G01X572629Y159500D02*
Y161371D01*
X571254Y162746D01*
Y168150D01*
G01D02*
Y179254D01*
X574000Y182000D01*
Y192656D01*
X575500Y194156D01*
Y198400D01*
G01X573224Y168150D02*
Y177290D01*
X577875Y181941D01*
X579400D01*
X579850Y182391D01*
Y183291D01*
X579400Y183741D01*
X576319D01*
X575819Y184241D01*
Y185041D01*
X576319Y185541D01*
X579400D01*
X579850Y185991D01*
Y186891D01*
X579400Y187341D01*
X576135D01*
X575650Y187826D01*
Y188656D01*
X576135Y189141D01*
X579400D01*
X579850Y189591D01*
Y190491D01*
X579400Y190941D01*
X576502D01*
X576002Y191441D01*
Y192241D01*
X576502Y192741D01*
X579400D01*
X579850Y193191D01*
Y194091D01*
X579400Y194541D01*
X577875D01*
X577425Y194991D01*
Y195891D01*
X577875Y196341D01*
X579400D01*
X579850Y196791D01*
Y197691D01*
X579400Y198141D01*
X577875D01*
X577425Y198591D01*
Y203725D01*
X576650Y204500D01*
G01X575194Y168150D02*
Y173694D01*
X576493Y174993D01*
Y175629D01*
X575514Y176608D01*
Y177244D01*
X576151Y177881D01*
X576787D01*
X577766Y176902D01*
X578402D01*
X581500Y180000D01*
Y206675D01*
X583325Y208500D01*
G01X561429Y174441D02*
Y173929D01*
X561414Y173914D01*
Y168150D01*
G01X563384D02*
Y160803D01*
X562231Y159650D01*
G01X563384Y243850D02*
Y239384D01*
X562706Y238706D01*
Y233558D01*
X563775Y232489D01*
Y213239D01*
X568158Y208856D01*
Y206455D01*
G01X567319Y243850D02*
Y234319D01*
X565425Y232425D01*
Y214079D01*
X571461Y208043D01*
Y207887D01*
G01X575194Y243850D02*
Y233194D01*
X575104Y233104D01*
Y232737D01*
X573977Y231610D01*
X572610D01*
X568725Y227725D01*
Y217275D01*
X569000Y217000D01*
G01X571254Y243850D02*
Y233264D01*
X567075Y229085D01*
Y215925D01*
X569127Y213873D01*
Y213100D01*
G01X565349Y243850D02*
Y235074D01*
X564631Y234356D01*
G01X569289Y243850D02*
Y234253D01*
X569322Y234220D01*
G01X573224Y243850D02*
Y234398D01*
X573179Y234353D01*
Y233535D01*
G01X561414Y243850D02*
Y239914D01*
X559971Y238471D01*
Y237753D01*
G01X560355Y333600D02*
X561230Y332725D01*
Y330477D01*
X560253Y329500D01*
G01X590315Y19134D02*
Y25405D01*
X597410Y32500D01*
X643748D01*
X644748Y33500D01*
X659946D01*
X667000Y40554D01*
Y57500D01*
X669500Y60000D01*
X677500D01*
X698000Y80500D01*
G01X581099Y168150D02*
Y172099D01*
X587250Y178250D01*
Y202450D01*
X587175Y202525D01*
G01X583069Y168150D02*
Y171069D01*
X591413Y179413D01*
Y199087D01*
G01X577159Y168150D02*
Y173159D01*
X583150Y179150D01*
Y203150D01*
X583500Y203500D01*
Y204500D01*
G01X579129Y168150D02*
Y172629D01*
X585325Y178825D01*
Y198000D01*
G01X576650Y204500D02*
X579000Y206850D01*
Y213500D01*
X588500Y223000D01*
X592500D01*
G01X591413Y199087D02*
X592826Y200500D01*
X596750D01*
G01X583500Y204500D02*
X591000Y212000D01*
X592500D01*
X593000Y212500D01*
G01X592500Y205000D02*
X586500D01*
X585500Y204000D01*
Y203500D01*
X585250Y203250D01*
Y201750D01*
X585325Y201675D01*
Y198000D01*
G01X596750Y218500D02*
X593500D01*
X592500Y217500D01*
G01D02*
X591087Y216087D01*
X590912D01*
X583325Y208500D01*
G01X592500Y205000D02*
X596750D01*
G01X577159Y243850D02*
Y233343D01*
X577119Y233303D01*
Y233139D01*
G01X592500Y223000D02*
X596750D01*
G01X583069Y243850D02*
Y237375D01*
X583204Y237240D01*
Y236805D01*
G01X581099Y243850D02*
Y238060D01*
X581046Y238007D01*
Y232428D01*
X580709Y232091D01*
G01X596750Y227500D02*
X589200D01*
X585360Y231340D01*
X581460D01*
X580709Y232091D01*
G01X585000Y252750D02*
X583069Y250819D01*
Y243850D01*
G01X596750Y200500D02*
X597000Y200250D01*
Y196500D01*
G01X596750Y214000D02*
X594500D01*
X593000Y212500D01*
G01X596750Y205000D02*
Y209500D01*
G01X594488Y1008860D02*
Y1000500D01*
X593178Y999190D01*
Y923322D01*
X597178Y919322D01*
Y805822D01*
X599000Y804000D01*
G01X631750Y584000D02*
X629475Y581725D01*
X623775D01*
X618950Y586550D01*
Y597000D01*
G01X627750Y612900D02*
X620900D01*
X618950Y610950D01*
Y597000D01*
G01X627750Y606900D02*
X623500D01*
X622500Y607900D01*
Y608500D01*
G01X639874Y580298D02*
X635500D01*
G01X631750Y579000D02*
Y575000D01*
G01X639874Y577738D02*
X635762D01*
X635000Y578500D01*
Y579798D01*
X635500Y580298D01*
G01X631750Y579000D02*
X633048Y580298D01*
X635500D01*
G01X631750Y575000D02*
Y571250D01*
X632000Y571000D01*
G01X639874Y582858D02*
X632892D01*
X631750Y584000D01*
G01Y588500D02*
X634832Y585418D01*
X639874D01*
G01D02*
X644418D01*
X653955Y594955D01*
G01X631000Y603000D02*
X631250Y603250D01*
Y606900D01*
G01D02*
X638860D01*
X639300Y607340D01*
G01X631500Y617000D02*
X631250Y616750D01*
Y612900D01*
G01D02*
X638860D01*
X639300Y612460D01*
G01X702473Y87000D02*
Y81473D01*
X679473Y58473D01*
Y39080D01*
X649527Y9134D01*
G01X657750Y606900D02*
Y598750D01*
X653955Y594955D01*
G01X652674Y585418D02*
X669300D01*
X673300Y581418D01*
Y579000D01*
G01X652674Y582858D02*
X668358D01*
X669000Y582216D01*
Y579000D01*
G01X657750Y613400D02*
X662000D01*
X663500Y611900D01*
Y610500D01*
G01X654500Y602500D02*
X654250Y602750D01*
Y606900D01*
G01D02*
X653810Y607340D01*
X646700D01*
G01X654500Y617000D02*
X654250Y616750D01*
Y613400D01*
G01D02*
X653850Y613000D01*
X652000D01*
X651460Y612460D01*
X646700D01*
G01X674688Y696751D02*
X663273Y708166D01*
Y861199D01*
X696499Y894425D01*
X697925D01*
G01X698750Y863500D02*
X694500D01*
X694125Y863125D01*
X677133D01*
X674333Y865925D01*
X672702D01*
X666573Y859796D01*
Y732927D01*
X691000Y708500D01*
Y704500D01*
G01X677500Y699000D02*
X677575Y699075D01*
Y715945D01*
X664923Y728597D01*
Y860515D01*
X689158Y884750D01*
X694750D01*
G01X674750Y768500D02*
Y770452D01*
X672600Y772602D01*
Y803816D01*
X668523Y807893D01*
Y809507D01*
X668549Y809533D01*
Y858049D01*
X671500Y861000D01*
G01X683218Y797784D02*
X681390D01*
X670474Y808700D01*
G01X743718Y768784D02*
Y806888D01*
X690606Y860000D01*
X677500D01*
X673500Y864000D01*
G01X699500Y56775D02*
X687275D01*
X685519Y55019D01*
G01X695000Y63500D02*
X691500Y60000D01*
X686277D01*
X684861Y58584D01*
G01X699000Y72500D02*
X696500D01*
X686000Y62000D01*
G01X679055Y266250D02*
Y281000D01*
X682055Y284000D01*
Y292000D01*
X686555Y296500D01*
Y300694D01*
X682874Y304375D01*
Y308070D01*
G01X675055Y266250D02*
Y293000D01*
X678939Y296884D01*
Y315945D01*
G01X687055Y266250D02*
Y275500D01*
X690749Y279194D01*
Y298230D01*
G01X683055Y266250D02*
Y282949D01*
X683505Y283399D01*
Y287051D01*
X686809Y290355D01*
G01X713250Y576500D02*
Y577250D01*
X711275Y579225D01*
X709584D01*
X684859Y603950D01*
X683000D01*
G01X713250Y582000D02*
Y586250D01*
X693500Y606000D01*
X688500D01*
G01X692500Y767204D02*
X689188D01*
X687968Y765984D01*
G01X682968Y770234D02*
X679984D01*
X678250Y768500D01*
G01X682968Y765734D02*
Y770234D01*
G01X687968Y765984D02*
X687718Y765734D01*
X682968D01*
G01X677500Y773500D02*
X678000Y774000D01*
X682702D01*
X682968Y773734D01*
G01D02*
X683518Y773184D01*
X684191D01*
X686391Y770984D01*
X687968D01*
G01D02*
X689188Y769764D01*
X698818D01*
G01X686718Y797784D02*
Y793718D01*
G01Y807484D02*
X686984D01*
X690000Y810500D01*
G01X696818Y807824D02*
Y808582D01*
X694900Y810500D01*
X690000D01*
G01X686718Y797784D02*
Y802484D01*
G01D02*
X686938Y802704D01*
X696818D01*
G01X707750Y59500D02*
Y59250D01*
X705275Y56775D01*
X699500D01*
G01X704250Y68000D02*
Y63500D01*
G01D02*
X695000D01*
G01X704250Y72500D02*
X699000D01*
G01X698000Y80500D02*
X700248Y82748D01*
Y99500D01*
X701248Y100500D01*
Y109000D01*
X704674Y112426D01*
X708216D01*
G01X710889Y107284D02*
Y105341D01*
X707748Y102200D01*
Y96500D01*
X702473Y91225D01*
Y87000D01*
G01X700216Y148534D02*
Y144532D01*
X700748Y144000D01*
G01X710889Y135284D02*
Y137859D01*
X709748Y139000D01*
X705748D01*
X700748Y144000D01*
G01X706055Y266250D02*
Y269500D01*
X722055Y285500D01*
Y292000D01*
X726055Y296000D01*
Y299500D01*
X734555Y308000D01*
Y309500D01*
X741000Y315945D01*
X741929D01*
G01X692500Y767204D02*
X698818D01*
G01X698968Y779234D02*
X698818Y779084D01*
Y772324D01*
G01X694500Y779500D02*
X694766Y779234D01*
X698968D01*
G01X696818Y805264D02*
X693336D01*
X691300Y807300D01*
G01X701440Y870250D02*
Y867440D01*
X698750Y864750D01*
Y863500D01*
G01X704000Y876750D02*
Y884750D01*
G01X706560Y876750D02*
X710750D01*
X712750Y874750D01*
X714000D01*
G01X704000Y884750D02*
X694750D01*
G01X724250Y887000D02*
Y887250D01*
X717075Y894425D01*
X697925D01*
G01X707750Y63500D02*
Y59500D01*
G01X711500Y68250D02*
X712250Y69000D01*
X723984D01*
X724000Y69016D01*
G01X711500Y68250D02*
X711250Y68000D01*
X707750D01*
G01X715940Y71750D02*
X711500D01*
G01X737200Y63840D02*
X734660D01*
X732500Y66000D01*
Y69000D01*
X729940Y71560D01*
X716130D01*
X715940Y71750D01*
G01X711500D02*
X710750Y72500D01*
X707750D01*
G01X720032Y57466D02*
X724532D01*
G01X720732Y107784D02*
Y98768D01*
X724716Y94784D01*
G01X737000Y90000D02*
X732959D01*
X722782Y100177D01*
Y100532D01*
G01D02*
X722700Y100614D01*
Y107784D01*
G01X711216Y90534D02*
X715716D01*
G01X716795Y107784D02*
Y103247D01*
X716048Y102500D01*
Y95900D01*
G01X715716Y90534D02*
X716048Y90866D01*
Y95900D01*
G01X780000Y250000D02*
X754200Y224200D01*
X730060D01*
X713750Y207890D01*
Y182500D01*
X715500Y180750D01*
X725748D01*
G01X711500Y179400D02*
X716265Y174635D01*
X759183D01*
X764457Y179909D01*
X769466D01*
G01X719250Y197500D02*
X716200Y200550D01*
Y206942D01*
X730258Y221000D01*
X774663D01*
X789500Y235837D01*
G01X722750Y193500D02*
Y197500D01*
G01X725200Y202000D02*
Y199950D01*
X722750Y197500D01*
G01X726100Y195600D02*
X724000Y193500D01*
X722750D01*
G01X710055Y266250D02*
Y267858D01*
X729054Y286857D01*
Y292499D01*
X734055Y297500D01*
Y299500D01*
X742625Y308070D01*
X745864D01*
G01X714055Y266250D02*
Y269807D01*
X730504Y286256D01*
Y291449D01*
X733555Y294500D01*
X734264D01*
X737994Y298230D01*
G01X718055Y266250D02*
Y271756D01*
X731954Y285655D01*
Y288255D01*
X734054Y290355D01*
G01X720700Y564200D02*
X722124D01*
X724887Y566963D01*
G01X736400Y580840D02*
X733640D01*
X727400Y574600D01*
Y572234D01*
X725166Y570000D01*
X723253D01*
X717036Y563783D01*
G01X723600Y580840D02*
X714410D01*
X713250Y582000D01*
G01X723600Y578280D02*
X718342D01*
X716562Y576500D01*
X713250D01*
G01Y572000D02*
Y568000D01*
G01X723600Y573160D02*
X720160D01*
X718000Y571000D01*
G01X713250Y572000D02*
X714820D01*
X718540Y575720D01*
X723600D01*
G01X713250Y568000D02*
X715000D01*
X718000Y571000D01*
G01X715118Y764644D02*
Y758584D01*
X715468Y758234D01*
G01D02*
X713734D01*
X713500Y758000D01*
X711000D01*
G01X715118Y767204D02*
X723000D01*
G01X727968Y763984D02*
X724748Y767204D01*
X723000D01*
G01X727968Y768984D02*
X727188Y769764D01*
X715118D01*
G01X713118Y802704D02*
X721500D01*
G01X725718Y801984D02*
X724998Y802704D01*
X721500D01*
G01X725718Y797484D02*
X725616Y797586D01*
X720586D01*
X720500Y797500D01*
G01X713118Y800144D02*
X717856D01*
X720500Y797500D01*
G01X713118Y805264D02*
X718764D01*
X722000Y808500D01*
G01X714000Y879000D02*
Y874750D01*
G01D02*
X714810Y875560D01*
X721250D01*
G01X737200Y56165D02*
X732835D01*
X731500Y57500D01*
G01X724000Y69016D02*
X724016Y69000D01*
X730000D01*
X731000Y68000D01*
Y65000D01*
X734720Y61280D01*
X737200D01*
G01X724532Y57466D02*
X731466D01*
X731500Y57500D01*
G01X740500Y82750D02*
X736750D01*
X724716Y94784D01*
G01X737000Y90000D02*
X738500Y88500D01*
X745750D01*
G01X734500Y97500D02*
X734000Y98000D01*
Y100748D01*
X730512Y104236D01*
Y107722D01*
X730574Y107784D01*
G01X745750Y94500D02*
X737500D01*
X734500Y97500D01*
G01X741500Y100500D02*
X739500Y102500D01*
X735748D01*
X732543Y105705D01*
Y107284D01*
G01X735216Y122268D02*
X739111D01*
X739430Y122587D01*
X739503D01*
X742048Y125132D01*
Y128717D01*
X746831Y133500D01*
X762250D01*
X762750Y134000D01*
G01X749500Y110000D02*
X745500D01*
X741106Y114394D01*
X735216D01*
G01Y126205D02*
X737453D01*
X738453Y127205D01*
Y129790D01*
X752163Y143500D01*
X761850D01*
X762650Y144300D01*
G01X735216Y124237D02*
X738819D01*
X740398Y125816D01*
Y129401D01*
X747622Y136625D01*
X757873D01*
X758748Y137500D01*
G01X728606Y134784D02*
Y139505D01*
X731326Y142225D01*
X732725D01*
X735038Y144538D01*
X737038D01*
X737500Y145000D01*
G01X732543Y135284D02*
X735748D01*
X740748Y140284D01*
Y140500D01*
G01X1107500Y580000D02*
X1090000D01*
X1045450Y535450D01*
Y478370D01*
X1041525Y474445D01*
Y397407D01*
X1041500Y397382D01*
Y397341D01*
X1017400Y373241D01*
Y367420D01*
X804980Y155000D01*
X740000D01*
X738500Y153500D01*
Y149685D01*
X738498Y149683D01*
Y145998D01*
X737500Y145000D01*
G01X743873Y179750D02*
X740708Y176585D01*
X727163D01*
X725748Y178000D01*
Y180750D01*
G01X738748Y189500D02*
X734998D01*
G01X738748D02*
X745748D01*
X747748Y187500D01*
Y187250D01*
G01X736060Y196965D02*
Y192560D01*
X734998Y191498D01*
Y189500D01*
G01X725200Y202000D02*
X729100D01*
X730940Y200160D01*
Y196965D01*
G01X736060Y205035D02*
X782135D01*
X818000Y240900D01*
G01X730940Y205035D02*
Y208860D01*
X729800Y210000D01*
G01D02*
X726450D01*
X725450Y209000D01*
G01X736214Y563538D02*
X736000D01*
X733500Y566038D01*
Y568500D01*
G01X736214Y558538D02*
X736462D01*
X730000Y565000D01*
Y568400D01*
X729900Y568500D01*
G01X739714Y558538D02*
X744462D01*
X744500Y558500D01*
G01X739714Y563538D02*
X743962D01*
X744000Y563500D01*
G01X736400Y578280D02*
X733880D01*
X730600Y575000D01*
Y572676D01*
X724887Y566963D01*
G01X737000Y583640D02*
X737140D01*
X739550Y586050D01*
Y586808D01*
X740775Y588033D01*
Y588422D01*
X742078Y589725D01*
X743225D01*
X743500Y590000D01*
X757500D01*
G01X732718Y763984D02*
X727968D01*
G01X736218Y768784D02*
X740218D01*
G01X732718Y763984D02*
Y764612D01*
X736218Y768112D01*
Y768784D01*
G01X735500Y771984D02*
Y771566D01*
X732718Y768784D01*
G01D02*
X732518Y768984D01*
X727968D01*
G01X729218Y806284D02*
X731784D01*
X736000Y810500D01*
G01X725718Y806284D02*
Y801984D01*
G01X727750Y882500D02*
Y880250D01*
X724500Y877000D01*
Y873500D01*
X725000Y873000D01*
X727750D01*
G01Y864000D02*
Y870440D01*
G01D02*
X740110D01*
X741050Y869500D01*
G01X727750Y887000D02*
Y882500D01*
G01X745400Y889000D02*
X738000D01*
G01X727750Y887000D02*
X734500D01*
X736500Y889000D01*
X738000D01*
G01X745400Y891560D02*
X730000D01*
G01X726000Y891250D02*
X726310Y891560D01*
X730000D01*
G01X745400Y886440D02*
X740440D01*
X740000Y886000D01*
G01X745400Y894120D02*
X736380D01*
X736377Y894123D01*
G01X726000Y894750D02*
X735750D01*
X736377Y894123D01*
G01X745400Y896675D02*
X739325D01*
X737000Y899000D01*
X732500D01*
G01D02*
X727750D01*
G01X755000Y56500D02*
X756000Y55500D01*
X758750D01*
G01X747800Y58720D02*
X752780D01*
X755000Y56500D01*
G01X747800Y61280D02*
X753780D01*
X754500Y62000D01*
G01X758750Y63500D02*
X756000D01*
X754500Y62000D01*
G01X753750Y82500D02*
X749250D01*
G01X765500Y83500D02*
X761500Y79500D01*
X756750D01*
X753750Y82500D01*
G01Y88500D02*
X749250D01*
G01X753750D02*
X756650Y85600D01*
X761000D01*
X768200Y92800D01*
G01X745750Y82500D02*
X740750D01*
X740500Y82750D01*
G01X741500Y100500D02*
X742500Y99500D01*
X745750D01*
G01X1136500Y592500D02*
Y592499D01*
X1108001Y564000D01*
X1088943D01*
X1055950Y531007D01*
Y473318D01*
X1052025Y469393D01*
Y393014D01*
X1027900Y368889D01*
Y363068D01*
X776682Y111850D01*
X773350D01*
X759000Y97500D01*
X755750D01*
X753750Y99500D01*
G01D02*
X749250D01*
G01X769000Y101500D02*
Y98400D01*
X762300Y91700D01*
X756195D01*
X753750Y94145D01*
Y94500D01*
G01D02*
X749250D01*
G01X756466Y112284D02*
X757682Y113500D01*
X775998D01*
X1026250Y363752D01*
Y369573D01*
X1050375Y393698D01*
Y470575D01*
X1054300Y474500D01*
Y531691D01*
X1088259Y565650D01*
X1107317D01*
X1134575Y592908D01*
Y593298D01*
X1135000Y593723D01*
Y597000D01*
G01X749500Y110000D02*
X751784Y112284D01*
X752966D01*
G01X740748Y152250D02*
X745500D01*
G01D02*
X778000D01*
G01X740748Y148750D02*
Y140500D01*
G01X761966Y183784D02*
X751214D01*
X747748Y187250D01*
G01X741250Y553500D02*
X743538Y553538D01*
X744962D01*
X745000Y553500D01*
G01X751484Y553491D02*
X748509D01*
X748500Y553500D01*
X745000D01*
G01X751484Y558491D02*
X747509D01*
X747500Y558500D01*
X744500D01*
G01X751484Y563491D02*
X751437Y563538D01*
X744038D01*
X744000Y563500D01*
G01X755750Y575500D02*
X755938Y575688D01*
X765694D01*
G01X755750Y571000D02*
X757878Y573128D01*
X765694D01*
G01X743000Y587500D02*
X741500Y586000D01*
Y582450D01*
G01X765694Y575688D02*
X770302D01*
X771688Y577074D01*
Y584054D01*
X768242Y587500D01*
X743000D01*
G01X741050Y869500D02*
X742425Y868125D01*
X786601D01*
X788060Y869584D01*
Y871250D01*
G01X754750Y874500D02*
X751000D01*
G01X745400Y883880D02*
X749500D01*
X751000Y882380D01*
Y874500D01*
G01X762250Y55500D02*
X780000Y73250D01*
Y97500D01*
X1027426Y344926D01*
Y346500D01*
G01X762250Y51500D02*
X782250Y71500D01*
Y95750D01*
X1031000Y344500D01*
Y348500D01*
G01X758750Y55500D02*
Y51500D01*
G01X762250Y63500D02*
X776100Y77350D01*
Y100600D01*
X1022500Y347000D01*
X1023000D01*
G01X762250Y59500D02*
X778050Y75300D01*
Y99327D01*
X1025476Y346753D01*
Y347309D01*
X1031000Y352833D01*
Y355950D01*
G01X758750Y59500D02*
Y63500D01*
G01X765500Y83500D02*
X774100Y92100D01*
Y101600D01*
X1029075Y356575D01*
Y356748D01*
X1030202Y357875D01*
X1030375D01*
X1032850Y360350D01*
Y366837D01*
X1056950Y390937D01*
Y390978D01*
X1056975Y391003D01*
Y467341D01*
X1060900Y471266D01*
Y492400D01*
X1080000Y511500D01*
Y520000D01*
G01X768200Y92800D02*
X771700Y96300D01*
Y102200D01*
X1031200Y361700D01*
Y367521D01*
X1055325Y391646D01*
Y468025D01*
X1059250Y471950D01*
Y529639D01*
X1083686Y554075D01*
X1086798D01*
X1091798Y559075D01*
X1100575D01*
G01X1098000Y562000D02*
X1089277D01*
X1057600Y530323D01*
Y472634D01*
X1053675Y468709D01*
Y392330D01*
X1029550Y368205D01*
Y362384D01*
X769000Y101834D01*
Y101500D01*
G01X762750Y138500D02*
X759748D01*
X758748Y137500D01*
G01X762750Y138500D02*
X765650Y141400D01*
X799230D01*
X1022950Y365120D01*
Y370941D01*
X1047075Y395066D01*
Y472145D01*
X1051000Y476070D01*
Y533059D01*
X1086891Y568950D01*
X1103841D01*
X1117399Y582508D01*
Y586000D01*
X1119487Y588088D01*
G01X783000Y133500D02*
X780500Y131000D01*
X766000D01*
X763000Y134000D01*
X762750D01*
G01X1132222Y593278D02*
X1121954D01*
X1115749Y587073D01*
Y583192D01*
X1103157Y570600D01*
X1086207D01*
X1049350Y533743D01*
Y476754D01*
X1045425Y472829D01*
Y395750D01*
X1021300Y371625D01*
Y365804D01*
X802996Y147500D01*
X765850D01*
X762650Y144300D01*
G01X775748Y180750D02*
X774907Y179909D01*
X769466D01*
G01X771484Y548491D02*
X771493Y548500D01*
X778000D01*
G01X771484Y553491D02*
X778000D01*
G01X771484Y558491D02*
X777500D01*
X778454Y559445D01*
G01X765694Y573128D02*
X770500D01*
X773638Y576266D01*
Y584862D01*
X768500Y590000D01*
X757500D01*
G01X770250Y853500D02*
Y843250D01*
X766500Y839500D01*
X763500D01*
G01X789250Y850940D02*
Y846250D01*
X781500Y838500D01*
X773500D01*
X768000Y833000D01*
G01X770250Y858000D02*
X774500D01*
X775103Y857397D01*
G01X782750Y853500D02*
X770250D01*
G01X758250Y874500D02*
X762000D01*
G01X767600Y883880D02*
X763000D01*
X762000Y882880D01*
Y874500D01*
G01X767600Y881325D02*
X767675Y881250D01*
X775500D01*
G01X783000Y133500D02*
X793664D01*
X1024600Y364436D01*
Y370257D01*
X1048725Y394382D01*
Y471325D01*
X1052650Y475250D01*
Y532375D01*
X1087575Y567300D01*
X1104525D01*
X1122000Y584775D01*
Y589915D01*
X1122353Y590268D01*
G01X1114883Y591925D02*
Y591217D01*
X1112172Y588506D01*
Y581949D01*
X1102473Y572250D01*
X1085523D01*
X1047700Y534427D01*
Y477438D01*
X1043775Y473513D01*
Y396434D01*
X1019650Y372309D01*
Y366488D01*
X805412Y152250D01*
X778000D01*
G01Y548500D02*
X780750D01*
X782750Y546500D01*
G01D02*
X786350Y550100D01*
X792150D01*
X795750Y546500D01*
G01Y553500D02*
X792825Y556425D01*
X786175D01*
X783250Y553500D01*
G01D02*
X783241Y553491D01*
X778000D01*
G01X795750Y561000D02*
X792750Y564000D01*
X784000D01*
X783250Y563250D01*
Y561000D01*
G01D02*
X783212Y561038D01*
X780047D01*
X778454Y559445D01*
G01X778494Y575688D02*
X786500D01*
G01X792344Y574968D02*
X790602D01*
X789882Y575688D01*
X786500D01*
G01X792344Y570468D02*
X786032D01*
G01X778494Y573128D02*
X783372D01*
X786032Y570468D01*
G01X778494Y580808D02*
X781808D01*
X784500Y583500D01*
X787000D01*
G01X792344Y579468D02*
X792312Y579500D01*
X785500D01*
X784248Y578248D01*
X778494D01*
G01X787000Y583500D02*
X792312D01*
X792344Y583468D01*
G01X782940Y864750D02*
Y856250D01*
X782750Y856060D01*
G01D02*
X776440D01*
X775103Y857397D01*
G01X789250Y850940D02*
X801690D01*
X801750Y851000D01*
G01X789500Y881250D02*
X788000Y879750D01*
Y871310D01*
X788060Y871250D01*
G01X785000Y881250D02*
X785500Y880750D01*
Y871250D01*
G01X780500Y881250D02*
X785000D01*
G01X780500D02*
X775500D01*
G01X780500Y884750D02*
X774750Y890500D01*
X774500D01*
G01X796000Y167600D02*
Y173300D01*
X868300Y245600D01*
X876600D01*
X1004200Y373200D01*
Y378711D01*
X1025050Y399561D01*
Y480776D01*
X1029750Y485476D01*
Y574750D01*
X1032100Y577100D01*
G01X1040000Y579000D02*
X1031700Y570700D01*
Y484668D01*
X1027000Y479968D01*
Y398753D01*
X1006150Y377903D01*
Y372392D01*
X877358Y243600D01*
X869258D01*
X797950Y172292D01*
Y166791D01*
X795500Y164341D01*
Y163408D01*
G01X792344Y583468D02*
Y579468D01*
G01X798000Y728250D02*
Y706000D01*
G01X806000Y731750D02*
X802000D01*
G01X799968Y743784D02*
Y737000D01*
G01X802000Y731750D02*
X799968Y733782D01*
Y737000D01*
G01Y763784D02*
Y768968D01*
X802500Y771500D01*
X809000D01*
X813000Y767500D01*
Y743500D01*
G01X801750Y851000D02*
X809750Y843000D01*
X836000D01*
X838750Y845750D01*
X839250Y846440D01*
G01X829055Y270250D02*
Y270620D01*
X826500Y273175D01*
Y294000D01*
X819609Y300891D01*
Y309891D01*
X817794Y311706D01*
Y357706D01*
X809500Y366000D01*
Y410500D01*
X831000Y432000D01*
X837500D01*
X859425Y453925D01*
Y582575D01*
X830250Y611750D01*
Y727250D01*
G01X821100Y348480D02*
X842290D01*
X844410Y346360D01*
G01X821100Y352480D02*
X847020D01*
X847500Y352000D01*
G01X813000Y743500D02*
Y731250D01*
X810000Y728250D01*
G01D02*
X806000D01*
G01X821250Y853500D02*
X825667Y849083D01*
X826000Y849000D01*
X839250D01*
G01X821250Y873000D02*
Y870750D01*
X819000Y868500D01*
G01X842555Y273750D02*
X838055Y278250D01*
Y288719D01*
X836419Y290355D01*
G01X838055Y273750D02*
X833555D01*
G01D02*
X833500Y273805D01*
Y292000D01*
X835000Y293500D01*
X836000D01*
X840354Y297854D01*
Y298230D01*
G01X829055Y273750D02*
Y289500D01*
X831500Y291945D01*
Y293000D01*
X837055Y298555D01*
Y302500D01*
X832479Y307076D01*
Y308070D01*
G01X841000Y715500D02*
X838500Y718000D01*
Y720925D01*
X837425Y722000D01*
X833500D01*
X832500Y721000D01*
Y614000D01*
X833500Y613000D01*
G01X835000Y719000D02*
Y715500D01*
X837000Y713500D01*
Y666000D01*
X853095Y649905D01*
G01X838750Y858000D02*
X844500Y852250D01*
Y839166D01*
X830250Y824916D01*
Y727250D01*
G01X826500Y743000D02*
Y776430D01*
G01D02*
Y823500D01*
X842500Y839500D01*
Y848000D01*
X841500Y849000D01*
X839250D01*
G01X838750Y863440D02*
Y858000D01*
G01X826500Y851500D02*
X826560Y851560D01*
X832750D01*
G01D02*
Y855500D01*
X835250Y858000D01*
G01D02*
X835500Y858250D01*
Y865000D01*
X834500Y866000D01*
X832250D01*
G01X824750Y873000D02*
X825250Y873500D01*
X828940D01*
G01X832250Y868560D02*
Y870750D01*
X829500Y873500D01*
X828940D01*
G01X847055Y273750D02*
X842555D01*
G01X856055D02*
X851555D01*
G01D02*
Y289746D01*
X852164Y290355D01*
G01X1010500Y451750D02*
Y439540D01*
X991800Y420840D01*
Y375014D01*
X973536Y356750D01*
X957750D01*
X902105Y301105D01*
X854913D01*
X853000Y299192D01*
Y298935D01*
X844420Y290355D01*
X844289D01*
G01X848229Y298230D02*
X853999Y304000D01*
X901500D01*
X956750Y359250D01*
X972854D01*
X989550Y375946D01*
Y426550D01*
X993100Y430100D01*
Y444400D01*
X985500Y452000D01*
Y482000D01*
X994500Y491000D01*
G01X1025500Y657000D02*
X1025000Y656500D01*
Y597000D01*
X988025Y560025D01*
Y540500D01*
X977000Y529475D01*
Y468500D01*
X976950Y468450D01*
Y462564D01*
X982266Y457248D01*
Y450492D01*
X990850Y441908D01*
Y431032D01*
X987300Y427482D01*
Y376878D01*
X971922Y361500D01*
X955500D01*
X904575Y310575D01*
X888925D01*
X888000Y311500D01*
X848734D01*
X844289Y315945D01*
G01X858800Y642060D02*
Y644200D01*
X853095Y649905D01*
G01X847750Y715500D02*
X847250Y715000D01*
X841500D01*
X841000Y715500D01*
G01X852500Y720000D02*
X857000D01*
X857500Y720500D01*
X860500D01*
G01X851250Y715500D02*
X852500Y716750D01*
Y720000D01*
G01D02*
Y726300D01*
X852300Y726500D01*
G01X866500Y100750D02*
X867250Y101500D01*
X872750D01*
G01X869544Y226000D02*
X1012850Y369306D01*
Y375127D01*
X1036500Y398777D01*
Y398818D01*
X1036975Y399293D01*
Y476331D01*
X1040900Y480256D01*
Y565190D01*
X1054075Y578365D01*
Y604798D01*
X1069974Y620697D01*
Y637197D01*
X1072202Y639425D01*
X1073825D01*
X1077750Y635500D01*
G01X870100Y237500D02*
X877552D01*
X1010600Y370548D01*
Y376059D01*
X1034250Y399709D01*
Y399750D01*
X1034725Y400225D01*
Y477425D01*
X1038650Y481350D01*
Y566122D01*
X1051500Y578972D01*
Y601000D01*
G01X860555Y273750D02*
X865055D01*
G01D02*
Y278000D01*
X856055Y287000D01*
Y298181D01*
X856104Y298230D01*
G01D02*
X857770D01*
X860645Y295355D01*
X875500D01*
X878375Y298230D01*
X926472D01*
X1002250Y374008D01*
Y379519D01*
X1023100Y400369D01*
Y481584D01*
X1027800Y486284D01*
Y576200D01*
X1032800Y581200D01*
Y629800D01*
X1038000Y635000D01*
G01X878750Y334500D02*
X865290D01*
X862240Y337550D01*
Y338460D01*
G01X871420Y344895D02*
X875820D01*
X876335Y344380D01*
X883330D01*
X903480Y324230D01*
G01X871420Y348835D02*
Y352980D01*
X871820Y353380D01*
G01X862220Y348835D02*
Y351980D01*
X860820Y353380D01*
G01X871420Y342925D02*
Y339310D01*
X872270Y338460D01*
X872500D01*
G01X862220Y342925D02*
Y339480D01*
X862240Y339460D01*
Y338460D01*
G01X863820Y360130D02*
Y363880D01*
G01X868820Y360130D02*
Y363880D01*
G01Y356630D02*
X871820Y353630D01*
Y353380D01*
G01X863820Y356630D02*
X860820Y353630D01*
Y353380D01*
G01X944000Y434000D02*
X924250Y414250D01*
X894603D01*
X889000Y408647D01*
Y408222D01*
X882253Y401475D01*
X870750D01*
X869750Y402475D01*
Y404500D01*
G01X856517Y404137D02*
X866637D01*
X867000Y404500D01*
X869750D01*
G01X862750Y613750D02*
X862250D01*
X859500Y616500D01*
Y629500D01*
G01X862750Y613750D02*
X867500D01*
G01D02*
X871403D01*
X873125Y615472D01*
G01X867500Y624750D02*
Y628000D01*
X869000Y629500D01*
G01X876000Y631700D02*
X871200D01*
X869000Y629500D01*
G01X879060Y642060D02*
X866200D01*
G01X865250Y662500D02*
X869000D01*
X870000Y661500D01*
Y646800D01*
X866200Y643000D01*
Y642060D01*
G01X865250Y659940D02*
Y657125D01*
X866375Y656000D01*
X866700D01*
X867500Y655200D01*
G01X858750Y665060D02*
Y666250D01*
X863674Y671175D01*
X871825D01*
X880000Y663000D01*
Y657500D01*
G01X861000Y680000D02*
Y683402D01*
X860718Y683684D01*
G01X873500Y679750D02*
X869750D01*
X869000Y679000D01*
G01X869468Y701534D02*
X868936Y701002D01*
Y695111D01*
G01X860718Y683684D02*
Y691284D01*
G01X868936Y695111D02*
X864545D01*
X860718Y691284D01*
G01X873468Y701534D02*
X871496Y699562D01*
Y695111D01*
G01Y687711D02*
Y681754D01*
X873500Y679750D01*
G01X860250Y711000D02*
Y712750D01*
X857750Y715250D01*
X857500D01*
G01X860250Y711000D02*
X861534D01*
X862500Y710034D01*
X865468D01*
G01D02*
X865500Y710066D01*
Y720500D01*
G01X860391Y706312D02*
X860000Y705921D01*
Y702000D01*
G01X860391Y706312D02*
X860613Y706534D01*
X865468D01*
G01D02*
X867475Y708541D01*
Y738525D01*
X865500Y740500D01*
G01X873468Y705034D02*
X869468D01*
G01X869968Y709784D02*
X870500Y710316D01*
Y720500D01*
G01X869468Y705034D02*
Y708710D01*
X869951Y709193D01*
Y709767D01*
X869968Y709784D01*
G01X870500Y720500D02*
Y731000D01*
X875500Y736000D01*
Y740500D01*
G01X860500Y720500D02*
Y725100D01*
X857775Y727825D01*
Y743301D01*
X862474Y748000D01*
X865300D01*
G01X870500Y740500D02*
Y746400D01*
X868900Y748000D01*
X865300D01*
G01X873862Y89876D02*
Y95388D01*
X872750Y96500D01*
G01Y101500D02*
Y96500D01*
G01X882250Y334500D02*
X884000D01*
X894000Y324500D01*
Y317277D01*
X898277Y313000D01*
X898500D01*
X899000Y312500D01*
G01X882250Y338500D02*
X885657D01*
X898000Y326157D01*
Y316000D01*
G01X878750Y338500D02*
X878710Y338460D01*
X872500D01*
G01X879060Y642060D02*
X881363D01*
X886125Y637298D01*
Y488950D01*
X903075Y472000D01*
G01X877000Y622972D02*
Y630700D01*
X876000Y631700D01*
G01X935400Y597300D02*
Y626800D01*
X920100Y642100D01*
X895400D01*
X880000Y657500D01*
G01X873500Y679750D02*
X874056Y680306D01*
Y687711D01*
G01X877500Y700500D02*
X876466Y701534D01*
X873468D01*
G01Y705034D02*
X877034D01*
X877500Y705500D01*
G01X893500Y427000D02*
X896100Y429600D01*
Y461600D01*
X935400Y500900D01*
Y597300D01*
G01X925750Y62060D02*
X921750D01*
X920000Y63810D01*
Y66250D01*
G01X920750Y70500D02*
X920000Y69750D01*
Y66250D01*
G01X932250Y56940D02*
X937038D01*
X939678Y54300D01*
G01X932250Y59500D02*
X941000D01*
G01X941260Y388465D02*
X924465D01*
G01X943344Y51797D02*
X942180D01*
X939678Y54300D01*
G01X948250Y59500D02*
X949847Y61097D01*
Y251607D01*
X1040850Y342610D01*
Y361481D01*
X1065900Y386531D01*
Y483600D01*
X1067900Y485600D01*
G01X941000Y59500D02*
X944750D01*
G01X949134Y371535D02*
X949126Y371527D01*
Y361626D01*
X939500Y352000D01*
G01X953500Y348927D02*
X974411D01*
X1000300Y374816D01*
Y380327D01*
X1021150Y401177D01*
Y482392D01*
X1025850Y487092D01*
Y580650D01*
X1028900Y583700D01*
G01X973015Y453416D02*
X972925Y453326D01*
Y446493D01*
X961632Y435200D01*
X956200D01*
X953450Y437950D01*
G01X950850Y447745D02*
Y444100D01*
X949950Y443200D01*
G01X953450Y441450D02*
X951700D01*
X949950Y443200D01*
G01X952450Y466950D02*
Y580450D01*
X957500Y585500D01*
G01X939200Y452700D02*
X943450D01*
G01X950850Y451685D02*
X947465D01*
X946450Y452700D01*
X943450D01*
G01X950850Y453655D02*
Y458600D01*
X950950Y458700D01*
G01X952450Y463450D02*
Y460200D01*
X950950Y458700D01*
G01X975500Y205000D02*
X958500Y188000D01*
Y187500D01*
G01X983524Y214578D02*
X980078D01*
X966000Y200500D01*
G01X957990Y191064D02*
X958000Y191074D01*
Y192500D01*
X966000Y200500D01*
G01X962000Y251500D02*
X963983Y253483D01*
X963999D01*
X1049250Y338734D01*
Y357250D01*
X1074300Y382300D01*
Y472000D01*
X1101425Y499125D01*
Y549148D01*
X1135102Y582825D01*
X1138525D01*
X1141100Y585400D01*
G01X965500Y260500D02*
X1045350Y340350D01*
Y359617D01*
X1070400Y384667D01*
Y474924D01*
X1097525Y502053D01*
Y550766D01*
X1139632Y592873D01*
Y594441D01*
G01X963500Y256000D02*
X965500Y258000D01*
X965758D01*
X1047300Y339542D01*
Y358809D01*
X1072350Y383859D01*
Y473850D01*
X1099475Y500975D01*
Y549956D01*
X1138538Y589019D01*
X1140481D01*
X1140500Y589000D01*
G01X1050000Y669500D02*
Y663500D01*
X1028900Y642400D01*
Y588800D01*
X1025200Y585100D01*
Y582760D01*
X1023900Y581460D01*
Y487900D01*
X1019200Y483200D01*
Y442300D01*
X996000Y419100D01*
Y373274D01*
X974414Y351688D01*
X959500D01*
G01X964000Y354000D02*
X964499Y354499D01*
X974467D01*
X994050Y374082D01*
Y419908D01*
X1017250Y443108D01*
Y490332D01*
X1021950Y495032D01*
Y582268D01*
X1023250Y583568D01*
Y592492D01*
X1026950Y596192D01*
Y649456D01*
X1049944Y672450D01*
X1054950D01*
X1056000Y673500D01*
G01X957008Y388465D02*
Y394008D01*
X979435Y416435D01*
Y438565D01*
X975266Y442734D01*
Y454347D01*
X969500Y460113D01*
Y540000D01*
X977000Y547500D01*
G01X964882Y388465D02*
Y397882D01*
X982000Y415000D01*
Y439000D01*
X982075Y439075D01*
Y439500D01*
G01X970382Y455872D02*
X970010Y455500D01*
Y446760D01*
X961200Y437950D01*
X957950D01*
G01X960050Y447745D02*
Y445100D01*
X961950Y443200D01*
G01X957950Y441450D02*
X960200D01*
X961950Y443200D01*
G01X957068Y467000D02*
Y473707D01*
X956275Y474500D01*
Y580275D01*
X961500Y585500D01*
G01X957068Y463500D02*
Y458600D01*
G01X960050Y453655D02*
Y455618D01*
X957068Y458600D01*
G01X983524Y209578D02*
X980078D01*
X975500Y205000D01*
G01X972756Y371535D02*
X975935D01*
X977500Y373100D01*
Y392500D01*
X982500Y397500D01*
G01X978000Y554000D02*
Y550400D01*
X980450Y547950D01*
Y545450D01*
X971000Y536000D01*
Y460664D01*
X976716Y454948D01*
Y447784D01*
X984000Y440500D01*
Y408244D01*
X972756Y397000D01*
Y388465D01*
G01X982500Y549500D02*
X984000Y548000D01*
Y543500D01*
X973000Y532500D01*
Y460998D01*
X978366Y455632D01*
Y448468D01*
X985650Y441184D01*
Y400650D01*
X982500Y397500D01*
G01X988900Y434800D02*
Y441100D01*
X980316Y449684D01*
Y456440D01*
X975000Y461756D01*
Y530500D01*
X986075Y541575D01*
Y575575D01*
X1020500Y610000D01*
Y660250D01*
X1041250Y681000D01*
X1045750D01*
G01X1033900Y225500D02*
X1042500Y216900D01*
Y199829D01*
X1034171Y191500D01*
X1025671D01*
X1009500Y175329D01*
Y98500D01*
X992500Y81500D01*
Y66000D01*
X999000Y59500D01*
X1003000D01*
G01X991000Y214578D02*
X987024D01*
G01X997274D02*
X991000D01*
G01X987024Y209578D02*
X991000D01*
G01X997274D02*
X991000D01*
G01X987024Y204578D02*
X991000D01*
G01X997274D02*
X991000D01*
G01X998000Y470500D02*
Y469000D01*
X1000000Y467000D01*
X1003750D01*
G01Y475873D02*
Y480000D01*
X1003000Y480750D01*
G01X998000D02*
Y470500D01*
G01X994250Y496500D02*
Y491250D01*
X994500Y491000D01*
G01X1003000Y484250D02*
Y486974D01*
X1008000Y491974D01*
Y492000D01*
G01X997900Y503700D02*
Y496650D01*
X997750Y496500D01*
G01X998000Y484250D02*
Y492250D01*
X1000500Y494750D01*
Y503700D01*
X1002200Y505400D01*
Y506700D01*
G01X997220Y513600D02*
Y504380D01*
X997900Y503700D01*
G01X999780Y513600D02*
Y509120D01*
X1002200Y506700D01*
G01X999000Y536750D02*
Y533100D01*
X998200Y532300D01*
G01X999780Y526400D02*
Y530720D01*
X998200Y532300D01*
G01X1002340Y526400D02*
Y530200D01*
X1004400Y532260D01*
Y532400D01*
G01X999000Y540250D02*
Y566036D01*
X1017982Y585018D01*
G01X1003000Y536750D02*
Y533800D01*
X1004400Y532400D01*
G01X1003000Y540250D02*
Y566500D01*
X1021000Y584500D01*
Y588500D01*
G01X1045750Y713000D02*
X1041446Y713054D01*
X1018000Y689608D01*
Y611000D01*
X998500Y591500D01*
G01X989000Y757150D02*
X990000D01*
X1030150Y717000D01*
X1066000D01*
G01X1013000Y91500D02*
X1016500Y88000D01*
Y87500D01*
G01X1037500Y225500D02*
Y224234D01*
X1044150Y217584D01*
Y199145D01*
X1037500Y192495D01*
Y192000D01*
X1035000Y189500D01*
X1026500D01*
X1011500Y174500D01*
Y93000D01*
X1013000Y91500D01*
G01X1017274Y199578D02*
X1023922D01*
G01X1017274Y204578D02*
X1023922D01*
G01X1017274Y209578D02*
X1023422D01*
G01X1010250Y464440D02*
Y459346D01*
G01D02*
Y455500D01*
X1010500Y455250D01*
G01X1003750Y469560D02*
Y475873D01*
G01X1003422Y490578D02*
X1009594Y496750D01*
X1011000D01*
G01X1008000Y492000D02*
X1009433D01*
X1013250Y495817D01*
Y502250D01*
X1015500Y504500D01*
Y507000D01*
X1013780Y508720D01*
Y513600D01*
G01X1016340Y526400D02*
Y524660D01*
X1019500Y521500D01*
Y503000D01*
X1018500Y502000D01*
G01X1011220Y513600D02*
Y507780D01*
X1012500Y506500D01*
G01X1011000Y500250D02*
Y505000D01*
X1012500Y506500D01*
G01X1013780Y526400D02*
Y531620D01*
X1012500Y532900D01*
G01X1017000Y536750D02*
Y533600D01*
X1018200Y532400D01*
G01X1016340Y526400D02*
Y529840D01*
X1018200Y531700D01*
Y532400D01*
G01X1013000Y540250D02*
Y554100D01*
G01X1016900Y561000D02*
Y549500D01*
X1017000Y549400D01*
Y545300D01*
G01Y540250D02*
Y545300D01*
G01X1013000Y536750D02*
Y533400D01*
X1012500Y532900D01*
G01X1013000Y554100D02*
Y558500D01*
X1013500Y559000D01*
G01X1121397Y706457D02*
X1116160D01*
X1115685Y705982D01*
X1093203D01*
X1085000Y714185D01*
Y714691D01*
X1081772Y717919D01*
X1070081D01*
X1063500Y724500D01*
X1033060D01*
X1003457Y754103D01*
Y904188D01*
X1044269Y945000D01*
X1328284D01*
X1350500Y922784D01*
Y700999D01*
X1390675Y660824D01*
Y576175D01*
X1384093Y569593D01*
Y360907D01*
X1388075Y356925D01*
Y308075D01*
X1381500Y301500D01*
Y292000D01*
G01X1376000D02*
X1379000Y295000D01*
Y301500D01*
X1386425Y308925D01*
Y355075D01*
X1382441Y359059D01*
Y573551D01*
X1389025Y580135D01*
Y658975D01*
X1348500Y699500D01*
Y922450D01*
X1328069Y942881D01*
X1079529D01*
X1077798Y941150D01*
X1076202D01*
X1076053Y941299D01*
X1042902D01*
X1005107Y903504D01*
Y754787D01*
X1033394Y726500D01*
X1064569D01*
X1071500Y719569D01*
X1082456D01*
X1086650Y715375D01*
Y714869D01*
X1093887Y707632D01*
X1115685D01*
X1115835Y707782D01*
X1122088D01*
X1123413Y706457D01*
X1124547D01*
G01X1023922Y199578D02*
X1028024D01*
G01X1023922Y204578D02*
X1028024D01*
G01Y214078D02*
Y209578D01*
G01D02*
X1023422D01*
G01X1032100Y577100D02*
X1036500Y581500D01*
G01X1035000Y594500D02*
Y629242D01*
X1039925Y634167D01*
Y637925D01*
X1046000Y644000D01*
G01X1028900Y583700D02*
X1030850Y585650D01*
Y639623D01*
X1054052Y662825D01*
X1064276D01*
X1064346Y662743D01*
X1067577D01*
X1067965Y663074D01*
X1075504D01*
X1076446Y664016D01*
X1077766D01*
X1081250Y667500D01*
G01X1024387Y738230D02*
X1030942Y731675D01*
X1069675D01*
X1071225Y733225D01*
X1085334D01*
X1088434Y730125D01*
X1108591D01*
X1117986Y720730D01*
X1122873D01*
X1124547Y719056D01*
G01X1051600Y214500D02*
X1055000D01*
G01X1045000Y260000D02*
Y266600D01*
G01X1124547Y665512D02*
X1122823Y663788D01*
X1117103D01*
X1116648Y663333D01*
X1110833D01*
X1089525Y642025D01*
X1071620D01*
X1066500Y636905D01*
Y621500D01*
X1051500Y606500D01*
Y601000D01*
G01X1069750Y668000D02*
X1067250Y670500D01*
X1051000D01*
X1050000Y669500D01*
G01X1049250Y685000D02*
Y684500D01*
X1045750Y681000D01*
G01X1049250D02*
X1053710D01*
X1054080Y680630D01*
G01X1051600Y688700D02*
X1052600Y689700D01*
Y692900D01*
X1052500Y693000D01*
G01X1049250D02*
X1052500D01*
G01X1049250Y705000D02*
X1051762D01*
X1052678Y704084D01*
G01X1049250Y709000D02*
X1052500D01*
G01X1049250Y701000D02*
X1051500D01*
X1052500Y700000D01*
G01X1049250Y697000D02*
X1054500D01*
G01X1049250Y713000D02*
X1052372D01*
X1052648Y712724D01*
G01X1060250Y215000D02*
X1059750Y214500D01*
X1055000D01*
G01X1068300Y488700D02*
Y486000D01*
X1067900Y485600D01*
G01X1151500Y622750D02*
X1151750D01*
X1153450Y621050D01*
Y616192D01*
X1136408Y599150D01*
X1070350D01*
X1068300Y601200D01*
X1059700D01*
X1058000Y599500D01*
G01X1151500Y619250D02*
Y617000D01*
X1135600Y601100D01*
X1071400D01*
X1069350Y603150D01*
X1056850D01*
X1056000Y604000D01*
G01X1077750Y644000D02*
X1076250Y645500D01*
X1072337D01*
X1064225Y637388D01*
Y631230D01*
X1062940Y629945D01*
G01X1054900Y660900D02*
X1057625Y658175D01*
X1077277D01*
X1077478Y658219D01*
X1077479Y658220D01*
X1078584Y659323D01*
X1079492Y659742D01*
X1081250Y661500D01*
G01X1056000Y673500D02*
X1057925Y675425D01*
X1067012D01*
X1068460Y674419D01*
X1068489Y674262D01*
X1069750Y673000D01*
G01X1057300Y694200D02*
X1054500Y697000D01*
G01X1055900Y703500D02*
X1053262D01*
X1052678Y704084D01*
G01X1056000Y708900D02*
X1052600D01*
X1052500Y709000D01*
G01X1057776Y699081D02*
X1053419D01*
X1052500Y700000D01*
G01X1055400Y714600D02*
X1054524D01*
X1052648Y712724D01*
G01X1065688Y746000D02*
X1065876D01*
X1066376Y746500D01*
X1072500D01*
X1077500Y741500D01*
X1081915D01*
X1083491Y739924D01*
X1085076D01*
X1091575Y733425D01*
X1110843D01*
X1116619Y727649D01*
Y726659D01*
X1119348Y723930D01*
X1122382D01*
X1124107Y722205D01*
X1124547D01*
G01X1065688Y749854D02*
Y746000D01*
G01X1064250Y733500D02*
Y737500D01*
G01Y733500D02*
X1060500D01*
X1059000Y735000D01*
X1054000D01*
G01X1064250Y737500D02*
Y741500D01*
G01X1075289Y738000D02*
X1074354D01*
X1071629Y735275D01*
X1070775D01*
X1069000Y733500D01*
X1067750D01*
G01X1107968Y256784D02*
X1104284D01*
X1098500Y251000D01*
Y237500D01*
X1084500Y223500D01*
G01X1081250Y627500D02*
X1086506D01*
X1089981Y630975D01*
Y631000D01*
X1101825Y642844D01*
Y644677D01*
X1107274Y650126D01*
G01X1081250Y631500D02*
X1085985D01*
X1088884Y632662D01*
X1094297Y638075D01*
X1094298D01*
X1095425Y639202D01*
Y639725D01*
X1099600Y643900D01*
G01X1081250Y635500D02*
X1086182D01*
X1101534Y650852D01*
G01X1081250Y644000D02*
X1085000D01*
X1085900Y644900D01*
G01X1081250Y661500D02*
X1082750Y663000D01*
X1086094D01*
X1086319Y662775D01*
X1093775D01*
X1112089Y681089D01*
X1119241D01*
X1121137Y682985D01*
X1125449D01*
X1126874Y684410D01*
X1127696D01*
G01X1081250Y648000D02*
X1084500D01*
X1087000Y650500D01*
X1091300D01*
G01X1081250Y656000D02*
X1083550Y656300D01*
X1086200D01*
G01X1081250Y652000D02*
X1085000D01*
X1087000Y654000D01*
X1091364D01*
X1094500Y657136D01*
Y657500D01*
G01X1077750Y652000D02*
X1071275D01*
X1070000Y650725D01*
G01X1081250Y679500D02*
Y679454D01*
X1082250Y678454D01*
X1094354D01*
X1094500Y678600D01*
G01X1081250Y675500D02*
X1081750Y676000D01*
X1087000D01*
G01X1081250Y671500D02*
X1082726Y670024D01*
X1093600D01*
G01X1069750Y673000D02*
Y673250D01*
X1071500Y675000D01*
X1075854D01*
X1076354Y675500D01*
X1077750D01*
G01Y671500D02*
X1076175Y669925D01*
X1071675D01*
X1069750Y668000D01*
G01X1081250Y667500D02*
X1082600D01*
X1085150Y664950D01*
X1086902D01*
X1086952Y664900D01*
X1087200D01*
G01X1081250Y691500D02*
X1082156Y690594D01*
X1084900D01*
G01D02*
X1086894D01*
X1088338Y689150D01*
X1100348D01*
X1105362Y694164D01*
X1115638D01*
X1116658Y695184D01*
X1122088D01*
X1123413Y693859D01*
X1124547D01*
G01X1081250Y695500D02*
X1082126Y694624D01*
X1100900D01*
G01X1081250Y687500D02*
X1091900D01*
X1093176Y686224D01*
X1097000D01*
G01X1081250Y683500D02*
Y683484D01*
X1082134Y682600D01*
X1086700D01*
G01X1081250Y711500D02*
X1085809Y707113D01*
X1085992D01*
G01X1081250Y707500D02*
X1081968Y706680D01*
X1086324Y702324D01*
G01X1081250Y703500D02*
X1082736Y702764D01*
X1086426Y699074D01*
X1087722D01*
X1088296Y698500D01*
X1094449D01*
G01X1081250Y699500D02*
X1083665D01*
X1085742Y697424D01*
X1086225D01*
X1086800Y696849D01*
G01X1081250Y715500D02*
X1081878Y714622D01*
X1089500Y707000D01*
Y706500D01*
X1091000Y705000D01*
G01X1081250Y730500D02*
X1084406Y727500D01*
X1088332Y723574D01*
Y723455D01*
X1089459Y722328D01*
X1090000D01*
X1091200Y721128D01*
Y719202D01*
X1091299Y719103D01*
G01X1081250Y726500D02*
X1085953Y723500D01*
X1088700Y720753D01*
Y719947D01*
X1088725Y719922D01*
Y718291D01*
X1089950Y717065D01*
Y717050D01*
X1095000Y712000D01*
G01X1081250Y722500D02*
X1083000D01*
X1086500Y719000D01*
G01X1084300Y741874D02*
X1087988D01*
G01X1121397Y722205D02*
X1119729D01*
X1110159Y731775D01*
X1090077D01*
X1083852Y738000D01*
X1075289D01*
G01X1118000Y739000D02*
Y746500D01*
X1114516Y749984D01*
X1097210D01*
X1097001Y749775D01*
X1092999D01*
X1092790Y749984D01*
X1084838D01*
X1084798Y750024D01*
X1083202D01*
X1083162Y749984D01*
X1079688D01*
G01X1084000Y748099D02*
X1076901D01*
X1075066Y749934D01*
X1074968D01*
G01D02*
X1074928Y749974D01*
X1070478D01*
G01X1099500Y256250D02*
X1100150D01*
X1103200Y259300D01*
G01X1092500Y457750D02*
Y461500D01*
G01X1099600Y643900D02*
Y645600D01*
X1112313Y658313D01*
X1115457D01*
X1118082Y660938D01*
X1122129D01*
X1123554Y662363D01*
X1124547D01*
G01X1121397Y665512D02*
X1110254D01*
X1090242Y645500D01*
X1086500D01*
X1085900Y644900D01*
G01X1121397Y662363D02*
X1116749D01*
X1115393Y661007D01*
X1111689D01*
X1101534Y650852D01*
G01X1091300Y650500D02*
X1091988D01*
X1109071Y667583D01*
X1109083D01*
X1109262Y667762D01*
X1120281D01*
X1120807Y667236D01*
X1124839D01*
X1126563Y665512D01*
X1127696D01*
G01X1086200Y656300D02*
X1090482D01*
X1107319Y673137D01*
X1125238D01*
X1126563Y671812D01*
X1127696D01*
G01X1121397Y690709D02*
X1120623Y689935D01*
X1119435D01*
X1118714Y689214D01*
X1107414D01*
X1096800Y678600D01*
X1094500D01*
G01X1124547Y687560D02*
X1123413D01*
X1122088Y688885D01*
X1119729D01*
X1118283Y687439D01*
X1115952D01*
X1115452Y686939D01*
X1108102D01*
X1097160Y676000D01*
X1087000D01*
G01X1093600Y670024D02*
X1094024D01*
X1108989Y684989D01*
X1115777D01*
X1117227Y686439D01*
X1118689D01*
X1119810Y687560D01*
X1121397D01*
G01X1124547Y684410D02*
X1123122Y685835D01*
X1119531D01*
X1119185Y685489D01*
X1118489D01*
X1116039Y683039D01*
X1109797D01*
X1091658Y664900D01*
X1087200D01*
G01X1121397Y697008D02*
X1120942Y696553D01*
X1116303D01*
X1115564Y695814D01*
X1102090D01*
X1100900Y694624D01*
G01X1097000Y686224D02*
X1099756D01*
X1106046Y692514D01*
X1119842D01*
X1120412Y693084D01*
X1120622D01*
X1121397Y693859D01*
G01X1127696Y697008D02*
X1126371Y698333D01*
X1118157D01*
X1117523Y697699D01*
X1100350D01*
X1098926Y696275D01*
X1087374D01*
X1086800Y696849D01*
G01X1124547Y690709D02*
X1123413D01*
X1122088Y692034D01*
X1120706D01*
X1119557Y690885D01*
X1119041D01*
X1119020Y690864D01*
X1106730D01*
X1098504Y682638D01*
X1086738D01*
X1086700Y682600D01*
G01X1121397Y703308D02*
X1120771Y702682D01*
X1090171D01*
X1085992Y706861D01*
Y707113D01*
G01X1121397Y712756D02*
X1115870D01*
X1115789Y712675D01*
X1097819D01*
X1091394Y719100D01*
X1091302D01*
X1091299Y719103D01*
G01X1124547Y709607D02*
X1123413D01*
X1122088Y710932D01*
X1096068D01*
X1095000Y712000D01*
G01X1124547Y700158D02*
X1123222Y701483D01*
X1120706D01*
X1120255Y701032D01*
X1087616D01*
X1086324Y702324D01*
G01X1121397Y700158D02*
X1120522Y699283D01*
X1115718D01*
X1115652Y699349D01*
X1099666D01*
X1098817Y698500D01*
X1094449D01*
G01X1121397Y709607D02*
X1116010D01*
X1115685Y709282D01*
X1094571D01*
X1088300Y715553D01*
Y716381D01*
X1086500Y718182D01*
Y719000D01*
G01X1124547Y703308D02*
X1123222Y704633D01*
X1115986D01*
X1115685Y704332D01*
X1091668D01*
X1091000Y705000D01*
G01X1087988Y741874D02*
X1090956Y738906D01*
X1095006D01*
G01X1098000Y810000D02*
X1098034Y810034D01*
X1101968D01*
G01X1238100Y857350D02*
Y871400D01*
X1202954Y906546D01*
X1097423D01*
G01X1093500Y905500D02*
X1095000Y904000D01*
X1200086D01*
X1222000Y882086D01*
Y841968D01*
X1221016Y840984D01*
G01X1110318Y267784D02*
X1114500D01*
X1121500Y260784D01*
Y257500D01*
G01X1107968Y256784D02*
X1113768D01*
X1114468Y256084D01*
G01D02*
X1114552Y256000D01*
X1120000D01*
X1121500Y257500D01*
G01X1110318Y263849D02*
X1106349D01*
X1103300Y260800D01*
Y259400D01*
X1103200Y259300D01*
G01X1195000Y428000D02*
Y457500D01*
X1176825Y475675D01*
Y501175D01*
X1161500Y516500D01*
X1112500D01*
X1111500Y517500D01*
G01X1133250Y618000D02*
Y616676D01*
X1127074Y610500D01*
X1107000D01*
X1106000Y609500D01*
G01X1142000Y625750D02*
X1144500Y623250D01*
Y616575D01*
X1133425Y605500D01*
X1106000D01*
G01X1117500Y617750D02*
X1122000D01*
G01X1114500Y645000D02*
X1114900Y644600D01*
Y641800D01*
G01X1115000Y637750D02*
Y641700D01*
X1114900Y641800D01*
G01X1107000Y637750D02*
Y643552D01*
X1111824Y648376D01*
G01X1110000Y642300D02*
Y643081D01*
X1115069Y648150D01*
X1116276D01*
X1125972Y657846D01*
Y659505D01*
X1127405Y660938D01*
X1128287D01*
X1129396Y662047D01*
Y664002D01*
X1130846Y665452D01*
Y665512D01*
G01X1111000Y637750D02*
Y638150D01*
X1110000Y639150D01*
Y642300D01*
G01X1127696Y662363D02*
X1126563D01*
X1124938Y660738D01*
X1124056D01*
X1123022Y659704D01*
Y658822D01*
X1116250Y652050D01*
X1112350D01*
X1105100Y644800D01*
Y644100D01*
X1104500Y643500D01*
G01X1103000Y637750D02*
X1104500Y639250D01*
Y643500D01*
G01X1111824Y648376D02*
X1113548Y650100D01*
X1115644D01*
X1124547Y659003D01*
Y659213D01*
G01X1107274Y650126D02*
X1111148Y654000D01*
X1114006D01*
X1119219Y659213D01*
X1121397D01*
G01Y725355D02*
X1119267D01*
X1117569Y727053D01*
Y728043D01*
X1116919Y728693D01*
Y730107D01*
X1114450Y732576D01*
Y735550D01*
G01X1115200Y745400D02*
X1111350D01*
X1111000Y745750D01*
G01D02*
X1104578D01*
X1104230Y745402D01*
G01X1111000Y742250D02*
X1111619Y741631D01*
X1111863D01*
X1114450Y739044D01*
Y735550D01*
G01X1128430Y749640D02*
X1117860D01*
X1114300Y753200D01*
Y786000D01*
X1110300Y790000D01*
G01X1121646Y775335D02*
X1119800D01*
X1119300Y775835D01*
Y777443D01*
X1118850Y777893D01*
X1117950D01*
X1117500Y777443D01*
Y776593D01*
X1117050Y776143D01*
X1116150D01*
X1115700Y776593D01*
Y779243D01*
X1116150Y779693D01*
X1118850D01*
X1119300Y780143D01*
Y780500D01*
X1120400Y781600D01*
G01X1121646Y778485D02*
X1122125Y778964D01*
Y782315D01*
X1120840Y783600D01*
X1116550D01*
G01X1121646Y794233D02*
X1114379Y801500D01*
X1107500D01*
G01X1101968Y806534D02*
X1107268D01*
X1107468Y806334D01*
G01D02*
X1107500Y806302D01*
Y801500D01*
G01X1101968Y810034D02*
Y816436D01*
X1101989Y816863D01*
X1101986Y816844D01*
G01X1126618Y269754D02*
X1129254D01*
X1129894Y270394D01*
X1129919D01*
X1130343Y270818D01*
Y270843D01*
X1132000Y272500D01*
Y279784D01*
X1134500Y282284D01*
G01X1126618Y265814D02*
X1132814D01*
X1133500Y266500D01*
X1134000D01*
G01D02*
X1138750D01*
G01X1126618Y263849D02*
X1129151D01*
X1131500Y261500D01*
X1134000D01*
G01X1138750Y262500D02*
X1135000D01*
X1134000Y261500D01*
G01X1126618Y267784D02*
X1130784D01*
X1135000Y272000D01*
Y274500D01*
G01X1126618Y271719D02*
Y277132D01*
X1125750Y278000D01*
G01X1142640Y359860D02*
X1140650Y357870D01*
Y304650D01*
X1125750Y289750D01*
Y278000D01*
G01X1123500Y521500D02*
Y524550D01*
X1139025Y540075D01*
X1148298D01*
X1165648Y557425D01*
X1214748D01*
X1225045Y567722D01*
Y606540D01*
X1218185Y613400D01*
X1212269D01*
X1199350Y626319D01*
Y629224D01*
X1199175Y629399D01*
Y630325D01*
X1194525Y634975D01*
X1193078D01*
X1191775Y636278D01*
Y637091D01*
X1183667Y645199D01*
X1181285D01*
X1177383Y649101D01*
Y649940D01*
X1175340Y651983D01*
Y654660D01*
X1174940Y655060D01*
Y659213D01*
G01X1342000Y81250D02*
X1335750D01*
X1331500Y77000D01*
Y67155D01*
X1330015Y65670D01*
X1284552D01*
X1283500Y66722D01*
Y259500D01*
X1276000Y267000D01*
Y323500D01*
X1253000Y346500D01*
Y369500D01*
X1203000Y419500D01*
Y428000D01*
X1201000Y430000D01*
Y460000D01*
X1183500Y477500D01*
Y501928D01*
X1157878Y527550D01*
X1130928D01*
G01X1179934Y609672D02*
X1185500D01*
X1189100Y606072D01*
Y571916D01*
X1181434Y564250D01*
X1131950D01*
X1125600Y570600D01*
G01X1167500Y634250D02*
X1170387D01*
X1178587Y626050D01*
X1185449D01*
X1191350Y620150D01*
Y570984D01*
X1182366Y562000D01*
X1132000D01*
G01X1125000Y603050D02*
X1134157D01*
X1148975Y617868D01*
Y638335D01*
X1148450Y638860D01*
Y640603D01*
X1148175Y640878D01*
Y641007D01*
X1147969Y641213D01*
Y653533D01*
X1147185Y654317D01*
Y656336D01*
X1146594Y656927D01*
Y659213D01*
G01X1137750Y618000D02*
X1133250D01*
G01X1133000Y634250D02*
Y633000D01*
X1131000Y631000D01*
G01X1137000Y631250D02*
Y631223D01*
X1131288Y625511D01*
X1126905D01*
X1123394Y622000D01*
X1121900D01*
X1121500Y621600D01*
G01X1129000Y634250D02*
Y628926D01*
X1130490Y627436D01*
G01X1125000Y634250D02*
X1125041Y634209D01*
Y631000D01*
G01X1140295Y659213D02*
Y649295D01*
X1137375Y646375D01*
Y637625D01*
X1138825Y636175D01*
Y630134D01*
X1132191Y623500D01*
X1130200D01*
X1128700Y622000D01*
G01X1122000Y617750D02*
X1125952Y621702D01*
X1128402D01*
X1128700Y622000D01*
G01X1129400Y641300D02*
Y647681D01*
X1129409Y647690D01*
Y649534D01*
X1129400Y649543D01*
Y650896D01*
X1135321Y656817D01*
Y659737D01*
X1137145Y661561D01*
Y662363D01*
G01X1129000Y637750D02*
X1129500Y638250D01*
Y640900D01*
X1129400Y641000D01*
Y641300D01*
G01X1132795Y644695D02*
Y652284D01*
X1134360Y653849D01*
X1137000Y656490D01*
Y658500D01*
X1137145Y658645D01*
Y659213D01*
G01X1133000Y637750D02*
X1132795Y637955D01*
Y644695D01*
G01X1125000Y637750D02*
X1127175Y639925D01*
Y648603D01*
X1127184Y648612D01*
G01X1133996Y665512D02*
X1132445Y663961D01*
Y663924D01*
X1132423Y663902D01*
G01X1127184Y648612D02*
X1127187Y648615D01*
Y650043D01*
X1133996Y656852D01*
Y659213D01*
G01Y678111D02*
X1132440Y676555D01*
G01X1127696Y674961D02*
X1129272Y673385D01*
Y673350D01*
G01X1130846Y671812D02*
X1129309Y670275D01*
X1129271D01*
G01X1127696Y678111D02*
X1126103Y676518D01*
X1126102D01*
G01X1130846Y674961D02*
X1132402Y673405D01*
G01X1130846Y668662D02*
X1132398Y667110D01*
Y667102D01*
G01X1130846Y678111D02*
X1129290Y676555D01*
G01X1127696Y681260D02*
X1127500D01*
X1126121Y679881D01*
Y679722D01*
G01X1130846Y681260D02*
Y681223D01*
X1132421Y679648D01*
G01X1133996Y674961D02*
X1134860Y675825D01*
X1135475D01*
X1136150Y676500D01*
G01X1127696Y687560D02*
X1126117Y685981D01*
Y685952D01*
G01X1130846Y690709D02*
X1129307Y689170D01*
X1129273D01*
G01X1127696Y690709D02*
X1126201Y689214D01*
X1126165D01*
X1126122Y689171D01*
G01X1130846Y693859D02*
X1129290Y692303D01*
G01X1127696Y693859D02*
X1126116Y692279D01*
G01X1133996Y693859D02*
X1132458Y695397D01*
Y695434D01*
X1132423Y695469D01*
G01X1133996Y690709D02*
X1132440Y692265D01*
G01X1133996Y687560D02*
X1132440Y686004D01*
G01X1133996Y684410D02*
X1132446Y682860D01*
X1132434D01*
G01X1130846Y684410D02*
X1129308Y682872D01*
Y682834D01*
X1129278Y682804D01*
G01X1130846Y687560D02*
X1129291Y686005D01*
X1129289D01*
G01X1133996Y681260D02*
X1134038D01*
X1135685Y679613D01*
G01X1130846Y703308D02*
X1130808D01*
X1129238Y704878D01*
G01X1133996Y700158D02*
X1132440Y701714D01*
G01X1130846Y700158D02*
X1129290Y701714D01*
X1129270D01*
G01X1127696Y709607D02*
X1126121Y711182D01*
Y711218D01*
G01X1130846Y706457D02*
X1129380Y707923D01*
Y707961D01*
X1129285Y708056D01*
G01X1127696Y700158D02*
X1126174Y701680D01*
X1126137D01*
X1126114Y701703D01*
G01X1127696Y703308D02*
X1127659D01*
X1126093Y704874D01*
G01X1133996Y706457D02*
X1133959D01*
X1132406Y704904D01*
G01X1133996Y697008D02*
X1132440Y698564D01*
G01X1130846Y697008D02*
X1129290Y698564D01*
G01X1127696Y706457D02*
X1126160Y707993D01*
Y708024D01*
X1126155Y708029D01*
G01X1127696Y712756D02*
X1127731D01*
X1129277Y711210D01*
G01X1127696Y722205D02*
X1127655D01*
X1125930Y723930D01*
X1123956D01*
X1123000Y724886D01*
Y725768D01*
X1121988Y726780D01*
X1120780D01*
X1118193Y729367D01*
Y738807D01*
X1118000Y739000D01*
G01X1137145Y725355D02*
X1136271Y726229D01*
Y726317D01*
X1133727Y728861D01*
Y730171D01*
X1127351Y736547D01*
X1127059D01*
X1126885Y736721D01*
G01X1137145Y719056D02*
Y719876D01*
X1135421Y721600D01*
Y722779D01*
X1134266Y723934D01*
X1133543D01*
X1132171Y725306D01*
Y725904D01*
X1128959Y729116D01*
Y729952D01*
G01X1137145Y722205D02*
Y722597D01*
X1135321Y724420D01*
Y725923D01*
X1132077Y729167D01*
Y730477D01*
X1128414Y734140D01*
X1124497D01*
G01X1130846Y725355D02*
X1129712D01*
X1128287Y726780D01*
X1128170D01*
X1126969Y727981D01*
G01X1133996Y725355D02*
X1133121Y726230D01*
Y726779D01*
X1130584Y729316D01*
Y730626D01*
X1129301Y731909D01*
X1126955D01*
G01X1127696Y715906D02*
X1127659D01*
X1126121Y714368D01*
G01X1140295Y725355D02*
Y725665D01*
X1137027Y728933D01*
Y731212D01*
X1128043Y740196D01*
X1127792D01*
X1127183Y740805D01*
G01X1143444Y725355D02*
X1142570Y726229D01*
Y726298D01*
X1140327Y728541D01*
Y732580D01*
X1128627Y744280D01*
X1127020D01*
X1126671Y744629D01*
G01X1143444Y722205D02*
Y723481D01*
X1141620Y725305D01*
Y725904D01*
X1138677Y728846D01*
Y731896D01*
X1127943Y742630D01*
X1126088D01*
X1124992Y743726D01*
X1123393D01*
G01X1146594Y722205D02*
X1145269Y723530D01*
Y725404D01*
X1141977Y728696D01*
Y733623D01*
X1138615Y736985D01*
Y737621D01*
X1139661Y738667D01*
Y739303D01*
X1139024Y739940D01*
X1138388D01*
X1137342Y738894D01*
X1136706D01*
X1135536Y740064D01*
Y740700D01*
X1136972Y742137D01*
Y742773D01*
X1136335Y743410D01*
X1135699D01*
X1134263Y741973D01*
X1133627D01*
X1132990Y742610D01*
Y743246D01*
X1134426Y744683D01*
Y745319D01*
X1133789Y745956D01*
X1133153D01*
X1131717Y744519D01*
X1131081D01*
X1129911Y745689D01*
Y746600D01*
G01X1140295Y722205D02*
Y722207D01*
X1138470Y724032D01*
Y725904D01*
X1135377Y728997D01*
Y730528D01*
X1127359Y738546D01*
X1124740D01*
X1124326Y738960D01*
G01X1129911Y746600D02*
X1128641D01*
X1127663Y747578D01*
X1124978D01*
G01X1137748Y757034D02*
X1131856D01*
X1131661Y756839D01*
G01D02*
X1128935Y754113D01*
Y750145D01*
X1128430Y749640D01*
G01X1127945Y775335D02*
Y776045D01*
X1126520Y777470D01*
Y779076D01*
X1126642Y779198D01*
Y785505D01*
G01X1124796Y775335D02*
Y776468D01*
X1123200Y778064D01*
Y783900D01*
G01X1131095Y775335D02*
Y774265D01*
X1129670Y772840D01*
Y769034D01*
X1125900Y765264D01*
Y764200D01*
G01X1137748Y757034D02*
Y759534D01*
X1132520Y764762D01*
Y765880D01*
X1132625Y765985D01*
Y767415D01*
X1132520Y767520D01*
Y772478D01*
X1134244Y774202D01*
Y775335D01*
G01X1129501Y776929D02*
X1127945Y778485D01*
G01X1131095D02*
Y782595D01*
X1132600Y784100D01*
Y784822D01*
G01X1124796Y778485D02*
Y782914D01*
X1125025Y783143D01*
Y784657D01*
X1123332Y786350D01*
X1120529D01*
G01X1127945Y794233D02*
Y794225D01*
X1126360Y792640D01*
G01X1127945Y791083D02*
X1127880Y791018D01*
Y789557D01*
X1127160Y788837D01*
G01X1131095Y794233D02*
X1131057D01*
X1129497Y792673D01*
G01X1131095Y791083D02*
Y789307D01*
X1130610Y788822D01*
Y788820D01*
G01X1134244Y791083D02*
Y788664D01*
X1134145Y788565D01*
Y788450D01*
G01X1134244Y794233D02*
Y794196D01*
X1132684Y792636D01*
G01X1121646Y791083D02*
X1119060D01*
G01X1124796D02*
X1124360Y790647D01*
Y788390D01*
G01X1124796Y794233D02*
Y794205D01*
X1123254Y792663D01*
G01X1142250Y266500D02*
X1146000D01*
X1146500Y267000D01*
G01X1142250Y258500D02*
X1146000D01*
G01X1138750Y266500D02*
Y270500D01*
G01Y258500D02*
Y262500D01*
G01X1142250D02*
X1150000D01*
X1151000Y263500D01*
Y264500D01*
G01X1142250Y270500D02*
X1149000D01*
X1151800Y267700D01*
X1153700D01*
G01X1192427Y238000D02*
Y238500D01*
X1191220Y239707D01*
X1179277D01*
X1172950Y246034D01*
Y261662D01*
X1146172Y288440D01*
Y322672D01*
X1150640Y327140D01*
Y359860D01*
G01X1146640D02*
Y334265D01*
X1142600Y330225D01*
Y322000D01*
X1144222Y320378D01*
Y287632D01*
X1171000Y260854D01*
Y244500D01*
X1178500Y237000D01*
X1181250D01*
G01X1142218Y286284D02*
X1142216Y286286D01*
Y290534D01*
X1141000Y291750D01*
G01X1138718Y286284D02*
Y282284D01*
G01D02*
X1134500D01*
G01X1135000Y274500D02*
X1138750D01*
G01D02*
Y278500D01*
G01X1181250Y244000D02*
X1180500D01*
X1176900Y247600D01*
Y263228D01*
X1150575Y289553D01*
Y320075D01*
X1161530Y331030D01*
Y360430D01*
G01X1192427Y242500D02*
X1191927Y242000D01*
X1179742D01*
X1174950Y246792D01*
Y262420D01*
X1148625Y288745D01*
Y321625D01*
X1157480Y330480D01*
Y361620D01*
G01X1141000Y291750D02*
Y292000D01*
X1138350Y294650D01*
X1136450D01*
G01X1136075Y559075D02*
X1182075D01*
X1193500Y570500D01*
Y610000D01*
X1196125Y612625D01*
Y629381D01*
X1188381Y637125D01*
X1182006D01*
X1172325Y646806D01*
Y650175D01*
X1170235Y652265D01*
Y664235D01*
X1171512Y665512D01*
X1171791D01*
G01X1145900Y579800D02*
X1147522Y581422D01*
X1149934D01*
G01D02*
X1150856Y580500D01*
X1151000D01*
X1158224Y573276D01*
X1159934D01*
G01X1149750Y597000D02*
X1152500D01*
X1154000Y598500D01*
G01X1141421Y632142D02*
X1143000Y630563D01*
Y629000D01*
G01X1137500Y625750D02*
X1138250D01*
X1141500Y629000D01*
X1143000D01*
G01X1137750Y618000D02*
X1137500Y618250D01*
Y622250D01*
G01X1146000Y630700D02*
Y634250D01*
G01X1142000Y625750D02*
X1146500D01*
G01D02*
Y630200D01*
X1146000Y630700D01*
G01Y637750D02*
Y640000D01*
X1145500Y640500D01*
Y644500D01*
G01D02*
Y646082D01*
X1145719Y646301D01*
Y656458D01*
X1145269Y656908D01*
Y660325D01*
X1146594Y661650D01*
Y662363D01*
G01X1150400Y641800D02*
Y644019D01*
X1149919Y644500D01*
Y653409D01*
X1148319Y655009D01*
Y660938D01*
X1149744Y662363D01*
G01X1151500Y637750D02*
Y638568D01*
X1150400Y639668D01*
Y641800D01*
G01X1137000Y634750D02*
X1135225Y636525D01*
Y648725D01*
X1135600Y649100D01*
G01X1140295Y665512D02*
X1138800Y664017D01*
Y663980D01*
X1138757Y663937D01*
G01X1148150Y663956D02*
X1146594Y665512D01*
G01X1140295Y662363D02*
Y661295D01*
X1138500Y659500D01*
Y658500D01*
X1138000Y658000D01*
Y651500D01*
X1135600Y649100D01*
G01X1137145Y665512D02*
X1135593Y663960D01*
X1135556D01*
X1135553Y663957D01*
G01X1149744Y668662D02*
X1148188Y667106D01*
G01X1149744Y671812D02*
X1148188Y670256D01*
G01X1143444Y671812D02*
X1141666Y673590D01*
X1141600D01*
G01X1149744Y665512D02*
X1149758D01*
X1151334Y663936D01*
X1151354D01*
G01X1135589Y673368D02*
X1137145Y671812D01*
G01X1140295Y668662D02*
X1140257D01*
X1138708Y667113D01*
G01X1140295Y671812D02*
Y672195D01*
X1139440Y673050D01*
Y674911D01*
X1139245Y675106D01*
G01X1146594Y712756D02*
X1146556D01*
X1145000Y711200D01*
G01X1143444Y712756D02*
Y712709D01*
X1141765Y711030D01*
G01X1149744Y712756D02*
X1149706D01*
X1148169Y711219D01*
G01X1140295Y715906D02*
X1140275D01*
X1138729Y714360D01*
G01X1149744Y719056D02*
X1149713D01*
X1148135Y720634D01*
G01X1140295Y719056D02*
X1138718Y720633D01*
X1138685D01*
G01X1146594Y725355D02*
X1146219Y725730D01*
Y725798D01*
X1143627Y728390D01*
Y734173D01*
X1142952Y734848D01*
Y738984D01*
X1144366Y740398D01*
Y741034D01*
X1143729Y741671D01*
X1143093D01*
X1141679Y740257D01*
X1141043D01*
X1140406Y740894D01*
Y741530D01*
X1141820Y742944D01*
Y743580D01*
X1140300Y745100D01*
G01X1146594Y719056D02*
X1145318D01*
X1143993Y717731D01*
X1142083D01*
X1141870Y717518D01*
G01X1149744Y715906D02*
Y715940D01*
X1148167Y717517D01*
G01X1146594Y715906D02*
Y715868D01*
X1145053Y714327D01*
G01X1149744Y722205D02*
X1147919Y724030D01*
Y725904D01*
X1146598Y727225D01*
X1146291D01*
X1144725Y728791D01*
Y735609D01*
X1156916Y747800D01*
X1163731D01*
X1163830Y747899D01*
G01X1149744Y725355D02*
Y725423D01*
X1146992Y728175D01*
X1146685D01*
X1145675Y729185D01*
Y734225D01*
X1155500Y744050D01*
X1163750D01*
X1164200Y744500D01*
G01X1143444Y715906D02*
X1143407D01*
X1141840Y714339D01*
G01X1137145Y715906D02*
X1137156D01*
X1138730Y717480D01*
G01X1143444Y719056D02*
X1141920Y720580D01*
Y720617D01*
X1141904Y720633D01*
G01X1152893Y719056D02*
Y719107D01*
X1151500Y720500D01*
Y725800D01*
X1147400Y729900D01*
G01X1150734Y736950D02*
X1153302Y739518D01*
X1157680D01*
G01X1149470Y734451D02*
X1149943Y734924D01*
X1151978D01*
X1153777Y736723D01*
G01X1140300Y745100D02*
X1140100Y745300D01*
X1137030D01*
G01X1143218Y757114D02*
Y759782D01*
X1141500Y761500D01*
G01D02*
X1136100Y766900D01*
Y771464D01*
X1135969Y771595D01*
Y772841D01*
X1137394Y774266D01*
Y775335D01*
G01X1146843Y778485D02*
Y781872D01*
X1143602Y785113D01*
X1141700D01*
G01X1146843Y775335D02*
Y774202D01*
X1145118Y772477D01*
Y771595D01*
X1144284Y770761D01*
X1143261D01*
X1141600Y769100D01*
Y767400D01*
X1142700Y766300D01*
X1146200D01*
G01X1137394Y778485D02*
X1137100Y778779D01*
Y781278D01*
X1136236Y782142D01*
G01X1140544Y772186D02*
Y769144D01*
X1139695Y768295D01*
X1137997D01*
X1137400Y768892D01*
Y770176D01*
X1138819Y771595D01*
Y775926D01*
X1138800Y775945D01*
Y776779D01*
X1138961Y776940D01*
G01X1146843Y791083D02*
Y791097D01*
X1145270Y792670D01*
G01X1137394Y791083D02*
Y789103D01*
X1138545Y787952D01*
G01X1143693Y791083D02*
X1145636Y789140D01*
X1145740D01*
G01X1137394Y794233D02*
Y794195D01*
X1138931Y792658D01*
G01X1140544Y791083D02*
Y791055D01*
X1142086Y789513D01*
G01X1149992Y794233D02*
X1150033D01*
X1151590Y795790D01*
X1154700D01*
G01X1140544Y797382D02*
X1139052Y795890D01*
X1139030D01*
X1138970Y795830D01*
G01X1146843Y797382D02*
Y813093D01*
X1147750Y814000D01*
G01X1141750Y822500D02*
X1147750D01*
G01D02*
Y818000D01*
G01X1141750Y827000D02*
Y830950D01*
X1141100Y831600D01*
G01X1146500Y827000D02*
X1141750D01*
G01X1147750Y818000D02*
Y814000D01*
G01Y822500D02*
X1146500Y823750D01*
Y827000D01*
G01X1159934Y614672D02*
Y617066D01*
X1159500Y617500D01*
Y620250D01*
G01X1159934Y599672D02*
X1155172D01*
X1154000Y598500D01*
G01X1163500Y634250D02*
Y631500D01*
X1164500Y630500D01*
Y628723D01*
G01X1159500Y634250D02*
Y631025D01*
X1159075Y630600D01*
G01X1155500Y634250D02*
Y631561D01*
X1154847Y630908D01*
G01X1159500Y620250D02*
X1159750Y620500D01*
X1163500D01*
G01X1167500Y624250D02*
X1167250D01*
X1163500Y620500D01*
G01X1151500Y634250D02*
Y630250D01*
G01D02*
Y630000D01*
X1154426Y627074D01*
Y625574D01*
X1155500Y624500D01*
G01X1151500Y626750D02*
Y622750D01*
G01X1159500Y623750D02*
Y624500D01*
X1156377Y627623D01*
G01X1163500Y637750D02*
X1162700Y638550D01*
Y640100D01*
X1157285Y645515D01*
Y649100D01*
G01X1163600Y642700D02*
X1161000Y645300D01*
Y650547D01*
X1157608Y653939D01*
Y660184D01*
X1156043Y661749D01*
Y662363D01*
G01X1167500Y637750D02*
X1165500Y639750D01*
Y640800D01*
X1163600Y642700D01*
G01X1152785Y646200D02*
Y651717D01*
X1152893Y651825D01*
Y659213D01*
G01X1155500Y637750D02*
X1152785Y640465D01*
Y646200D01*
G01X1159500Y637750D02*
X1156400Y640850D01*
Y642600D01*
G01D02*
X1155035Y643965D01*
Y652917D01*
X1154288Y653664D01*
Y663301D01*
X1152893Y664696D01*
Y665512D01*
G01X1183000Y628000D02*
X1181723D01*
X1164332Y645391D01*
Y656372D01*
X1162342Y658362D01*
Y659213D01*
G01X1156043D02*
Y654159D01*
X1157285Y652917D01*
Y649100D01*
G01X1156043Y665512D02*
X1157599Y663956D01*
G01X1159192Y662363D02*
X1160748Y660807D01*
G01X1159192Y659213D02*
X1160748Y657657D01*
G01X1165492Y662363D02*
Y662400D01*
X1163946Y663946D01*
G01X1159192Y671812D02*
X1157613Y673391D01*
Y673418D01*
G01X1152893Y668662D02*
X1151351Y667120D01*
X1151314D01*
X1151282Y667088D01*
G01X1165492Y668662D02*
Y668700D01*
X1163917Y670275D01*
G01X1162342Y668662D02*
X1162304D01*
X1160741Y667099D01*
G01X1165492Y671812D02*
X1165454D01*
X1163914Y673352D01*
G01X1165492Y665512D02*
Y665550D01*
X1167034Y667092D01*
G01X1162342Y665512D02*
X1162380D01*
X1163944Y667076D01*
G01X1156043Y671812D02*
X1154487Y670256D01*
G01X1152893Y712756D02*
X1151449Y714200D01*
X1151413D01*
X1151307Y714306D01*
G01X1167048Y714312D02*
X1165492Y712756D01*
G01X1156043D02*
X1154464Y714335D01*
X1154434D01*
G01X1162342Y712756D02*
X1163892Y711206D01*
X1163905D01*
G01X1157636Y711200D02*
X1159192Y712756D01*
G01X1156043Y722205D02*
Y722543D01*
X1157368Y723868D01*
Y729132D01*
X1155375Y731125D01*
Y735174D01*
X1157680Y737479D01*
Y739518D01*
G01X1156043Y725355D02*
Y728889D01*
X1154260Y730672D01*
Y736240D01*
X1153777Y736723D01*
G01X1152893Y715906D02*
Y715943D01*
X1151318Y717518D01*
G01X1159192Y715906D02*
Y715908D01*
X1157637Y717463D01*
G01X1159192Y719056D02*
X1157700Y720548D01*
Y720585D01*
X1157643Y720642D01*
G01X1156043Y715906D02*
X1157580Y714369D01*
Y714332D01*
X1157581Y714331D01*
G01X1156043Y719056D02*
X1156005D01*
X1154430Y717481D01*
G01X1165492Y715906D02*
X1166750Y717164D01*
Y717202D01*
X1167049Y717501D01*
G01X1165492Y719056D02*
X1167048Y720612D01*
G01X1162342Y715906D02*
X1163898Y717462D01*
G01X1171500Y733725D02*
X1171450Y733775D01*
Y738792D01*
X1170549Y739693D01*
Y739728D01*
X1167877Y742400D01*
X1163600D01*
X1163025Y741825D01*
Y740141D01*
X1163475Y739691D01*
X1164250D01*
X1164700Y739241D01*
Y738341D01*
X1164250Y737891D01*
X1163475D01*
X1163025Y737441D01*
Y736541D01*
X1163475Y736091D01*
X1164250D01*
X1164700Y735641D01*
Y734741D01*
X1164250Y734291D01*
X1163475D01*
X1163025Y733841D01*
Y732678D01*
X1162342Y731995D01*
Y725355D01*
G01Y722205D02*
X1163500D01*
X1164000Y722705D01*
Y731699D01*
X1165426Y733125D01*
X1166443D01*
X1166893Y733575D01*
Y738350D01*
X1167343Y738800D01*
X1168243D01*
X1168693Y738350D01*
Y733575D01*
X1170168Y732100D01*
X1172230D01*
X1175000Y734870D01*
G01X1162342Y719056D02*
X1163898Y720612D01*
G01X1153142Y778485D02*
Y780940D01*
X1153219Y781017D01*
Y781303D01*
G01X1153142Y775335D02*
Y775346D01*
X1151564Y776924D01*
G01X1156292Y778485D02*
Y781398D01*
X1153500Y784190D01*
G01X1162591Y775335D02*
X1164016Y773910D01*
Y770494D01*
X1167002Y767508D01*
G01X1159441Y778485D02*
X1159900Y778944D01*
Y784571D01*
X1161022Y785693D01*
G01X1165740Y775335D02*
X1167260Y776855D01*
Y776870D01*
X1167326Y776936D01*
G01X1159441Y791083D02*
X1161545Y788979D01*
Y788844D01*
G01X1156292Y791083D02*
X1157517D01*
X1157900Y790700D01*
Y787907D01*
X1158092Y787715D01*
G01X1153142Y794233D02*
Y794212D01*
X1151590Y792660D01*
G01X1162591Y794233D02*
X1164241Y792583D01*
Y788322D01*
X1165063Y787500D01*
G01X1162591Y791083D02*
X1163270Y790404D01*
Y786853D01*
X1164593Y785530D01*
X1167410D01*
G01X1181250Y248000D02*
X1181427Y251500D01*
G01D02*
X1179500Y253427D01*
Y253506D01*
X1179345Y253661D01*
G01X1180677Y256500D02*
X1182177Y255000D01*
X1187000D01*
G01X1182000Y360250D02*
Y357000D01*
G01X1189750Y359000D02*
X1185250Y354500D01*
X1176500D01*
X1174500Y356500D01*
X1174400D01*
G01X1178000Y360250D02*
Y356500D01*
G01X1182000Y363750D02*
X1178000D01*
G01X1182660Y373910D02*
Y370660D01*
X1179500Y367500D01*
G01X1178000Y363750D02*
Y366000D01*
X1179500Y367500D01*
G01X1183000Y396500D02*
Y400250D01*
G01X1185220Y390090D02*
Y393780D01*
X1183000Y396000D01*
Y396500D01*
G01Y400250D02*
X1179000D01*
G01X1173500Y550400D02*
Y554000D01*
G01X1186500Y597250D02*
X1183150D01*
X1181350Y595450D01*
G01X1179934Y589068D02*
Y594034D01*
X1181350Y595450D01*
G01X1179934Y614672D02*
X1185172D01*
X1186000Y615500D01*
G01X1186500Y600750D02*
X1185422Y599672D01*
X1179934D01*
G01X1173250Y621000D02*
Y614750D01*
X1173500Y614500D01*
Y606500D01*
X1175328Y604672D01*
X1179934D01*
G01X1173250Y621000D02*
Y625750D01*
X1173000Y626000D01*
G01X1177100Y624750D02*
X1176750Y624400D01*
Y621000D01*
G01D02*
X1180500D01*
G01X1194000Y637200D02*
X1184351Y646849D01*
X1181969D01*
X1177818Y651000D01*
X1177667D01*
X1176290Y652377D01*
Y659773D01*
X1174940Y661123D01*
Y662363D01*
G01Y665512D02*
X1173366Y663938D01*
X1173332D01*
G01X1178090Y662363D02*
X1178059D01*
X1176506Y663916D01*
G01X1195000Y643000D02*
X1193711D01*
X1187684Y649027D01*
Y650416D01*
X1179500Y658600D01*
Y663500D01*
X1178090Y664910D01*
Y665512D01*
G01X1181240Y662363D02*
Y661760D01*
X1182964Y660036D01*
Y658011D01*
X1189155Y651820D01*
X1190479D01*
X1194599Y647700D01*
X1203800D01*
X1203875Y647625D01*
X1203881D01*
X1205125Y646381D01*
Y646375D01*
X1207826Y643674D01*
X1207869D01*
G01X1242900Y647000D02*
X1240000D01*
X1229500Y657500D01*
X1203000D01*
X1201175Y659325D01*
X1189675D01*
X1188250Y660750D01*
X1187136D01*
X1186000Y661886D01*
Y662768D01*
X1184768Y664000D01*
X1183500D01*
X1181988Y665512D01*
X1181240D01*
G01X1182900Y649100D02*
X1178900Y653100D01*
X1178500D01*
G01X1202500Y638500D02*
X1200225Y640775D01*
X1193138D01*
X1185734Y648219D01*
Y650965D01*
X1178090Y658610D01*
Y659213D01*
G01Y678111D02*
X1176525Y679676D01*
G01X1168641Y671812D02*
X1167692Y672761D01*
Y674996D01*
G01X1168641Y668662D02*
X1170158Y670179D01*
Y670217D01*
X1170181Y670240D01*
G01X1174940Y671812D02*
X1176503Y670249D01*
Y670218D01*
G01X1181240Y668662D02*
Y668260D01*
X1182500Y667000D01*
X1188000D01*
X1188500Y667500D01*
X1190500D01*
X1191000Y667000D01*
G01X1184389Y668662D02*
X1184375D01*
X1182803Y670234D01*
G01X1178090Y671812D02*
X1176534Y673368D01*
G01X1181240Y671812D02*
X1179728Y670300D01*
X1179719D01*
X1179653Y670234D01*
G01X1174940Y674961D02*
X1174925D01*
X1173370Y673406D01*
X1173309D01*
G01X1178090Y674961D02*
X1179630Y673421D01*
X1179662D01*
G01X1181240Y674961D02*
X1182807Y673394D01*
X1189687D01*
X1190500Y674207D01*
G01X1174940Y678111D02*
X1176496Y676555D01*
X1176534D01*
G01X1178090Y681260D02*
X1179613Y679737D01*
Y679709D01*
X1179667Y679655D01*
G01X1181240Y681260D02*
X1182831Y679669D01*
Y679666D01*
G01X1181240Y678111D02*
X1181277D01*
X1182815Y676573D01*
G01X1171791Y668662D02*
X1171754D01*
X1170192Y667100D01*
G01X1178090Y668662D02*
X1176526Y667098D01*
Y667092D01*
G01X1171791Y671812D02*
X1173289Y670314D01*
X1173326D01*
X1173403Y670237D01*
G01X1181240Y684410D02*
X1182692Y685862D01*
Y685884D01*
X1182785Y685977D01*
G01X1174940Y687560D02*
X1176320Y686180D01*
Y686170D01*
X1176520Y685970D01*
G01X1178090Y684410D02*
X1179495Y685815D01*
X1179519D01*
X1179663Y685959D01*
G01X1174940Y684410D02*
Y684426D01*
X1173392Y685974D01*
G01X1174940Y681260D02*
Y681298D01*
X1176482Y682840D01*
G01X1178090Y690709D02*
X1176529Y692270D01*
Y692276D01*
G01X1181240Y690709D02*
X1179685Y692264D01*
Y692292D01*
G01X1174940Y693859D02*
X1176496Y695415D01*
G01X1178090Y693859D02*
X1179664Y695433D01*
Y695466D01*
G01X1181240Y693859D02*
X1182796Y695415D01*
G01X1174940Y690709D02*
X1173384Y692265D01*
G01X1171791Y712756D02*
X1170270Y714277D01*
Y714308D01*
X1170248Y714330D01*
G01X1206500Y706000D02*
X1206000Y706500D01*
X1193098D01*
X1191816Y707782D01*
X1187490D01*
X1185878Y709394D01*
Y709992D01*
X1184439Y711431D01*
X1183840D01*
X1182515Y712756D01*
X1181240D01*
G01X1216000Y741000D02*
X1204500D01*
X1201475Y737975D01*
X1201389D01*
X1198039Y734625D01*
X1191889D01*
X1191863Y734599D01*
X1191156D01*
X1185925Y729368D01*
Y729107D01*
X1182964Y726146D01*
Y725063D01*
X1181831Y723930D01*
X1180949D01*
X1179224Y722205D01*
X1178090D01*
G01X1174940Y719056D02*
Y719020D01*
X1173400Y717480D01*
G01X1178090Y715906D02*
X1179576Y714420D01*
X1179614D01*
X1179703Y714331D01*
G01X1181240Y725355D02*
Y725766D01*
X1184974Y729500D01*
Y729761D01*
X1190762Y735549D01*
X1191469D01*
X1191923Y736003D01*
X1193338D01*
X1193910Y736575D01*
X1196388D01*
X1196500Y736687D01*
G01X1171791Y715906D02*
X1173347Y714350D01*
G01X1178090Y719056D02*
X1178052D01*
X1176499Y720609D01*
G01X1174940Y715906D02*
Y715905D01*
X1176503Y714342D01*
G01X1183370Y735070D02*
Y732509D01*
X1179861Y729000D01*
X1179500D01*
X1176265Y725765D01*
Y724806D01*
X1175489Y724030D01*
X1174500D01*
X1173470Y723000D01*
X1172586D01*
X1171791Y722205D01*
G01Y725355D02*
Y725791D01*
X1178525Y732525D01*
Y736469D01*
X1178180Y736814D01*
Y741180D01*
X1178500Y741500D01*
G01X1182000Y745500D02*
Y739830D01*
X1179560Y737390D01*
Y731849D01*
X1173615Y725904D01*
Y725305D01*
X1172310Y724000D01*
X1171712D01*
X1170466Y722754D01*
Y720881D01*
X1168641Y719056D01*
G01X1175500Y748000D02*
Y739426D01*
X1176119Y738807D01*
Y737531D01*
X1177575Y736075D01*
Y733802D01*
X1170000Y726227D01*
Y724000D01*
X1168641Y722641D01*
Y722205D01*
G01Y715906D02*
Y715943D01*
X1170199Y717501D01*
G01X1168641Y725355D02*
Y726212D01*
X1176625Y734196D01*
Y735544D01*
X1175674Y736495D01*
X1175673D01*
X1173400Y738768D01*
Y740100D01*
X1172000Y741500D01*
Y744000D01*
G01X1184500Y749500D02*
Y739562D01*
X1180520Y735582D01*
Y731420D01*
X1174940Y725840D01*
Y725355D01*
G01X1171791Y719056D02*
Y719291D01*
X1173113Y720613D01*
X1173348D01*
G01X1176489Y717469D02*
X1179653D01*
X1181240Y719056D01*
G01X1206040Y732500D02*
X1200016D01*
X1198966Y731450D01*
X1193398D01*
X1192948Y731000D01*
X1190612D01*
X1186000Y726388D01*
Y724915D01*
X1185085Y724000D01*
X1185050D01*
X1184980Y723930D01*
X1183930D01*
X1182205Y722205D01*
X1181240D01*
G01X1178090Y725355D02*
Y725635D01*
X1195955Y743500D01*
X1199500D01*
G01X1189000Y742250D02*
Y740700D01*
X1183370Y735070D01*
G01X1180000Y753750D02*
Y752000D01*
X1178500Y750500D01*
Y741500D01*
G01X1184000Y753750D02*
Y753000D01*
X1182000Y751000D01*
Y745500D01*
G01X1172000Y744000D02*
Y753750D01*
G01X1176000Y757250D02*
Y761500D01*
X1187500Y773000D01*
X1188500D01*
G01X1180000Y757250D02*
Y761500D01*
X1184975Y766475D01*
Y767500D01*
G01X1176000Y753750D02*
Y748500D01*
X1175500Y748000D01*
G01X1184500Y772782D02*
X1181382D01*
X1172000Y763400D01*
Y761000D01*
G01D02*
Y757250D01*
G01X1168890Y778485D02*
X1169795D01*
X1170912Y777368D01*
X1171108D01*
G01X1168890Y794233D02*
X1170900Y792223D01*
Y784923D01*
X1170911Y784912D01*
G01X1168890Y791083D02*
X1169170Y790803D01*
Y783666D01*
X1170718Y782118D01*
G01X1195927Y238000D02*
X1196027Y238100D01*
X1203900D01*
X1206250Y235750D01*
X1207500D01*
G01X1195927Y242500D02*
X1197739Y240688D01*
X1199144D01*
X1199782Y240050D01*
X1204708D01*
X1205258Y239500D01*
X1207500D01*
G01X1215256Y240945D02*
X1211555D01*
X1210900Y241600D01*
X1205916D01*
X1205516Y242000D01*
X1200590D01*
X1199677Y242913D01*
G01X1184750Y244000D02*
X1189500D01*
X1189825Y244325D01*
X1198265D01*
X1199677Y242913D01*
G01X1192427Y252500D02*
X1189500D01*
X1187000Y255000D01*
G01X1184750Y248000D02*
Y249500D01*
X1185750Y250500D01*
X1199177D01*
X1199677Y251000D01*
G01X1215256Y250394D02*
X1209830D01*
X1209224Y251000D01*
X1199677D01*
G01X1215256Y253544D02*
X1198471D01*
X1195927Y252500D01*
G01D02*
Y256750D01*
X1195677Y257000D01*
G01X1192427Y247500D02*
X1189000D01*
X1188000Y248500D01*
G01X1207700Y244095D02*
X1202405D01*
X1199000Y247500D01*
X1195927D01*
G01X1189750Y363500D02*
X1192000Y361250D01*
Y358309D01*
X1185191Y351500D01*
X1184000D01*
G01X1185220Y373910D02*
Y367720D01*
X1185000Y367500D01*
G01X1186250Y359000D02*
Y363500D01*
G01D02*
Y366250D01*
X1185000Y367500D01*
G01X1197000Y366000D02*
X1195000Y368000D01*
X1190000D01*
X1187780Y370220D01*
Y373910D01*
G01Y390090D02*
Y396280D01*
X1188000Y396500D01*
G01D02*
X1187000Y397500D01*
Y400250D01*
G01D02*
X1191000D01*
G01X1198500Y396000D02*
X1199000Y396500D01*
Y400250D01*
G01X1190340Y390090D02*
X1192590D01*
X1198500Y396000D01*
G01X1199000Y400250D02*
X1195000D01*
G01X1200250Y605500D02*
X1196300D01*
X1196000Y605800D01*
G01X1186500Y604600D02*
Y600750D01*
G01X1209000Y634250D02*
Y637242D01*
X1203242Y643000D01*
X1195000D01*
G01X1194000Y637200D02*
X1198050D01*
X1201000Y634250D01*
G01X1187539Y665512D02*
X1188051Y665000D01*
X1193000D01*
X1194500Y663500D01*
X1228500D01*
X1235294Y656706D01*
X1235794D01*
X1238838Y653662D01*
G01X1214000Y642500D02*
X1206850Y649650D01*
X1195407D01*
X1192007Y653050D01*
X1190106D01*
X1185050Y658106D01*
Y658552D01*
X1184389Y659213D01*
G01X1204500Y659500D02*
X1202725Y661275D01*
X1190285D01*
X1189197Y662363D01*
X1187539D01*
G01X1184389Y665512D02*
X1184988D01*
X1186500Y664000D01*
X1190000D01*
X1191000Y663000D01*
G01X1193804Y657175D02*
X1200525D01*
X1202200Y655500D01*
X1227250D01*
X1239750Y643000D01*
X1250250D01*
G01X1230500D02*
X1221900Y651600D01*
X1196342D01*
X1193942Y654000D01*
X1190500D01*
X1186000Y658500D01*
Y660000D01*
X1184389Y661611D01*
Y662363D01*
G01X1187539Y659213D02*
X1188443D01*
X1192206Y655450D01*
X1195250D01*
X1197150Y653550D01*
X1225450D01*
X1227500Y651500D01*
G01X1187539Y671812D02*
X1226812D01*
X1228000Y673000D01*
G01X1184389Y674961D02*
Y674997D01*
X1185965Y676573D01*
G01X1235000Y682000D02*
X1219000D01*
X1215143Y678143D01*
X1190000D01*
X1188707Y679436D01*
X1185714D01*
X1184389Y678111D01*
G01X1231450Y677500D02*
X1223750D01*
X1219893Y673643D01*
X1195351D01*
X1192994Y676000D01*
X1188578D01*
X1187539Y674961D01*
G01X1231000Y665000D02*
X1230500Y665500D01*
X1197500D01*
G01X1238500Y663000D02*
X1236758D01*
X1232258Y667500D01*
X1195500D01*
X1194275Y668725D01*
X1187602D01*
X1187539Y668662D01*
G01X1184389Y671812D02*
X1185665D01*
X1186990Y670487D01*
X1188825D01*
X1188862Y670450D01*
X1194550D01*
X1195500Y669500D01*
X1234100D01*
X1238300Y665300D01*
X1243000D01*
X1243200Y665100D01*
X1246855D01*
G01X1187539Y678111D02*
X1188688D01*
X1189606Y677193D01*
X1194051D01*
X1195351Y675893D01*
X1216075D01*
X1218293Y678111D01*
X1221111D01*
X1221500Y678500D01*
X1221568D01*
X1222818Y679750D01*
X1235933D01*
X1237433Y681250D01*
X1238250D01*
X1240000Y683000D01*
G01X1187539Y681260D02*
X1188227D01*
X1189694Y679793D01*
X1214004D01*
X1221711Y687500D01*
X1246000D01*
G01X1184389Y690709D02*
X1185714Y692034D01*
X1187834D01*
X1191875Y696075D01*
X1211000D01*
G01X1244824Y702176D02*
X1242648Y700000D01*
X1219926D01*
X1212926Y693000D01*
X1193100D01*
X1190809Y690709D01*
X1187539D01*
G01X1212000Y685000D02*
X1209018Y682018D01*
X1189482D01*
X1188890Y682610D01*
X1185610D01*
X1184389Y681389D01*
Y681260D01*
G01X1208000Y727500D02*
X1205500Y730000D01*
X1194000D01*
X1189355Y725355D01*
X1187539D01*
G01X1207000Y720500D02*
X1205000Y722500D01*
X1200108D01*
X1199108Y721500D01*
X1193500D01*
X1191056Y719056D01*
X1187539D01*
G01X1202000Y715000D02*
X1199894D01*
X1199369Y715525D01*
X1189032D01*
X1188088Y714581D01*
X1185714D01*
X1184389Y715906D01*
G01X1208000Y738500D02*
X1204051D01*
X1202086Y736535D01*
Y736500D01*
X1199561Y733975D01*
X1199440D01*
X1198640Y733175D01*
X1192938D01*
X1192913Y733150D01*
X1191150D01*
X1186901Y728901D01*
Y728704D01*
X1184389Y726192D01*
Y725355D01*
G01X1192000Y753750D02*
X1192132Y750718D01*
X1196500Y746350D01*
Y745500D01*
G01X1189000Y745750D02*
X1192250D01*
X1192500Y745500D01*
G01X1192000Y753750D02*
X1188000D01*
G01D02*
X1187500D01*
X1184000Y757250D01*
G01X1194000Y764500D02*
X1195500Y766000D01*
Y776500D01*
G01X1215500Y851750D02*
Y839500D01*
X1195500Y819500D01*
Y776500D01*
G01X1191500Y807000D02*
Y769000D01*
X1190000Y767500D01*
G01X1201500Y851750D02*
Y831000D01*
X1191500Y821000D01*
Y807000D01*
G01X1201500Y855250D02*
X1197000D01*
G01D02*
X1198500Y856750D01*
Y862250D01*
G01X1215256Y234646D02*
X1210854D01*
X1209750Y235750D01*
X1207500D01*
G01X1215256Y237796D02*
X1210704D01*
X1209000Y239500D01*
X1207500D01*
G01X1215256Y244095D02*
X1207700D01*
G01X1203750Y605500D02*
Y596920D01*
X1203830Y596840D01*
G01X1207700Y605500D02*
X1203750D01*
G01X1227500Y504246D02*
X1227575Y504321D01*
Y560474D01*
X1228945Y561844D01*
Y611055D01*
X1213000Y627000D01*
Y630750D01*
G01X1209000D02*
Y625343D01*
X1226995Y607348D01*
Y562652D01*
X1219575Y555232D01*
Y538702D01*
X1222425Y535852D01*
Y505575D01*
X1227500Y500500D01*
G01X1205000Y630750D02*
Y626500D01*
X1208500Y623000D01*
G01X1201000Y630750D02*
X1201250Y630500D01*
Y627000D01*
G01X1217000Y634250D02*
Y639500D01*
X1214000Y642500D01*
G01X1207869Y643674D02*
Y643631D01*
X1213000Y638500D01*
Y634250D01*
G01X1205000D02*
Y636000D01*
X1202500Y638500D01*
G01X1250250Y707500D02*
X1247000D01*
X1241800Y702300D01*
X1219468D01*
X1213243Y696075D01*
X1211000D01*
G01X1237250Y729500D02*
X1232250Y724500D01*
X1228000D01*
X1226000Y726500D01*
X1209000D01*
X1208000Y727500D01*
G01X1206040Y732500D02*
X1207500D01*
X1212000Y728000D01*
X1215250D01*
X1218250Y731000D01*
G01X1222250Y740500D02*
X1221750Y741000D01*
X1216000D01*
G01X1208000Y738500D02*
X1215250D01*
X1218250Y735500D01*
G01X1201968Y764534D02*
Y766468D01*
X1204500Y769000D01*
G01X1205160Y775850D02*
Y769660D01*
X1204500Y769000D01*
G01X1210280Y792150D02*
X1210330Y790516D01*
Y795330D01*
X1215500Y800500D01*
G01X1212840Y792150D02*
X1218350D01*
X1219716Y790784D01*
X1219968D01*
G01X1207688Y800688D02*
X1207720Y792150D01*
G01X1220000Y805750D02*
X1215748D01*
X1215716Y805718D01*
G01D02*
Y800716D01*
X1215500Y800500D01*
G01X1211216Y805718D02*
X1207032D01*
G01D02*
X1207688Y805062D01*
Y800688D01*
G01X1207032Y805718D02*
X1207000Y805750D01*
G01Y809250D02*
Y823000D01*
X1218500Y834500D01*
G01X1215716Y809218D02*
X1219498Y813000D01*
X1227500D01*
X1235258Y820758D01*
G01X1211216Y809218D02*
Y814716D01*
X1223000Y826500D01*
G01X1201500Y855250D02*
X1201750Y855000D01*
X1205100D01*
G01X1211000Y855250D02*
X1215500D01*
G01X1211000D02*
X1211500Y855750D01*
Y862250D01*
G01X1215500Y855250D02*
X1215750Y855500D01*
X1219100D01*
G01X1232776Y234646D02*
X1237354D01*
X1238554Y233446D01*
X1244549D01*
X1247495Y230500D01*
X1249000D01*
G01X1232776Y231496D02*
X1243741D01*
X1249649Y225588D01*
G01X1232776Y240945D02*
X1238555D01*
X1241169Y238331D01*
X1244997D01*
G01X1232776Y237796D02*
X1238704D01*
X1240829Y235671D01*
X1241000D01*
G01X1232776Y244095D02*
X1241405D01*
X1242000Y243500D01*
G01X1232776Y247245D02*
X1241487D01*
X1242500Y248258D01*
X1242636D01*
G01X1232776Y256693D02*
X1238684D01*
X1240377Y255000D01*
G01Y259843D02*
X1232776D01*
G01X1333403Y643634D02*
Y638903D01*
X1325500Y631000D01*
X1310000D01*
X1291550Y612550D01*
X1244120D01*
X1235213Y603643D01*
Y553713D01*
X1233557Y552057D01*
Y543893D01*
X1234582Y542868D01*
Y537057D01*
X1230525Y533000D01*
X1229500D01*
G01X1325533Y643634D02*
Y640669D01*
X1322569Y637705D01*
X1312533D01*
X1290328Y615500D01*
X1242898D01*
X1231900Y604502D01*
Y560627D01*
X1230607Y559334D01*
Y542671D01*
X1231632Y541646D01*
Y537000D01*
G01X1219200Y564600D02*
X1216720Y567080D01*
Y568510D01*
G01D02*
X1220370Y572160D01*
Y576840D01*
G01X1250250Y635000D02*
X1238500D01*
X1230500Y643000D01*
G01X1227500Y651500D02*
X1240000Y639000D01*
X1250250D01*
G01Y657000D02*
X1239000D01*
X1231000Y665000D01*
G01X1237500Y675500D02*
X1230500D01*
X1228000Y673000D01*
G01X1231450Y677500D02*
X1236865D01*
X1238365Y679000D01*
X1243500D01*
G01X1225750Y718500D02*
X1226500D01*
X1229000Y716000D01*
G01X1222250Y718500D02*
X1220000D01*
X1218650Y719850D01*
X1218040D01*
G01X1225750Y740500D02*
Y739750D01*
X1229500Y736000D01*
X1239500D01*
X1241000Y734500D01*
G01X1218250Y731000D02*
X1222250D01*
G01X1218250Y735500D02*
X1222250D01*
G01X1226500Y767500D02*
X1226750D01*
X1232250Y762000D01*
G01D02*
X1235500D01*
X1238000Y764500D01*
G01X1230219Y747469D02*
Y747495D01*
X1232250Y749526D01*
Y753000D01*
G01D02*
X1233170Y753920D01*
X1238420D01*
X1241500Y757000D01*
G01X1236500Y757500D02*
X1232250D01*
G01X1225500Y789750D02*
X1224466Y790784D01*
X1219968D01*
G01X1257950Y809250D02*
X1220000D01*
G01X1221750Y831500D02*
X1221016Y832234D01*
Y840984D01*
G01X1225250Y831500D02*
X1229500D01*
G01X1235540Y834350D02*
X1232690Y831500D01*
X1229500D01*
G01X1253738Y235000D02*
X1248511D01*
X1246165Y237346D01*
X1245982D01*
X1244997Y238331D01*
G01X1253738Y230500D02*
X1251238Y233000D01*
X1247753D01*
X1245357Y235396D01*
X1241275D01*
X1241000Y235671D01*
G01X1253738Y226000D02*
Y226939D01*
X1250177Y230500D01*
X1249000D01*
G01X1247427Y241500D02*
X1245427Y243500D01*
X1242000D01*
G01X1247427Y245500D02*
X1245394D01*
X1242636Y248258D01*
G01X1243927Y255000D02*
X1240377D01*
G01X1243927Y259500D02*
X1240843D01*
X1240500Y259843D01*
X1240377D01*
G01X1247427Y255000D02*
X1262500D01*
X1262558Y254942D01*
G01X1247427Y259500D02*
X1252677D01*
G01X1240250Y593000D02*
X1239000D01*
X1238300Y593700D01*
Y602558D01*
X1241742Y606000D01*
X1274500D01*
G01X1240250Y598000D02*
Y600000D01*
X1243750Y603500D01*
X1278500D01*
G01X1255000Y593000D02*
X1248000D01*
G01D02*
X1243750D01*
G01X1255000Y598000D02*
X1248000D01*
G01D02*
X1243750D01*
G01X1250250Y647000D02*
X1242900D01*
G01X1238838Y653662D02*
X1241500Y651000D01*
X1250250D01*
G01X1245750Y661000D02*
X1240500D01*
X1238500Y663000D01*
G01X1237500Y675500D02*
X1249000D01*
G01D02*
X1250250Y674250D01*
Y671000D01*
G01X1243500Y679000D02*
X1249250D01*
X1250250Y680000D01*
G01X1246855Y665100D02*
X1248350D01*
X1250250Y667000D01*
G01Y684000D02*
X1249750Y683500D01*
X1240500D01*
X1240000Y683000D01*
G01X1246000Y687500D02*
X1249750D01*
X1250250Y688000D01*
G01Y703500D02*
X1246148D01*
X1244824Y702176D01*
G01X1241500Y757000D02*
X1241984Y757484D01*
Y768500D01*
G01X1240016D02*
Y761500D01*
G01D02*
Y761016D01*
X1236500Y757500D01*
G01X1244250Y762000D02*
X1243953Y762297D01*
Y768500D01*
G01X1244250Y762000D02*
Y755500D01*
X1238750Y750000D01*
X1237000D01*
G01D02*
X1236500D01*
X1234000Y747500D01*
G01X1238047Y768500D02*
X1238000Y768453D01*
Y764500D01*
G01X1253500Y778465D02*
X1248950D01*
G01X1238047Y782500D02*
Y791953D01*
G01X1240016Y782500D02*
Y788928D01*
X1240045Y788957D01*
G01X1241984Y782500D02*
Y796000D01*
G01X1243953Y782500D02*
Y789000D01*
G01X1238100Y840850D02*
Y848400D01*
G01X1240660Y840850D02*
X1245850D01*
X1246000Y841000D01*
G01X1250600Y838850D02*
X1248450Y841000D01*
X1246000D01*
G01X1238100Y848400D02*
Y853850D01*
G01X1257238Y221500D02*
X1264000D01*
X1276500Y234000D01*
G01X1253738Y221500D02*
X1253737D01*
X1249649Y225588D01*
G01X1261677Y231000D02*
X1264177Y233500D01*
G01X1257238Y230500D02*
X1261177D01*
X1261677Y231000D01*
G01X1261177Y226000D02*
X1257238D01*
G01X1267677Y232500D02*
X1261177Y226000D01*
G01X1250927Y241500D02*
X1261677D01*
G01X1264600Y238800D02*
X1261900Y241500D01*
X1261677D01*
G01X1265500Y246500D02*
X1262677D01*
X1261677Y245500D01*
G01X1250927D02*
X1261677D01*
G01X1265900Y254900D02*
X1262600D01*
X1262558Y254942D01*
G01X1264500Y260000D02*
X1258000D01*
X1257500Y259500D01*
X1252677D01*
G01X1285700Y529700D02*
X1283900Y531500D01*
X1251500D01*
G01X1304700Y536000D02*
X1303700Y535000D01*
X1266000D01*
X1249773Y551227D01*
Y551500D01*
G01X1261250Y577000D02*
X1265000D01*
X1265500Y577500D01*
G01X1275000Y593000D02*
X1270500D01*
X1267500Y590000D01*
Y579500D01*
X1265500Y577500D01*
G01X1312867Y599912D02*
X1294888D01*
X1285200Y609600D01*
X1255300D01*
X1255000Y609300D01*
G01X1253750Y657000D02*
X1257750D01*
G01D02*
X1258000D01*
X1260225Y654775D01*
X1263411D01*
X1263663Y654523D01*
X1267911D01*
X1268805Y655405D01*
G01X1253750Y651000D02*
X1257750D01*
G01D02*
X1258000D01*
X1259825Y652825D01*
X1262603D01*
X1262875Y652553D01*
X1265447D01*
X1265500Y652500D01*
G01X1249250Y661000D02*
X1253500D01*
G01X1257100Y664300D02*
X1257750Y663650D01*
Y661000D01*
G01D02*
X1253500D01*
G01X1258500Y684000D02*
X1263000Y679500D01*
Y678742D01*
X1263121Y678621D01*
G01X1253750Y667000D02*
X1257750Y667500D01*
G01D02*
Y666750D01*
X1258900Y665600D01*
X1266000D01*
G01X1253750Y684000D02*
X1258500D01*
G01X1253750Y688000D02*
X1260600D01*
X1266500Y682100D01*
Y676000D01*
X1267500Y675000D01*
G01X1273000Y719750D02*
X1271750D01*
X1259500Y707500D01*
X1253750D01*
G01X1273000Y705750D02*
X1256000D01*
X1253750Y703500D01*
G01X1253500Y778465D02*
X1258715D01*
X1259250Y779000D01*
G01D02*
Y783000D01*
G01D02*
Y804250D01*
X1261000Y806000D01*
Y834250D01*
X1261850Y835100D01*
G01X1256350Y844100D02*
X1255850D01*
X1250600Y838850D01*
G01X1261850Y835100D02*
Y838225D01*
X1263850Y840225D01*
G01X1279401Y38583D02*
Y34599D01*
X1284000Y30000D01*
G01X1279401Y38583D02*
X1286818Y46000D01*
X1332000D01*
X1339000Y53000D01*
Y54000D01*
G01X1284500Y323250D02*
X1281000Y319750D01*
Y316500D01*
X1282750Y314750D01*
X1284500D01*
G01Y326750D02*
Y334000D01*
X1280500Y338000D01*
G01X1276000Y569000D02*
X1275750Y568750D01*
Y564500D01*
G01D02*
X1273404Y562154D01*
Y557000D01*
G01X1282000Y569000D02*
X1281750Y568750D01*
Y564500D01*
G01D02*
X1283596Y562654D01*
Y557000D01*
G01X1275000Y583000D02*
X1280000D01*
X1281000Y582000D01*
Y579000D01*
X1278000Y576000D01*
Y573200D01*
G01D02*
Y571000D01*
X1276000Y569000D01*
G01X1283225Y579501D02*
Y577275D01*
X1280450Y574500D01*
Y570550D01*
X1282000Y569000D01*
G01X1275000Y588000D02*
X1278000D01*
X1283225Y582775D01*
Y579501D01*
G01X1279340Y618660D02*
X1279660D01*
X1280575Y619575D01*
Y647575D01*
X1282000Y649000D01*
G01X1273250Y681000D02*
X1269527Y677277D01*
Y657973D01*
X1272451Y655049D01*
Y642500D01*
G01X1273250Y674500D02*
X1271777Y673027D01*
Y659223D01*
X1274701Y656299D01*
Y641201D01*
X1272502Y639002D01*
Y638900D01*
G01X1289500Y669000D02*
X1289000D01*
X1286750Y666750D01*
X1281960D01*
X1278243Y663033D01*
Y662582D01*
X1276000Y660250D01*
G01D02*
X1277000Y659250D01*
Y656000D01*
G01X1288818Y647754D02*
X1284500D01*
X1283254Y649000D01*
X1282000D01*
G01X1276000Y663750D02*
Y665500D01*
X1278815Y668315D01*
G01X1266000Y669000D02*
Y665600D01*
G01X1280500Y674500D02*
X1276750D01*
G01X1288318Y675314D02*
X1284814D01*
X1284000Y674500D01*
X1280500D01*
G01X1282500Y669561D02*
X1282061D01*
X1281500Y669000D01*
X1279500D01*
X1278815Y668315D01*
G01X1276750Y681000D02*
X1277250Y681500D01*
X1280500D01*
G01X1288318Y679254D02*
X1284246D01*
X1282000Y681500D01*
X1280500D01*
G01X1277000Y705750D02*
X1273000D01*
G01X1277000D02*
X1281000D01*
G01D02*
X1281750Y705000D01*
X1308500D01*
X1313500Y710000D01*
G01X1277000Y719750D02*
X1273000D01*
G01X1277000D02*
X1281000D01*
G01D02*
Y729500D01*
X1286500Y735000D01*
X1291000D01*
G01X1284000Y30000D02*
X1285827Y28173D01*
Y17914D01*
G01X1295670D02*
Y26330D01*
X1295500Y26500D01*
G01Y30750D02*
Y26500D01*
G01X1304050Y296500D02*
X1287372D01*
G01Y301500D02*
X1303000D01*
X1312750Y311250D01*
Y314000D01*
G01X1305250Y316500D02*
X1299000D01*
X1296000Y319500D01*
G01X1284500Y314750D02*
Y309372D01*
X1287372Y306500D01*
G01X1284825Y621500D02*
Y631901D01*
G01X1288818Y643814D02*
X1286000D01*
X1284825Y642639D01*
Y631901D01*
G01X1305118Y643814D02*
X1300186D01*
X1297050Y646950D01*
Y654450D01*
X1295500Y656000D01*
G01X1288818Y641849D02*
X1292000D01*
X1292543Y642392D01*
Y649306D01*
X1292130Y649719D01*
X1288818D01*
G01X1293968Y659534D02*
Y657532D01*
X1295500Y656000D01*
G01X1286500Y652500D02*
Y653500D01*
X1289468Y656468D01*
Y659534D01*
G01X1288818Y649719D02*
X1286500Y652037D01*
Y652500D01*
G01X1289468Y659534D02*
X1285000Y659750D01*
G01X1293968Y663034D02*
X1295934Y665000D01*
X1297500D01*
G01X1288318Y673349D02*
X1291849D01*
X1292043Y673543D01*
Y680957D01*
X1291781Y681219D01*
X1288318D01*
G01X1282500Y669561D02*
X1282939Y670000D01*
X1283750D01*
X1284750Y671000D01*
X1285969D01*
X1288318Y673349D01*
G01X1297468Y843534D02*
Y840968D01*
X1294575Y838075D01*
Y772425D01*
X1313325Y753675D01*
Y737325D01*
X1311000Y735000D01*
X1291000D01*
G01X1292968Y843534D02*
Y767668D01*
X1310500Y750136D01*
Y737500D01*
G01X1383084Y319907D02*
Y310584D01*
X1367075Y294575D01*
X1343925D01*
X1337000Y301500D01*
X1314872D01*
G01Y296500D02*
X1320000D01*
X1322500Y299000D01*
G01X1314872Y291500D02*
X1323000D01*
X1324000Y290500D01*
G01X1312750Y318000D02*
Y314000D01*
G01X1327498Y643634D02*
Y646502D01*
X1325500Y648500D01*
X1323000D01*
X1317000Y642500D01*
X1314500D01*
G01X1305118Y641849D02*
X1309651D01*
X1310302Y642500D01*
X1314500D01*
G01X1305118Y649719D02*
X1314294D01*
X1315500Y650925D01*
G01X1305118Y647754D02*
X1301746D01*
X1301393Y648107D01*
Y652393D01*
X1303500Y654500D01*
Y655500D01*
G01X1299968Y658034D02*
X1300966D01*
X1303500Y655500D01*
G01X1299968Y661534D02*
X1304266D01*
X1304400Y661400D01*
G01X1314500Y679500D02*
X1313700D01*
X1311700Y681500D01*
G01X1304618Y679254D02*
X1308154D01*
X1309631Y680731D01*
X1310931D01*
X1311700Y681500D01*
G01X1304618Y675314D02*
X1308801D01*
X1312115Y672000D01*
G01X1304618Y673349D02*
X1312167Y665800D01*
X1318700D01*
G01X1304618Y681219D02*
X1307299Y683900D01*
X1315100D01*
X1324000Y675000D01*
G01X1337468Y676534D02*
Y679532D01*
X1330000Y687000D01*
X1311800D01*
X1311300Y687500D01*
G01X1307468Y917034D02*
Y920968D01*
X1309925Y923425D01*
X1316429D01*
X1327950Y911904D01*
Y762450D01*
X1315425Y749925D01*
Y699775D01*
X1307150Y691500D01*
G01X1312500Y827000D02*
Y830750D01*
G01X1313784Y821032D02*
Y825716D01*
X1312500Y827000D01*
G01X1308500Y834250D02*
Y841000D01*
X1313500Y846000D01*
X1317742D01*
X1318113Y846371D01*
G01X1312500Y830750D02*
X1308500D01*
G01X1312500Y838000D02*
Y834250D01*
G01X1326000Y854000D02*
Y851500D01*
X1312500Y838000D01*
G01X1317000Y857500D02*
X1312500D01*
G01D02*
Y862000D01*
G01Y854000D02*
Y851000D01*
X1312000Y850500D01*
G01X1309438Y874634D02*
Y867804D01*
X1312500Y864742D01*
Y862000D01*
G01X1311403Y874634D02*
Y870597D01*
X1320000Y862000D01*
G01X1311403Y890934D02*
Y896653D01*
X1317500Y902750D01*
G01X1312468Y902784D02*
X1309438Y899754D01*
Y890934D01*
G01X1317500Y902750D02*
X1314500Y905750D01*
Y907516D01*
X1316968Y909984D01*
G01X1312468Y913534D02*
Y902784D01*
G01X1301968Y917034D02*
Y919968D01*
X1306875Y924875D01*
X1317030D01*
X1329400Y912505D01*
Y761400D01*
X1319000Y751000D01*
Y708000D01*
G01X1330750Y293000D02*
Y290693D01*
X1349018Y272425D01*
X1382425D01*
X1384500Y274500D01*
G01X1330750Y298000D02*
X1333500Y295250D01*
Y290277D01*
X1349702Y274075D01*
X1379075D01*
X1379500Y274500D01*
G01X1327250Y298000D02*
X1326250Y299000D01*
X1322500D01*
G01X1327250Y293000D02*
X1324750Y290500D01*
X1324000D01*
G01X1316250Y318000D02*
Y323250D01*
G01X1322500Y332250D02*
Y337000D01*
G01X1327000Y328750D02*
X1350334D01*
X1353084Y326000D01*
Y320611D01*
G01X1322500Y328750D02*
X1327000D01*
G01X1316250Y323250D02*
Y328000D01*
X1317000Y328750D01*
G01X1348084Y319907D02*
X1325843D01*
X1317000Y328750D01*
G01Y336000D02*
Y332250D01*
G01X1321707Y565252D02*
X1316367Y559912D01*
G01X1336743Y581762D02*
X1336262D01*
X1321707Y567207D01*
Y565252D01*
G01X1316367Y564412D02*
Y565662D01*
X1324117Y573412D01*
Y575512D01*
G01X1316367Y586412D02*
Y581912D01*
G01X1332967Y585538D02*
X1324117Y576688D01*
Y575512D01*
G01X1324917Y584912D02*
X1320502Y580497D01*
Y580297D01*
X1317617Y577412D01*
G01X1316367Y568912D02*
X1316450Y568995D01*
Y573000D01*
G01X1317617Y577412D02*
Y574167D01*
X1316450Y573000D01*
G01X1333317Y595381D02*
X1329569D01*
X1325950Y599000D01*
G01X1325900Y602100D02*
Y602078D01*
X1330629Y597349D01*
X1333317D01*
G01X1316367Y599912D02*
Y595412D01*
G01X1322717Y592412D02*
X1317867D01*
X1316367Y590912D01*
G01X1333317Y591443D02*
X1323686D01*
X1322717Y592412D01*
G01X1316367Y595412D02*
Y590912D01*
G01X1333317Y589475D02*
X1322780D01*
X1320617Y587312D01*
G01D02*
X1319717Y586412D01*
X1316367D01*
G01X1333317Y587506D02*
X1327511D01*
X1324917Y584912D01*
G01X1332967Y601286D02*
Y602462D01*
X1321617Y613812D01*
G01X1316367Y621412D02*
X1318617D01*
X1319617Y620412D01*
Y615812D01*
X1321617Y613812D01*
G01X1316367Y607912D02*
X1320066D01*
X1324066Y603912D01*
X1324088D01*
X1325900Y602100D01*
G01X1336743Y605062D02*
Y607536D01*
X1333292Y610987D01*
X1331042D01*
X1329017Y613012D01*
G01X1327617Y618662D02*
Y614412D01*
X1329017Y613012D01*
G01X1333317Y599318D02*
X1330994D01*
X1328608Y601704D01*
Y602921D01*
X1322617Y608912D01*
G01X1316367Y616912D02*
Y612412D01*
G01D02*
X1319217D01*
X1322617Y609012D01*
Y608912D01*
G01X1323117Y618662D02*
X1327617D01*
G01X1331438Y643634D02*
Y649562D01*
X1330075Y650925D01*
X1315500D01*
G01X1327498Y659934D02*
Y663502D01*
X1325200Y665800D01*
X1318700D01*
G01X1325533Y659934D02*
Y655467D01*
X1326000Y655000D01*
X1332500D01*
X1333403Y655903D01*
Y659934D01*
G01X1331438D02*
Y667562D01*
X1324000Y675000D01*
G01X1328968Y673034D02*
X1333468D01*
G01X1317500Y827000D02*
X1316500Y828000D01*
Y830750D01*
G01X1318784Y821032D02*
Y825716D01*
X1317500Y827000D01*
G01X1320500Y834250D02*
X1325250D01*
G01X1316500Y830750D02*
X1320500D01*
G01X1316500Y834250D02*
Y839000D01*
G01X1326000Y857500D02*
X1321500D01*
G01D02*
Y860500D01*
X1320000Y862000D01*
G01X1317000Y854000D02*
Y850500D01*
G01X1321500Y854000D02*
Y849758D01*
X1318113Y846371D01*
G01X1316968Y913534D02*
Y909984D01*
G01X1347000Y78000D02*
X1342250D01*
X1342000Y77750D01*
G01X1352000Y78250D02*
X1347250D01*
X1347000Y78000D01*
G01X1337500Y77000D02*
X1341250D01*
X1342000Y77750D01*
G01X1342875Y119750D02*
X1340250D01*
X1336500Y123500D01*
Y129000D01*
G01Y138750D02*
Y270874D01*
G01X1362250Y106000D02*
Y122750D01*
X1361000Y124000D01*
X1340500D01*
X1339000Y125500D01*
Y274000D01*
G01X1336500Y135250D02*
Y129000D01*
G01X1342639Y555024D02*
Y562390D01*
X1342617Y562412D01*
G01X1343867Y567412D02*
Y563662D01*
X1342617Y562412D01*
G01X1348595Y545800D02*
Y549148D01*
X1345770Y551973D01*
Y558565D01*
X1348117Y560912D01*
Y562412D01*
G01X1347367Y567412D02*
Y563162D01*
X1348117Y562412D01*
G01X1343867Y567412D02*
Y571200D01*
G01D02*
Y572867D01*
X1344617Y573617D01*
Y582112D01*
G01X1346586D02*
Y576414D01*
X1348500Y574500D01*
G01D02*
Y568545D01*
X1347367Y567412D01*
G01X1346586Y604712D02*
Y609381D01*
X1347617Y610412D01*
G01X1332117Y618662D02*
Y615545D01*
X1334384Y613278D01*
G01X1338711Y604712D02*
Y608951D01*
X1334384Y613278D01*
G01X1340680Y604712D02*
Y610349D01*
X1338867Y612162D01*
Y615534D01*
G01X1350017Y615812D02*
X1348167Y613962D01*
X1347667D01*
X1344617Y610912D01*
Y604712D01*
G01X1338867Y623912D02*
Y619412D01*
G01D02*
Y615534D01*
G01X1333403Y659934D02*
Y663903D01*
X1337500Y668000D01*
Y673002D01*
G01X1342000Y673000D02*
X1341998Y673002D01*
X1337500D01*
G01D02*
X1337468Y673034D01*
G01X1333468D02*
X1337468D01*
G01X1367067Y78544D02*
X1366773Y78250D01*
X1352000D01*
G01X1355000Y106000D02*
X1358750D01*
G01X1357875Y119750D02*
Y109875D01*
X1355000Y107000D01*
Y106000D01*
G01X1350000Y276500D02*
X1348084Y278416D01*
Y282053D01*
G01D02*
Y282757D01*
G01X1353084Y319907D02*
Y320611D01*
G01X1363117Y565662D02*
X1362617Y566162D01*
Y572412D01*
X1360117Y574912D01*
G01X1348554Y582112D02*
Y577975D01*
X1351617Y574912D01*
X1354117D01*
G01X1358617Y565662D02*
Y570412D01*
X1354117Y574912D01*
G01X1350523Y582112D02*
Y579006D01*
X1352442Y577087D01*
X1357942D01*
X1360117Y574912D01*
G01X1348554Y604712D02*
Y608349D01*
X1350617Y610412D01*
Y611117D01*
X1351912Y612412D01*
X1354317D01*
X1355517Y613612D01*
G01X1354417Y619662D02*
Y615383D01*
X1355517Y614283D01*
Y613612D01*
G01X1360617Y619662D02*
X1359262D01*
X1357300Y617700D01*
G01D02*
X1355338Y619662D01*
X1354417D01*
G01X1350617Y621162D02*
Y616412D01*
X1350017Y615812D01*
G01X1392657Y78544D02*
X1367067D01*
G01X1390004Y117145D02*
X1389859Y117000D01*
X1385500D01*
X1383500Y115000D01*
X1377500D01*
X1375355Y117145D01*
X1369720D01*
G01X1378084Y282053D02*
Y276500D01*
X1378189Y275979D01*
X1379500Y274668D01*
Y274500D01*
G01X1390004Y117145D02*
Y122600D01*
G01X1383084Y282053D02*
Y275584D01*
X1384084Y274584D01*
X1384416D01*
X1384500Y274500D01*
G01Y331500D02*
X1383084Y330084D01*
Y320611D01*
G01D02*
Y319907D01*
G54D177*
G01X674666Y82002D02*
Y86794D01*
G01D02*
X678616D01*
X680366Y88544D01*
G01X677586Y114964D02*
X672044D01*
X670998Y116010D01*
G01X706716Y87034D02*
Y82448D01*
G01X711216Y87034D02*
Y82402D01*
G01X720216Y87034D02*
Y82138D01*
G01X731716Y152034D02*
Y156500D01*
G01X1134500Y826960D02*
X1129760D01*
X1128500Y825700D01*
G01X1138250Y827000D02*
X1138210Y826960D01*
X1134500D01*
G01X1150258Y756944D02*
Y766242D01*
X1147080Y769420D01*
X1146480D01*
G01D02*
X1146370Y769310D01*
G01X1138250Y822500D02*
Y827000D01*
G01X1156768Y757034D02*
Y768178D01*
X1158100Y769510D01*
Y769700D01*
G01X1164200Y756950D02*
Y765672D01*
X1162450Y767422D01*
Y769190D01*
G54D75*
X251500Y908565D03*
X1052500Y245435D03*
G54D93*
X332000Y123900D03*
Y126100D03*
X334500Y123900D03*
Y126100D03*
X342429Y330900D03*
Y333100D03*
X346429Y330900D03*
Y333100D03*
X342429Y345400D03*
Y347600D03*
X345929Y345400D03*
Y347600D03*
Y358900D03*
Y361100D03*
X342429Y358900D03*
Y361100D03*
X343555Y439900D03*
Y442100D03*
X339555Y439900D03*
Y442100D03*
X335555Y439900D03*
Y442100D03*
X331555Y439900D03*
Y442100D03*
X359555Y439900D03*
Y442100D03*
X355555Y439900D03*
Y442100D03*
X351555Y439900D03*
Y442100D03*
X347555Y439900D03*
Y442100D03*
X367000Y439900D03*
Y442100D03*
X363555Y439900D03*
Y442100D03*
X407555Y448900D03*
Y451100D03*
X410055Y448900D03*
Y451100D03*
X400555Y448900D03*
Y451100D03*
X403055Y448900D03*
Y451100D03*
X428555Y448900D03*
Y451100D03*
X424055Y448900D03*
Y451100D03*
X421555Y448900D03*
Y451100D03*
X417055Y448900D03*
Y451100D03*
X414555Y448900D03*
Y451100D03*
X445055Y448900D03*
Y451100D03*
X442555Y448900D03*
Y451100D03*
X438055Y448900D03*
Y451100D03*
X435555Y448900D03*
Y451100D03*
X431055Y448900D03*
Y451100D03*
X459055Y448900D03*
Y451100D03*
X456555Y448900D03*
Y451100D03*
X452055Y448900D03*
Y451100D03*
X449555Y448900D03*
Y451100D03*
X477555Y448900D03*
Y451100D03*
X473055Y448900D03*
Y451100D03*
X470555Y448900D03*
Y451100D03*
X466055Y448900D03*
Y451100D03*
X463555Y448900D03*
Y451100D03*
X480055Y448900D03*
Y451100D03*
X518365Y388360D03*
Y390560D03*
X525055Y387900D03*
Y390100D03*
X522555Y387900D03*
Y390100D03*
X515865Y388360D03*
Y390560D03*
X539000Y387900D03*
Y390100D03*
X536500Y387900D03*
Y390100D03*
X532055Y387900D03*
Y390100D03*
X529555Y387900D03*
Y390100D03*
G54D39*
X117654Y301703D03*
X113779Y309203D03*
X121529D03*
X139191Y298593D03*
X143066Y306093D03*
X135316D03*
G54D66*
X212250Y853579D03*
Y855547D03*
Y857516D03*
Y859484D03*
Y861453D03*
Y863421D03*
X231750Y859484D03*
Y857516D03*
Y855547D03*
Y853579D03*
Y863421D03*
Y861453D03*
G54D168*
X1333317Y587506D03*
Y589475D03*
Y591443D03*
Y593412D03*
Y595381D03*
Y597349D03*
Y599318D03*
X1355917Y597349D03*
Y595381D03*
Y593412D03*
Y591443D03*
Y589475D03*
Y587506D03*
Y599318D03*
G54D57*
X171800Y666500D03*
X315700Y56700D03*
Y51700D03*
Y61700D03*
X385800Y943000D03*
X437855Y290600D03*
X688300Y473000D03*
X765548Y123500D03*
X789800Y897000D03*
X793574Y434078D03*
X812074Y465078D03*
X881800Y330000D03*
X1056516Y277968D03*
X1056300Y283000D03*
X1073300Y141000D03*
X1084800Y412000D03*
X1097300Y61000D03*
Y66500D03*
X1116300Y280000D03*
X1145768Y252784D03*
X1150800Y592500D03*
X1152300Y827000D03*
X1186870Y777000D03*
X1227800Y452500D03*
X1254000Y209700D03*
X1254800Y675500D03*
X1281800Y569000D03*
X1291712Y434712D03*
X1309800Y363000D03*
X1350300Y420000D03*
X1353917Y562412D03*
G54D48*
X143500Y680750D03*
X139625Y673250D03*
X147375D03*
X143500Y695960D03*
X139625Y688460D03*
X147375D03*
X163000Y680750D03*
X159125Y673250D03*
X166875D03*
X163000Y696460D03*
X159125Y688960D03*
X166875D03*
X747748Y187250D03*
X743873Y179750D03*
X751623D03*
X873125Y615472D03*
X880875D03*
X877000Y622972D03*
X1181125Y861750D03*
X1188875D03*
X1185000Y869250D03*
G54D159*
X1258504Y329331D03*
Y368701D03*
X1272677Y349016D03*
G54D84*
X304500Y125700D03*
Y137300D03*
X318000Y125700D03*
Y137300D03*
X579500Y369800D03*
Y358200D03*
X593000Y369800D03*
Y358200D03*
X778824Y334248D03*
X792324D03*
X778824Y345848D03*
X792324D03*
X1030000Y58700D03*
Y70300D03*
X1057000Y58700D03*
X1043500D03*
X1057000Y70300D03*
X1043500D03*
G54D187*
G01X341000Y105290D02*
G02X342000Y102876I-2414J-2414D01*
G01Y102000D01*
G01X347000Y105179D02*
G03X346000Y102765I2414J-2414D01*
G01Y102000D01*
G01X347000Y112679D02*
X345351Y114329D01*
G02X345000Y115175I846J847D01*
G01Y119638D01*
G02X345545Y120954I1861J0D01*
G01X346045Y121454D01*
G02X347001Y121850I956J-956D01*
G01X362012D01*
G03X363320Y122390I2J1850D01*
G01X366644Y125715D01*
X367464Y126535D01*
G03X368359Y128696I-2162J2161D01*
G01Y128758D01*
G02X369218Y130832I2933J0D01*
G01X369882Y131496D01*
G01X341000Y108790D02*
Y112790D01*
G01D02*
X343105Y114895D01*
G03X343650Y116211I-1316J1316D01*
G01Y119638D01*
G02X344590Y121909I3211J1D01*
G01X345090Y122409D01*
G02X347000Y123200I1910J-1911D01*
G01X362012D01*
G03X362365Y123346I0J500D01*
G01X366509Y127490D01*
G03X367009Y128697I-1207J1207D01*
G01Y130830D01*
G03X366733Y131496I-942J0D01*
G01X341029Y248400D02*
X341179Y248250D01*
Y241500D01*
G01D02*
Y237500D01*
G01X347000Y108679D02*
Y112679D01*
G01X376181Y134645D02*
Y134059D01*
G03X376518Y133246I1149J0D01*
G01X377172Y132592D01*
G02X377656Y131424I-1167J-1168D01*
G01Y130690D01*
G02X376875Y128803I-2668J-1D01*
G01X376573Y128500D01*
X368818Y120745D01*
G03X367354Y117210I3536J-3535D01*
G01Y89567D01*
G03X368818Y86032I5000J0D01*
G01X409118Y45732D01*
G03X410886Y45000I1768J1768D01*
G01X428905D01*
G02X431628Y43872I0J-3850D01*
G01X460418Y15082D01*
G03X462186Y14350I1768J1768D01*
G01X537212D01*
G03X540845Y15855I0J5137D01*
G01X560545Y35555D01*
G03X562999Y41481I-5926J5925D01*
G01X563000Y41480D01*
Y61370D01*
G02X564859Y65859I6350J0D01*
G01X729140Y230140D01*
G02X733630Y232000I4490J-4490D01*
G01X743447D01*
G03X746982Y233464I0J5000D01*
G01X799567Y286049D01*
G03X800375Y288000I-1951J1951D01*
G01Y290500D01*
G02X801821Y293991I4937J0D01*
G01X803585Y295755D01*
G03X804289Y297456I-1701J1700D01*
G01X804290Y297455D01*
Y299996D01*
G03X802942Y303250I-4602J0D01*
G01X379331Y131496D02*
G02X379456Y131194I-302J-302D01*
G01Y129000D01*
G02X378277Y126155I-4024J1D01*
G01X374764Y122642D01*
G03X372904Y118152I4490J-4490D01*
G01Y93316D01*
G03X374764Y88826I6350J0D01*
G01X411813Y51777D01*
G03X414536Y50650I2722J2723D01*
G01X429904D01*
G02X431672Y49918I0J-2500D01*
G01X460462Y21128D01*
G03X463185Y20000I2723J2722D01*
G01X534303D01*
G03X537027Y21127I2J3850D01*
G01X555000Y39100D01*
G03X557250Y44532I-5432J5432D01*
G01Y64769D01*
G02X558714Y68304I5000J0D01*
G01X730678Y240268D01*
G02X732446Y241000I1768J-1768D01*
G01X738405D01*
G03X741128Y242128I0J3850D01*
G01X784544Y285544D01*
G03X785975Y288999I-3456J3455D01*
G01Y291500D01*
G02X786318Y292328I1171J0D01*
G01X788790Y294800D01*
G03X789890Y297456I-2656J2656D01*
G01Y300430D01*
G02X791058Y303250I3988J0D01*
G01X379331Y134645D02*
X380107Y133869D01*
G02X380806Y132182I-1686J-1687D01*
G01Y128999D01*
G02X379232Y125200I-5374J1D01*
G01X375718Y121685D01*
G03X374254Y118150I3536J-3535D01*
G01Y93317D01*
G03X375718Y89782I5000J0D01*
G01X412768Y52732D01*
G03X414536Y52000I1768J1768D01*
G01X429905D01*
G02X432628Y50872I0J-3850D01*
G01X461418Y22082D01*
G03X463186Y21350I1768J1768D01*
G01X534304D01*
G03X536072Y22082I0J2500D01*
G01X554045Y40055D01*
G03X555900Y44531I-4477J4478D01*
G01Y64770D01*
G02X557759Y69259I6350J0D01*
G01X729722Y241222D01*
G02X732445Y242350I2723J-2722D01*
G01X738404D01*
G03X740172Y243082I0J2500D01*
G01X783589Y286499D01*
G03X784625Y289000I-2501J2501D01*
G01Y291500D01*
G02X785363Y293283I2521J1D01*
G01X787835Y295755D01*
G03X788539Y297456I-1701J1700D01*
G01X788540Y297455D01*
Y299996D01*
G03X787192Y303250I-4602J0D01*
G01X376181Y131496D02*
G02X375137Y128974I-3566J-1D01*
G01X374883Y128721D01*
Y128720D01*
X367864Y121701D01*
G03X366004Y117211I4490J-4490D01*
G01Y89566D01*
G03X367864Y85076I6350J0D01*
G01X408163Y44777D01*
G03X410886Y43650I2722J2723D01*
G01X428904D01*
G02X430672Y42918I0J-2500D01*
G01X459462Y14128D01*
G03X462185Y13000I2723J2722D01*
G01X537211D01*
G03X541800Y14900I2J6487D01*
G01X561500Y34600D01*
G03X564350Y41481I-6881J6881D01*
G01Y61369D01*
G02X565814Y64904I5000J0D01*
G01X730096Y229186D01*
G02X733631Y230650I3535J-3536D01*
G01X743448D01*
G03X747938Y232510I0J6350D01*
G01X800522Y285094D01*
G03X801725Y288001I-2906J2905D01*
G01Y290500D01*
G02X802776Y293036I3587J-1D01*
G01X804540Y294800D01*
G03X805640Y297456I-2656J2656D01*
G01Y300430D01*
G02X806808Y303250I3988J0D01*
G01X376181Y144094D02*
X374607Y142520D01*
G01X376181Y140945D02*
G03X375657Y140728I0J-741D01*
G01X374699Y139770D01*
G03X374600Y139530I240J-239D01*
G01Y139390D01*
G01X379331Y144094D02*
X377757Y142520D01*
G01X379331Y140945D02*
X378636D01*
G03X378283Y140799I0J-500D01*
G01X377984Y140500D01*
G03X377750Y139935I565J-565D01*
G01Y139400D01*
G01X388780Y131496D02*
G02X388904Y131197I-299J-299D01*
G01Y127697D01*
X388905Y127696D01*
Y123580D01*
G02X388494Y122589I-1402J1D01*
G01X387696Y121791D01*
X387619Y121713D01*
G03X386704Y119501I2219J-2213D01*
G01Y100566D01*
G03X388564Y96076I6350J0D01*
G01X403860Y80780D01*
X419157Y65484D01*
G03X421171Y64650I2015J2016D01*
G01X431904D01*
G02X433672Y63918I0J-2500D01*
G01X462462Y35128D01*
G03X465185Y34000I2723J2722D01*
G01X525803D01*
G03X528527Y35127I2J3850D01*
G01X540100Y46700D01*
G03X542350Y52132I-5432J5432D01*
G01Y70110D01*
G02X543814Y73645I5000J0D01*
G01X752084Y281915D01*
G03X754480Y287702I-5786J5785D01*
G01Y291099D01*
X754481Y291100D01*
G02X755106Y292611I2136J1D01*
G01X757295Y294800D01*
G03X758395Y297456I-2656J2656D01*
G01Y300430D01*
G02X759563Y303250I3988J0D01*
G01X385630Y134645D02*
X386097Y134177D01*
G02X387105Y131745I-2432J-2433D01*
G01Y126705D01*
G02X386299Y124759I-2752J0D01*
G01X382618Y121078D01*
G03X381154Y117543I3536J-3535D01*
G01Y96567D01*
G03X382618Y93032I5000J0D01*
G01X415918Y59732D01*
G03X417686Y59000I1768J1768D01*
G01X430905D01*
G02X433628Y57872I0J-3850D01*
G01X462518Y28982D01*
G03X464286Y28250I1768J1768D01*
G01X530604D01*
G03X532372Y28982I0J2500D01*
G01X546895Y43505D01*
G03X548999Y48586I-5081J5080D01*
G01X549000Y48585D01*
Y68352D01*
G02X550465Y72407I6350J-2D01*
G01Y72447D01*
X727470Y249452D01*
G02X730000Y250500I2530J-2530D01*
G03X731860Y251271I-1J2631D01*
G01X732795Y252205D01*
X767671Y287081D01*
G03X768880Y290000I-2919J2919D01*
G01Y291100D01*
G02X769901Y293566I3487J1D01*
G01X772090Y295755D01*
G03X772794Y297456I-1701J1700D01*
G01X772795Y297455D01*
Y299996D01*
G03X771447Y303250I-4602J0D01*
G01X385630Y131496D02*
G02X385755Y131194I-302J-302D01*
G01Y126705D01*
G02X385344Y125714I-1402J1D01*
G01X381664Y122034D01*
G03X379804Y117544I4490J-4490D01*
G01Y96566D01*
G03X381664Y92076I6350J0D01*
G01X414963Y58777D01*
G03X417686Y57650I2722J2723D01*
G01X430904D01*
G02X432672Y56918I0J-2500D01*
G01X461562Y28028D01*
G03X464285Y26900I2723J2722D01*
G01X530603D01*
G03X533327Y28027I2J3850D01*
G01X547850Y42550D01*
G03X550350Y48586I-6036J6036D01*
G01Y68351D01*
G02X551504Y71544I4999J-2D01*
G02X551815Y71886I3850J-3189D01*
G01X728218Y248289D01*
Y248290D01*
X728425Y248497D01*
G02X730000Y249149I1575J-1575D01*
G03X732815Y250316I-1J3981D01*
G01X733750Y251250D01*
X768626Y286126D01*
G03X770230Y290001I-3874J3873D01*
G01Y291100D01*
G02X770856Y292611I2137J0D01*
G01X773045Y294800D01*
G03X774145Y297456I-2656J2656D01*
G01Y300430D01*
G02X775313Y303250I3988J0D01*
G01X395079Y131496D02*
G02X395179Y131255I-241J-241D01*
G01Y124328D01*
G02X394424Y122505I-2578J0D01*
G03X393604Y120525I1980J-1980D01*
G01Y103566D01*
G03X395464Y99076I6350J0D01*
G01X422056Y72484D01*
G03X424070Y71650I2015J2016D01*
G01X433404D01*
G02X435172Y70918I0J-2500D01*
G01X464062Y42028D01*
G03X466785Y40900I2723J2722D01*
G01X520117D01*
G03X522840Y42028I0J3850D01*
G01X530755Y49945D01*
G03X534850Y59834I-9888J9887D01*
G01Y72369D01*
G02X536314Y75904I5000J0D01*
G01X658130Y197720D01*
G03X659990Y202210I-4490J4490D01*
G01Y291100D01*
G02X660616Y292611I2137J0D01*
G01X662805Y294800D01*
G03X663905Y297456I-2656J2656D01*
G01Y300430D01*
G02X665073Y303250I3988J0D01*
G01X395079Y134645D02*
X395613Y134110D01*
G02X396529Y131900I-2210J-2211D01*
G01Y124329D01*
G02X395379Y121550I-3928J-2D01*
G03X394955Y120525I1025J-1024D01*
G01X394954Y120526D01*
Y103567D01*
G03X396418Y100032I5000J0D01*
G01X423011Y73439D01*
G03X424071Y73000I1060J1061D01*
G01X433405D01*
G02X436128Y71872I0J-3850D01*
G01X465018Y42982D01*
G03X466786Y42250I1768J1768D01*
G01X520114D01*
G03X521882Y42982I0J2500D01*
G01X529800Y50900D01*
G03X533500Y59833I-8933J8933D01*
G01Y72370D01*
G02X535360Y76860I6350J0D01*
G01X657176Y198676D01*
G03X658640Y202211I-3536J3535D01*
G01Y291100D01*
G02X659661Y293566I3487J1D01*
G01X661850Y295755D01*
G03X662554Y297456I-1701J1700D01*
G01X662555Y297455D01*
Y299996D01*
G03X661207Y303250I-4602J0D01*
G01X388780Y134645D02*
Y134148D01*
G03X389055Y133485I937J0D01*
G01X389642Y132898D01*
G02X390255Y131419I-1478J-1479D01*
G01Y129646D01*
X390254Y129645D01*
Y128257D01*
X390255Y128256D01*
Y123579D01*
G02X389449Y121634I-2752J1D01*
G01X388657Y120842D01*
X388577Y120761D01*
G03X388054Y119500I1261J-1262D01*
G01Y100567D01*
G03X389518Y97032I5000J0D01*
G01X420112Y66439D01*
G03X421172Y66000I1060J1061D01*
G01X431905D01*
G02X434628Y64872I0J-3850D01*
G01X463418Y36082D01*
G03X465186Y35350I1768J1768D01*
G01X525804D01*
G03X527572Y36082I0J2500D01*
G01X539145Y47655D01*
G03X541000Y52132I-4477J4478D01*
G01Y70111D01*
G02X542859Y74600I6350J0D01*
G01X751129Y282870D01*
G03X753130Y287701I-4831J4831D01*
G01Y291100D01*
G02X754150Y293566I3487J2D01*
G01X755246Y294661D01*
X756340Y295755D01*
G03X757044Y297456I-1701J1700D01*
G01X757045Y297455D01*
Y299996D01*
G03X755697Y303250I-4602J0D01*
G01X388780Y144094D02*
X387206Y142520D01*
G01X388780Y140945D02*
X388742D01*
X387173Y139376D01*
G01X385630Y144094D02*
X384056Y142520D01*
G01X395079Y144094D02*
X393505Y142520D01*
G01X395079Y140945D02*
Y140909D01*
X393510Y139340D01*
G01X385630Y140945D02*
X385593D01*
X384019Y139371D01*
G01X398229Y131496D02*
X398553Y131172D01*
Y126580D01*
G03X399359Y124634I2752J0D01*
G01X400343Y123650D01*
G02X400754Y122659I-991J-992D01*
G01Y106488D01*
G03X402614Y101998I6350J0D01*
G01X424696Y79916D01*
G03X427418Y78788I2723J2722D01*
G01X434266D01*
G02X436034Y78056I0J-2500D01*
G01X464462Y49628D01*
G03X467185Y48500I2723J2722D01*
G01X516403D01*
G03X519127Y49627I2J3850D01*
G01X524900Y55400D01*
G03X527250Y61073I-5673J5673D01*
G01Y74769D01*
G02X528714Y78304I5000J0D01*
G01X642380Y191970D01*
G03X644240Y196460I-4490J4490D01*
G01Y291100D01*
G02X644866Y292611I2137J0D01*
G01X647055Y294800D01*
G03X648155Y297456I-2656J2656D01*
G01Y300430D01*
G02X649323Y303250I3988J0D01*
G01X398229Y134645D02*
X398395D01*
X399187Y133853D01*
G02X399903Y132125I-1727J-1728D01*
G01Y126580D01*
G03X400314Y125589I1402J1D01*
G01X401298Y124605D01*
G02X402104Y122660I-1946J-1946D01*
G01Y106489D01*
G03X403568Y102954I5000J0D01*
G01X425651Y80871D01*
G03X427419Y80138I1768J1767D01*
G01X434267D01*
G02X436990Y79010I0J-3850D01*
G01X465418Y50582D01*
G03X467186Y49850I1768J1768D01*
G01X516404D01*
G03X518172Y50582I0J2500D01*
G01X523945Y56355D01*
G03X525900Y61074I-4718J4719D01*
G01Y74770D01*
G02X527760Y79260I6350J0D01*
G01X641426Y192926D01*
G03X642890Y196461I-3536J3535D01*
G01Y291100D01*
G02X643911Y293566I3487J1D01*
G01X646100Y295755D01*
G03X646804Y297456I-1701J1700D01*
G01X646805Y297455D01*
Y299996D01*
G03X645457Y303250I-4602J0D01*
G01X404528Y131496D02*
X404653Y131371D01*
Y130152D01*
G03X404848Y129681I666J0D01*
G02X405043Y129210I-471J-471D01*
G01Y123052D01*
G03X405849Y121106I2752J0D01*
G01X407243Y119712D01*
G02X407654Y118721I-991J-992D01*
G01Y109347D01*
G03X409514Y104857I6350J0D01*
G01X427555Y86816D01*
G03X430278Y85688I2723J2722D01*
G01X435800D01*
G02X437527Y84972I-1J-2443D01*
G01X465372Y57128D01*
G03X468095Y56000I2723J2722D01*
G01X513096D01*
G03X517200Y57700I0J5804D01*
G03X520350Y65305I-7605J7605D01*
G01Y77869D01*
G02X521814Y81404I5000J0D01*
G01X626635Y186225D01*
G03X628495Y190715I-4490J4490D01*
G01Y291100D01*
G02X629121Y292611I2137J0D01*
G01X631310Y294800D01*
G03X632410Y297456I-2656J2656D01*
G01Y300430D01*
G02X633578Y303250I3988J0D01*
G01X404528Y134645D02*
Y134512D01*
X405351Y133689D01*
G02X406003Y132115I-1574J-1574D01*
G01Y130676D01*
G03X406198Y130205I666J0D01*
G02X406393Y129734I-471J-471D01*
G01Y123052D01*
G03X406804Y122061I1402J1D01*
G01X408198Y120667D01*
G02X409004Y118722I-1946J-1946D01*
G01Y109348D01*
G03X410468Y105813I5000J0D01*
G01X428511Y87770D01*
G03X430279Y87038I1768J1768D01*
G01X435801D01*
G02X438482Y85927I-1J-3793D01*
G01X466328Y58082D01*
G03X468096Y57350I1768J1768D01*
G01X513095D01*
G03X516245Y58655I0J4454D01*
G03X519000Y65304I-6650J6651D01*
G01Y77870D01*
G02X520860Y82360I6350J0D01*
G01X625681Y187181D01*
G03X627145Y190716I-3536J3535D01*
G01Y291100D01*
G02X628166Y293566I3487J1D01*
G01X630355Y295755D01*
G03X631059Y297456I-1701J1700D01*
G01X631060Y297455D01*
Y299996D01*
G03X629712Y303250I-4602J0D01*
G01X407677Y131496D02*
G02X407802Y131194I-302J-302D01*
G01Y127080D01*
G03X408608Y125134I2752J0D01*
G01X414143Y119599D01*
G02X414554Y118608I-991J-992D01*
G01Y112206D01*
G03X416414Y107716I6350J0D01*
G01X430736Y93394D01*
G03X432681Y92588I1946J1946D01*
G01X453868D01*
G03X458358Y94448I0J6350D01*
G01X465153Y101243D01*
G03X466281Y103966I-2722J2723D01*
G01Y105871D01*
G02X468560Y108150I2279J0D01*
G01X537206D01*
G03X539929Y109278I0J3850D01*
G01X610885Y180234D01*
G03X612745Y184724I-4490J4490D01*
G01Y291571D01*
G02X613038Y292278I1000J0D01*
G01X614880Y294120D01*
G03X616660Y298419I-4299J4298D01*
G01Y300430D01*
G02X617828Y303250I3988J0D01*
G01X407677Y134645D02*
Y134059D01*
G03X408014Y133246I1149J0D01*
G01X408668Y132592D01*
G02X409152Y131424I-1167J-1168D01*
G01Y127080D01*
G03X409563Y126089I1402J1D01*
G01X415098Y120554D01*
G02X415904Y118609I-1946J-1946D01*
G01Y112207D01*
G03X417368Y108672I5000J0D01*
G01X431691Y94349D01*
G03X432682Y93938I992J991D01*
G01X453867D01*
G03X457402Y95402I0J5000D01*
G01X464199Y102199D01*
G03X464930Y103966I-1768J1766D01*
G01X464931Y103965D01*
Y105871D01*
G02X468560Y109500I3629J0D01*
G01X537205D01*
G03X538973Y110232I0J2500D01*
G01X609931Y181190D01*
G03X611395Y184725I-3536J3535D01*
G01Y291572D01*
G02X612083Y293233I2350J0D01*
G01X613925Y295075D01*
G03X615310Y298419I-3344J3344D01*
G01Y299996D01*
G03X613962Y303250I-4602J0D01*
G01X404528Y144094D02*
X402954Y142520D01*
G01X404528Y140945D02*
X402953Y139370D01*
G01X407677Y144094D02*
X406103Y142520D01*
G01X407677Y140945D02*
X406103Y139371D01*
G01X398229Y144094D02*
X396655Y142520D01*
G01X398229Y140945D02*
X397581D01*
G03X397228Y140799I0J-500D01*
G01X396829Y140400D01*
G03X396683Y140047I354J-353D01*
G01Y139362D01*
G01X479923Y298683D02*
X476417D01*
X473600Y301500D01*
X472805D01*
G01D02*
Y293800D01*
G01X678076Y99024D02*
X675328D01*
G02X674469Y99380I0J1215D01*
G01X678076Y103524D02*
X675213D01*
G03X674358Y103170I0J-1209D01*
G01X685326Y94934D02*
X687966Y92294D01*
Y88544D01*
G01X681576Y99024D02*
X685326Y95274D01*
Y94934D01*
G01X681576Y99024D02*
X681826Y99274D01*
X685272D01*
X685748Y99750D01*
G01D02*
G02X687194Y100349I1446J-1446D01*
G01X693087D01*
G03X695288Y101260I1J3112D01*
G01X697088Y103060D01*
G03X697948Y105138I-2078J2077D01*
G01Y111103D01*
G02X698533Y112515I1997J0D01*
G01X699983Y113965D01*
G02X701250Y114490I1267J-1267D01*
G01X704852D01*
G03X705084Y114394I232J232D01*
G01X708216D01*
G01X681576Y103524D02*
X685474D01*
X685748Y103250D01*
G01X681576Y103524D02*
X685336Y107284D01*
Y107744D01*
G01X708216Y116363D02*
X705818D01*
G03X705465Y116217I0J-500D01*
G01X705234Y115986D01*
G02X704881Y115840I-353J354D01*
G01X701249D01*
G03X699028Y114920I1J-3142D01*
G01X697578Y113470D01*
G03X696598Y111104I2367J-2366D01*
G01Y105138D01*
G02X696133Y104015I-1588J0D01*
G01X694333Y102215D01*
G02X693087Y101699I-1246J1246D01*
G01X688148D01*
G02X686698Y102299I-1J2050D01*
G01X685748Y103249D01*
Y103250D01*
G01X685336Y107744D02*
X685186Y107894D01*
Y114964D01*
G01X682382Y122692D02*
X682574Y122500D01*
X686998D01*
G01D02*
Y121158D01*
G03X687640Y119608I2192J0D01*
G01X689498Y117750D01*
G03X691864Y116770I2366J2367D01*
G01X694561D01*
G03X697048Y117800I0J3518D01*
G01X699148Y119900D01*
G02X701152Y120730I2004J-2004D01*
G01X704811D01*
G02X705164Y120584I0J-500D01*
G01X705302Y120446D01*
G03X705655Y120300I353J354D01*
G01X708216D01*
G01X690512Y126202D02*
Y122514D01*
X690498Y122500D01*
G01D02*
Y119384D01*
G03X690924Y118356I1454J0D01*
G03X691865Y118120I942J1761D01*
G01X694560D01*
G03X696093Y118755I0J2168D01*
G01X698193Y120855D01*
G02X701152Y122080I2958J-2959D01*
G01X705228D01*
X705322Y122174D01*
G02X705549Y122268I227J-227D01*
G01X708216D01*
G01X686432Y129762D02*
X686396Y129798D01*
G02X685898Y131000I1202J1202D01*
G01Y133380D01*
G01X682382Y126192D02*
Y129944D01*
X682418Y129980D01*
G01X678222Y122842D02*
X678372Y122692D01*
X682382D01*
G01X690512Y126202D02*
X690452Y126262D01*
X686432D01*
G01X1066929Y43267D02*
X1069137D01*
G03X1069700Y43500I0J796D01*
G03X1070191Y44685I-1185J1185D01*
G01Y52100D01*
G02X1071605Y55515I4829J1D01*
G01X1085626Y69536D01*
G02X1088800Y70850I3173J-3175D01*
G01X1092310D01*
G03X1093045Y71155I-1J1040D01*
G03X1094249Y74063I-2908J2907D01*
G01X1094250Y74062D01*
Y79700D01*
G01X1074803Y43267D02*
X1073187D01*
G02X1071900Y43800I0J1820D01*
G02X1071541Y44667I867J867D01*
G01Y52100D01*
G02X1072560Y54560I3479J0D01*
G01X1086581Y68581D01*
G02X1088800Y69500I2219J-2219D01*
G01X1092310D01*
G03X1094000Y70200I0J2390D01*
G03X1095600Y74063I-3863J3863D01*
G01Y75534D01*
G02X1096000Y76500I1366J0D01*
G03X1096500Y77707I-1207J1207D01*
G01Y83700D01*
G03X1095900Y84300I-600J0D01*
G02X1095558Y84441I-1J483D01*
G01X1094750Y85250D01*
G02X1094250Y86457I1207J1207D01*
G01Y90300D01*
G01X1090061Y98242D02*
Y95631D01*
G03X1090550Y94450I1670J0D01*
G01X1091750Y93250D01*
G01X1092400Y87700D02*
Y86397D01*
G03X1092900Y85190I1707J0D01*
G01X1093795Y84295D01*
Y84294D01*
G02X1094250Y83197I-1097J-1098D01*
G01Y79700D01*
G01X1093861Y104842D02*
Y106615D01*
G03X1093408Y107709I-1547J0D01*
G01X1093215Y107902D01*
G02X1092636Y109300I1398J1398D01*
G01Y124000D01*
G02X1093514Y126120I2998J0D01*
G01X1093894Y126500D01*
G01X1090061Y104842D02*
Y106491D01*
G02X1090602Y107797I1847J0D01*
G01X1090707Y107902D01*
G03X1091286Y109300I-1398J1398D01*
G01Y124000D01*
G03X1090408Y126120I-2998J0D01*
G01X1090028Y126500D01*
G01X1093861Y98242D02*
Y91239D01*
G03X1094250Y90300I1328J0D01*
G01X1124547Y725355D02*
G03X1124348Y725834I-678J-1D01*
G01X1124000Y726183D01*
X1121441Y728742D01*
X1120813Y729371D01*
G03X1120500Y729500I-312J-313D01*
G01X1127696Y725355D02*
G02X1126063Y726032I1J2310D01*
G01X1124640Y727454D01*
G02X1124000Y729000I1547J1546D01*
G01X1192418Y268560D02*
G02X1188616Y266985I-3802J3802D01*
G01X1185100D01*
G02X1182309Y268141I0J3947D01*
G01X1164425Y286025D01*
G02X1161630Y292773I6748J6748D01*
G01Y311830D01*
G03X1160810Y313810I-2801J0D01*
G01X1160750Y313870D01*
G03X1157901Y315050I-2849J-2850D01*
G02X1157139Y315365I-1J1077D01*
G01X1156100Y316405D01*
G01X1192418Y264060D02*
G03X1188616Y265635I-3802J-3802D01*
G01X1185100D01*
G02X1181354Y267186I-1J5298D01*
G01X1163470Y285070D01*
G02X1160280Y292773I7703J7702D01*
G01Y311829D01*
G03X1159855Y312855I-1451J0D01*
G01X1159795Y312915D01*
G03X1157900Y313700I-1895J-1895D01*
G03X1156372Y313067I0J-2161D01*
G01X1156100Y312795D01*
G01X1215256Y278741D02*
X1211000D01*
G03X1209705Y278205I0J-1832D01*
G01X1209500Y278000D01*
G02X1209017Y277800I-483J483D01*
G01X1192390D01*
G02X1189481Y279005I0J4114D01*
G01X1185493Y282993D01*
G03X1179801Y285350I-5691J-5692D01*
G01X1177499D01*
G02X1173335Y287075I2J5893D01*
G01X1172455Y287955D01*
G02Y288803I424J424D01*
G01X1173777Y290125D01*
G01X1215256Y275591D02*
X1210500D01*
G02X1210344Y275655I-1J220D01*
G01X1210000Y276000D01*
G03X1208914Y276450I-1086J-1086D01*
G01X1192389D01*
G02X1188526Y278050I0J5464D01*
G01X1184538Y282038D01*
G03X1179801Y284000I-4737J-4737D01*
G01X1177500D01*
G02X1172378Y286121I-1J7243D01*
G01X1172250Y286250D01*
X1170638Y287861D01*
G02X1169777Y289941I2081J2080D01*
G01Y290125D01*
G01X1215256Y300788D02*
X1211000D01*
G02X1209655Y301345I0J1902D01*
G01X1209500Y301500D01*
G03X1209017Y301700I-483J-483D01*
G01X1175700D01*
G02X1170780Y306620I0J4920D01*
G01Y321500D01*
G03X1170108Y323124I-2296J1D01*
G01X1169515Y323716D01*
G01X1215256Y303937D02*
X1210555D01*
G03X1209500Y303500I0J-1492D01*
G02X1208414Y303050I-1086J1086D01*
G01X1175700D01*
G02X1172130Y306620I0J3570D01*
G01Y321500D01*
G02X1172993Y323585I2948J1D01*
G01X1173125Y323716D01*
G01X1178090Y687560D02*
X1178127D01*
X1179678Y689111D01*
G01X1181240Y687560D02*
Y687578D01*
X1182817Y689155D01*
G01X1195918Y268560D02*
X1196630Y267848D01*
G03X1198677Y267000I2047J2047D01*
G01X1200346D01*
G02X1200911Y266766I0J-799D01*
G01X1202201Y265476D01*
G03X1202766Y265242I565J565D01*
G01X1209377D01*
G03X1210000Y265500I0J881D01*
G01X1210389Y265889D01*
G02X1211000Y266142I611J-611D01*
G01X1215256D01*
G01X1195918Y264060D02*
X1196682Y264823D01*
G02X1198677Y265650I1996J-1995D01*
G01X1199889D01*
G02X1200278Y265489I0J-550D01*
G01X1201246Y264521D01*
G03X1202766Y263892I1519J1520D01*
G01X1209554D01*
G02X1210500Y263500I0J-1338D01*
G03X1211724Y262993I1224J1224D01*
G01X1215256D01*
G01Y291339D02*
X1210318D01*
G03X1209500Y291000I0J-1157D01*
G02X1208655Y290650I-845J845D01*
G01X1202430D01*
G03X1199545Y289455I0J-4081D01*
G01X1197045Y286955D01*
G02X1195584Y286350I-1461J1461D01*
G01X1193569D01*
G02X1192000Y287000I0J2219D01*
G01X1191854Y287146D01*
G02X1191500Y288000I853J854D01*
G02X1191894Y288951I1345J0D01*
G01X1192743Y289800D01*
G01X1215256Y288189D02*
X1210500D01*
G02X1210177Y288322I-1J456D01*
G01X1209500Y289000D01*
G03X1208776Y289300I-724J-724D01*
G01X1202431D01*
G03X1200500Y288500I0J-2731D01*
G01X1198000Y286000D01*
G02X1195584Y285000I-2415J2416D01*
G01X1193568D01*
G02X1191045Y286045I0J3569D01*
G01X1190899Y286191D01*
G02X1190150Y288001I1808J1808D01*
G03X1189778Y288899I-1270J0D01*
G01X1188877Y289800D01*
G01X1215256Y313386D02*
X1211482D01*
G02X1210000Y314000I0J2096D01*
G03X1209085Y314302I-757J-756D01*
G01X1208941Y314280D01*
G02X1208534Y314250I-403J2686D01*
G01X1205707D01*
G02X1201565Y315965I-1J5857D01*
G01X1199765Y317765D01*
G02X1197150Y324081I6315J6314D01*
G01Y342600D01*
G03X1196504Y344158I-2204J-1D01*
G01X1196075Y344588D01*
G01X1215256Y316536D02*
X1210500D01*
G03X1209708Y316208I0J-1120D01*
G01X1209500Y316000D01*
G02X1208534Y315600I-966J966D01*
G01X1205707D01*
G02X1202520Y316920I0J4507D01*
G01X1200720Y318720D01*
G02X1198500Y324080I5360J5360D01*
G01Y342600D01*
G02X1199068Y343971I1939J0D01*
G01X1199685Y344588D01*
G01X1187539Y684410D02*
X1189533D01*
X1189890Y684053D01*
G01X1184389Y684410D02*
X1184496D01*
X1186107Y686021D01*
X1190827D01*
X1192937Y683911D01*
G01X1244250Y268500D02*
X1242933Y269817D01*
G03X1242030Y270191I-903J-903D01*
G01X1238567D01*
G03X1238178Y270030I0J-550D01*
G01X1237601Y269453D01*
G02X1237212Y269292I-389J389D01*
G01X1232776D01*
G01Y285040D02*
X1237212D01*
G02X1237601Y284879I0J-550D01*
G01X1238179Y284301D01*
G03X1238568Y284140I389J389D01*
G01X1239263D01*
G03X1239720Y284330I-1J646D01*
G01X1239945Y284555D01*
G02X1243796Y286150I3851J-3852D01*
G01X1248600D01*
G03X1249841Y286664I0J1755D01*
G01X1250677Y287500D01*
G01X1232776Y281890D02*
X1237212D01*
G03X1237601Y282051I0J550D01*
G01X1238179Y282629D01*
G02X1238568Y282790I389J-389D01*
G01X1239263D01*
G03X1240675Y283375I0J1997D01*
G01X1240900Y283600D01*
G02X1243797Y284800I2897J-2897D01*
G01X1248600D01*
G02X1249927Y284251I1J-1876D01*
G01X1250677Y283500D01*
G01X1244250Y272500D02*
G02X1241935Y271541I-2315J2315D01*
G01X1238568D01*
G02X1238179Y271702I0J550D01*
G01X1237601Y272280D01*
G03X1237212Y272441I-389J-389D01*
G01X1232776D01*
G01Y297638D02*
X1237212D01*
G02X1237601Y297477I0J-550D01*
G01X1238178Y296900D01*
G03X1238567Y296739I389J389D01*
G01X1244742D01*
G03X1245745Y297155I-1J1419D01*
G02X1249113Y298550I3368J-3369D01*
G01X1258700D01*
G03X1259483Y298875I-1J1108D01*
G01X1260577Y299968D01*
G01X1232776Y294489D02*
X1237212D01*
G03X1237601Y294650I0J550D01*
G01X1238179Y295228D01*
G02X1238568Y295389I389J-389D01*
G01X1244742D01*
G03X1246700Y296200I0J2769D01*
G02X1249114Y297200I2414J-2414D01*
G01X1258700D01*
G02X1260030Y296649I0J-1881D01*
G01X1260577Y296102D01*
G01X1232776Y310237D02*
X1237212D01*
G02X1237601Y310076I0J-550D01*
G01X1238179Y309498D01*
G03X1238568Y309337I389J389D01*
G01X1243124D01*
G03X1244000Y309700I0J1239D01*
G02X1247380Y311100I3380J-3380D01*
G01X1251400D01*
G03X1252043Y311367I-1J910D01*
G01X1253477Y312800D01*
G01X1232776Y307087D02*
X1237212D01*
G03X1237601Y307248I0J550D01*
G01X1238179Y307826D01*
G02X1238568Y307987I389J-389D01*
G01X1243125D01*
G03X1244955Y308745I0J2589D01*
G02X1247379Y309750I2426J-2425D01*
G01X1251400D01*
G02X1253494Y308882I-1J-2962D01*
G01X1253577Y308800D01*
G01X1232776Y322835D02*
X1237212D01*
G02X1237601Y322674I0J-550D01*
G01X1238179Y322096D01*
G03X1238568Y321935I389J389D01*
G01X1241636D01*
G03X1243000Y322500I0J1929D01*
G02X1244207Y323000I1207J-1207D01*
G01X1251000D01*
G03X1252155Y323479I-1J1634D01*
G01X1253177Y324500D01*
G01X1232776Y319685D02*
X1237212D01*
G03X1237601Y319846I0J550D01*
G01X1238179Y320424D01*
G02X1238568Y320585I389J-389D01*
G01X1241637D01*
G03X1243955Y321545I0J3279D01*
G02X1244208Y321650I253J-252D01*
G01X1251000D01*
G02X1252753Y320924I0J-2479D01*
G01X1253177Y320500D01*
G01X1247750Y268500D02*
X1249300D01*
G03X1249850Y269050I0J550D01*
G01Y269275D01*
G02X1250400Y269825I550J0D01*
G01X1253458D01*
G02X1253847Y269664I0J-550D01*
G01X1254944Y268567D01*
G01X1247750Y272500D02*
X1249300D01*
G02X1249850Y271950I0J-550D01*
G01Y271725D01*
G03X1250400Y271175I550J0D01*
G01X1253458D01*
G03X1253847Y271336I0J550D01*
G01X1254944Y272433D01*
G01X1322900Y524600D02*
Y526422D01*
G02X1323450Y527750I1878J0D01*
G02X1323926Y528073I1085J-1087D01*
G02X1324536Y528200I612J-1409D01*
G01X1327200D01*
G03X1331000Y532000I0J3800D01*
G01Y560000D01*
G02X1334038Y567333I10371J-1D01*
G01X1340317Y573612D01*
G03X1342648Y579240I-5628J5628D01*
G01Y582112D01*
G01X1340680D02*
Y577749D01*
G02X1339362Y574567I-4500J0D01*
G01X1333083Y568288D01*
G03X1329650Y560000I8288J-8288D01*
G01Y552085D01*
G02X1329255Y551295I-990J1D01*
G03X1328860Y550505I595J-791D01*
G01Y548855D01*
G03X1329255Y548065I990J1D01*
G02X1329650Y547275I-595J-791D01*
G01Y545625D01*
G02X1329255Y544835I-990J1D01*
G03X1328860Y544045I595J-791D01*
G01Y542395D01*
G03X1329255Y541605I990J1D01*
G02X1329650Y540815I-595J-791D01*
G01Y532000D01*
G02X1327200Y529550I-2450J0D01*
G01X1323345D01*
G02X1322500Y529900I0J1195D01*
G02X1322400Y530141I241J241D01*
G01Y533100D01*
G01X1355917Y587506D02*
X1356644D01*
G02X1361217Y585612I0J-6467D01*
G01X1375914Y570915D01*
G02X1377850Y566241I-4675J-4674D01*
G01Y539536D01*
G02X1374955Y532545I-9886J-1D01*
G01X1372784Y530374D01*
G02X1368500Y528600I-4283J4284D01*
G01X1355031D01*
G03X1354946Y528598I16J-2489D01*
G03X1353271Y527871I84J-2487D01*
G01X1352450Y527050D01*
G03X1351900Y525722I1328J-1328D01*
G01Y524600D01*
G01X1356267Y585538D02*
X1358311D01*
G02X1360136Y584782I0J-2581D01*
G01X1361303Y583615D01*
G02X1361582Y582777I-701J-699D01*
G03X1361861Y581939I981J-139D01*
G01X1363028Y580773D01*
G03X1363866Y580494I699J701D01*
G02X1364704Y580214I138J-980D01*
G01X1365871Y579048D01*
G02X1366150Y578210I-701J-699D01*
G03X1366430Y577372I980J-138D01*
G01X1367596Y576205D01*
G03X1368434Y575926I699J701D01*
G02X1369272Y575646I138J-980D01*
G01X1370439Y574480D01*
G02X1370718Y573642I-701J-699D01*
G03X1370998Y572804I980J-138D01*
G01X1372164Y571637D01*
G03X1373002Y571358I699J701D01*
G02X1373840Y571079I139J-980D01*
G01X1374959Y569960D01*
G02X1376500Y566240I-3720J-3720D01*
G01Y558916D01*
G02X1376105Y558126I-990J1D01*
G03X1375710Y557336I595J-791D01*
G01Y555686D01*
G03X1376105Y554896I990J1D01*
G02X1376500Y554106I-595J-791D01*
G01Y552456D01*
G02X1376105Y551666I-990J1D01*
G03X1375710Y550876I595J-791D01*
G01Y549226D01*
G03X1376105Y548436I990J1D01*
G02X1376500Y547646I-595J-791D01*
G01Y545996D01*
G02X1376105Y545206I-990J1D01*
G03X1375710Y544416I595J-791D01*
G01Y542766D01*
G03X1376105Y541976I990J1D01*
G02X1376500Y541186I-595J-791D01*
G01Y539536D01*
G02X1374000Y533500I-8536J0D01*
G01X1371829Y531329D01*
G02X1368500Y529950I-3329J3329D01*
G01X1353469D01*
G02X1351900Y530600I0J2219D01*
G02Y533100I1250J1250D01*
G01X1352400Y533600D01*
G01X1369867Y585412D02*
X1368754Y586525D01*
G03X1366917Y587286I-1837J-1837D01*
G01X1364717D01*
G02X1361348Y588681I-1J4764D01*
G03X1359431Y589475I-1917J-1917D01*
G01X1355917D01*
G01X1369867Y602412D02*
X1368245Y600791D01*
G02X1367211Y600362I-1035J1034D01*
G01X1365347D01*
G03X1363239Y599490I-2J-2979D01*
G01X1362188Y598440D01*
G02X1359554Y597349I-2634J2634D01*
G01X1355917D01*
G01X1369867Y597912D02*
G03X1367211Y599012I-2656J-2656D01*
G01X1365346D01*
G03X1364194Y598535I0J-1629D01*
G01X1362844Y597185D01*
X1361764Y596104D01*
G02X1360017Y595381I-1746J1747D01*
G01X1355917D01*
G01X1369867Y589912D02*
X1369421Y589466D01*
G02X1367417Y588636I-2004J2004D01*
G01X1364717D01*
G02X1362303Y589636I0J3414D01*
G01X1362022Y589917D01*
G03X1358338Y591443I-3684J-3684D01*
G01X1355917D01*
G01X1369867Y611412D02*
X1361292Y602837D01*
G02X1357548Y601286I-3744J3744D01*
G01X1356267D01*
G01X1369867Y606912D02*
G03X1369067Y607712I-800J0D01*
G01X1368517D01*
G03X1367766Y607401I0J-1062D01*
G01X1362057Y601692D01*
X1362046Y601687D01*
X1362022Y601677D01*
G02X1356327Y599318I-5695J5695D01*
G01X1355917D01*
G01X1373367Y597912D02*
X1374955Y599500D01*
X1379740D01*
X1380925Y598315D01*
G01X1373367Y589912D02*
X1374088D01*
X1375700Y588300D01*
X1381610D01*
X1383950Y585960D01*
Y582380D01*
X1385135Y581195D01*
G01X1373367Y585412D02*
X1374162D01*
X1375700Y586950D01*
X1381050D01*
X1382600Y585400D01*
Y582380D01*
X1381415Y581195D01*
G01X1373367Y611412D02*
X1374989Y609790D01*
X1376939D01*
X1377996Y610847D01*
G01X1373367Y602412D02*
X1374929Y600850D01*
X1379740D01*
X1380925Y602035D01*
G01X1373367Y606912D02*
X1374895Y608440D01*
X1376938D01*
X1377996Y607382D01*
G54D178*
G01X33554Y844660D02*
Y841950D01*
X36004Y839500D01*
G01X72672Y820904D02*
X73772Y822004D01*
G01X75432Y758844D02*
Y759092D01*
X73804Y760720D01*
Y766470D01*
G01X93347Y765754D02*
Y766263D01*
X94838Y767754D01*
X96772D01*
G01X183614Y573950D02*
Y575886D01*
X182000Y577500D01*
G01X181055Y573950D02*
Y576555D01*
X182000Y577500D01*
G01X320664Y70353D02*
Y66164D01*
X320500Y66000D01*
G01X365146Y151942D02*
Y151966D01*
X366723Y153543D01*
X366733D01*
G01X412500Y268750D02*
X412250D01*
X409500Y271500D01*
G01X434448Y343897D02*
Y343987D01*
X432585Y345850D01*
G01X450196Y347834D02*
X449834D01*
X448000Y346000D01*
G01X501378Y363582D02*
X505523D01*
G01X501378Y355708D02*
X505048D01*
X505440Y356100D01*
X507955D01*
G01X501378Y371456D02*
X505523D01*
G01X706500Y863250D02*
X706560Y863310D01*
Y870250D01*
G01X701440Y876750D02*
X697250D01*
G01X720500Y478750D02*
X724000D01*
G01D02*
X724940Y477810D01*
Y471072D01*
G01X714000Y871250D02*
X717000D01*
X717810Y870440D01*
X721250D01*
G01X743000Y571750D02*
X740500D01*
G01X743000Y575250D02*
X742530Y575720D01*
G01X727750Y875560D02*
X733440D01*
G01X756000Y579750D02*
X757502Y578248D01*
G01X756000Y583250D02*
X758250D01*
X760692Y580808D01*
G01X801750Y856000D02*
X801690Y856060D01*
X789250D01*
G01X782750Y850940D02*
Y845750D01*
G01X801750Y860500D02*
X797500D01*
X793250Y864750D01*
X788060D01*
G01X782940Y871250D02*
Y875060D01*
X781000Y877000D01*
G01X832750Y846440D02*
X821940D01*
X821250Y845750D01*
G01X839250Y851560D02*
Y854500D01*
G01X838750Y868560D02*
X845690D01*
X845750Y868500D01*
G01X832250Y863440D02*
X826060D01*
G01X868936Y687711D02*
X868289D01*
X865500Y690500D01*
G01X874056Y695111D02*
X878111D01*
X878500Y695500D01*
G01X1030098Y897618D02*
X1027716Y900000D01*
G01X1101986Y823344D02*
X1098500D01*
G01X1113250Y817000D02*
X1113094Y816844D01*
X1107106D01*
G01X1134000Y613500D02*
X1137500D01*
X1141250Y617250D01*
Y618000D01*
G01X1142000Y622250D02*
Y618750D01*
X1141250Y618000D01*
G01X1146500Y622250D02*
Y619500D01*
X1147000Y619000D01*
G01X1212840Y775850D02*
Y781000D01*
G01X1201060Y862250D02*
X1203750D01*
X1204000Y862000D01*
G01X1214060Y862250D02*
X1217250D01*
G54D67*
X214400Y912820D03*
Y898980D03*
G54D94*
X332829Y248400D03*
X341029D03*
X332829Y262600D03*
X341029D03*
G54D169*
X1348084Y282053D03*
Y320611D03*
X1363084Y282053D03*
X1358084D03*
X1353084D03*
Y320611D03*
X1358084D03*
X1363084D03*
X1378084Y282053D03*
X1373084D03*
X1368084D03*
Y320611D03*
X1373084D03*
X1378084D03*
X1383084Y282053D03*
Y320611D03*
G54D85*
X311085Y217872D03*
X308885D03*
X311085Y221372D03*
X308885D03*
X303529Y336000D03*
X301329D03*
X303529Y332000D03*
X301329D03*
X341640Y132500D03*
X339440D03*
X341640Y130000D03*
X339440D03*
X341640Y136500D03*
X339440D03*
X341640Y139000D03*
X339440D03*
X341640Y143000D03*
X339440D03*
X341640Y145500D03*
X339440D03*
X341640Y152000D03*
X339440D03*
X341640Y149500D03*
X339440D03*
X341640Y169000D03*
X339440D03*
X341640Y171500D03*
X339440D03*
X341640Y165000D03*
X339440D03*
X341640Y156000D03*
X339440D03*
X341640Y162500D03*
X339440D03*
X341640Y158500D03*
X339440D03*
X341640Y175500D03*
X339440D03*
X341640Y178000D03*
X339440D03*
G54D76*
X257200Y859500D03*
G54D49*
X153937Y238898D03*
Y246772D03*
Y260551D03*
X224015Y234961D03*
Y246772D03*
Y260551D03*
G54D58*
X180118Y729409D03*
Y739409D03*
X200118Y729409D03*
X190118D03*
X200118Y739409D03*
X190118D03*
X210118Y729409D03*
Y739409D03*
X230118Y729409D03*
X220118D03*
X230118Y739409D03*
X220118D03*
X250118Y729409D03*
X240118D03*
X250118Y739409D03*
X240118D03*
X260118Y729409D03*
Y739409D03*
X270118Y729409D03*
Y739409D03*
G54D179*
G01X41304Y927220D02*
X39804Y928720D01*
Y931220D01*
G01X97500Y931000D02*
Y927388D01*
X96412Y926300D01*
X95700D01*
G01X128000Y544050D02*
X128500Y543550D01*
Y532608D01*
X161608Y499500D01*
X184500D01*
X215500Y468500D01*
X224869D01*
X258691Y434678D01*
X260909D01*
G01X204500Y470000D02*
Y470306D01*
X184856Y489950D01*
X161960D01*
X121000Y530910D01*
Y545500D01*
G01X204500Y470000D02*
X204806D01*
X212806Y462000D01*
X219500D01*
X262500Y419000D01*
X262981D01*
X263153Y418828D01*
X290559D01*
X291409Y419678D01*
G01X1088500Y761300D02*
X1091250Y764050D01*
Y764750D01*
X1093000Y766500D01*
G01X1300784Y830782D02*
Y826216D01*
X1303784Y823216D01*
Y821032D01*
G54D86*
X330200Y9000D03*
Y20000D03*
X347600Y9000D03*
X338900D03*
X347600Y20000D03*
X338900D03*
X356300Y9000D03*
X365000D03*
X356300Y20000D03*
X365000D03*
X359000Y34000D03*
Y45000D03*
X377000Y34000D03*
X368000D03*
X377000Y45000D03*
X368000D03*
X1047500Y831500D03*
Y842500D03*
X1075500Y893500D03*
Y882500D03*
X1180500Y826000D03*
Y837000D03*
X1374500Y438500D03*
Y449500D03*
G54D68*
X226921Y848750D03*
X224953D03*
X222984D03*
X221016D03*
X219047D03*
X217079D03*
Y868250D03*
X219047D03*
X221016D03*
X222984D03*
X224953D03*
X226921D03*
G54D77*
X252800Y859500D03*
G54D59*
X200000Y391500D03*
Y401500D03*
Y411500D03*
Y421500D03*
X216500Y391500D03*
Y401500D03*
Y411500D03*
Y421500D03*
X1296000Y319500D03*
Y329500D03*
X1367067Y42323D03*
Y60039D03*
Y78544D03*
Y96260D03*
X1392657Y42323D03*
Y60039D03*
Y78544D03*
Y96260D03*
G54D95*
X342429Y316600D03*
Y314400D03*
X346429Y316600D03*
Y314400D03*
X516283Y318377D03*
X519283D03*
X516283Y320577D03*
X519283D03*
G54D69*
X222000Y858500D03*
G54D87*
X331180Y72321D03*
Y68384D03*
X320664Y70353D03*
G54D78*
X271500Y893500D03*
Y902500D03*
G54D96*
X364700Y55500D03*
X376300D03*
X576300Y380500D03*
X564700D03*
X576300Y394000D03*
X564700D03*
X576300Y421000D03*
X564700D03*
X576300Y407500D03*
X564700D03*
X886200Y70500D03*
Y84500D03*
X897800Y70500D03*
Y84500D03*
X1247700Y176000D03*
Y189000D03*
X1259300Y176000D03*
Y189000D03*
G54D79*
X299474Y111000D03*
X332526D03*
G54D97*
G01X40054Y849780D02*
X42880D01*
X44500Y851400D01*
Y851500D01*
G01X109000Y844220D02*
X104554D01*
G01X390988Y256450D02*
Y259988D01*
X392500Y261500D01*
Y262400D01*
X392600Y262500D01*
Y264700D01*
X392200Y265100D01*
Y278403D01*
X381278Y289325D01*
X316625D01*
X316400Y289100D01*
X303700D01*
X280200Y312600D01*
Y385800D01*
X254581Y411420D01*
X254580D01*
X250353Y415647D01*
X236853D01*
X236800Y415700D01*
X231132D01*
X230000Y416832D01*
Y439500D01*
X203050Y466450D01*
X203028D01*
X200950Y468528D01*
Y468550D01*
X183100Y486400D01*
X172000D01*
G01X418700Y402953D02*
X416731Y404922D01*
G01X418700Y406890D02*
X418699D01*
X416731Y404922D01*
G01X434448Y347834D02*
Y347833D01*
X436416Y345865D01*
G01X852500Y636940D02*
X858800D01*
G01X1064208Y201524D02*
X1061992D01*
X1060000Y203516D01*
Y207500D01*
G01X1069328Y208924D02*
X1072500D01*
G01X1202218Y804284D02*
Y801282D01*
X1205128Y798372D01*
X1205160Y792150D01*
X360433Y131496D03*
Y134645D03*
X357284D03*
X360433Y137795D03*
X357284D03*
X360433Y216535D03*
X357284D03*
X360433Y219685D03*
X357284D03*
X360433Y222834D03*
X363583Y131496D03*
Y134645D03*
Y137795D03*
Y216535D03*
Y219685D03*
Y222834D03*
X442323Y131496D03*
Y134645D03*
Y137795D03*
Y216535D03*
Y219685D03*
Y222834D03*
X445473Y131496D03*
X448622Y134645D03*
X445473D03*
X448622Y137795D03*
X445473D03*
X448622Y216535D03*
X445473D03*
X448622Y219685D03*
X445473D03*
Y222834D03*
X1121397Y662363D03*
X1124547D03*
X1127696D03*
X1121397Y659213D03*
X1124547D03*
X1127696D03*
X1121397Y665512D03*
X1124547D03*
X1127696D03*
X1121397Y725355D03*
X1124547D03*
X1127696D03*
X1121397Y722205D03*
X1124547D03*
X1127696D03*
X1121397Y719056D03*
X1124547D03*
X1127696D03*
X1181240Y662363D03*
Y659213D03*
Y665512D03*
Y725355D03*
Y722205D03*
Y719056D03*
X1184389Y662363D03*
X1187539D03*
X1184389Y659213D03*
X1187539D03*
X1184389Y665512D03*
X1187539D03*
X1184389Y725355D03*
X1187539D03*
X1184389Y722205D03*
X1187539D03*
X1184389Y719056D03*
X1187539D03*
G54D88*
X323214Y74290D03*
G54D89*
X317514Y80195D03*
Y76258D03*
Y78227D03*
X334330Y80195D03*
Y78227D03*
Y76258D03*
Y74290D03*
G54D98*
G01X40945Y393623D02*
Y384710D01*
G01X50395Y393623D02*
Y384679D01*
G01X39370Y403503D02*
Y412673D01*
G01X48820Y403503D02*
Y412435D01*
G01X43804Y932470D02*
X45270Y931004D01*
Y921988D01*
G01X59840Y393623D02*
Y384679D01*
G01X58270Y403503D02*
Y412485D01*
G01X67715Y403503D02*
Y412518D01*
G01X66612Y820904D02*
X72672D01*
G01X64052D02*
Y825284D01*
X66022Y827254D01*
G01X69290Y393623D02*
Y384865D01*
G01X78740Y393623D02*
Y384915D01*
G01X77165Y403503D02*
Y412590D01*
G01X77992Y729959D02*
Y724724D01*
X77272Y724004D01*
G01X93347Y765754D02*
Y752049D01*
G01X87928Y853207D02*
Y848107D01*
G01X85304Y884470D02*
X85368Y884406D01*
Y875297D01*
G01X201805Y552940D02*
X195865D01*
G01X317514Y80195D02*
X317305D01*
X316000Y81500D01*
X311500D01*
G01X326906Y83682D02*
Y89406D01*
X327000Y89500D01*
G01X360433Y144094D02*
X360435D01*
X362009Y142520D01*
G01X357284Y144094D02*
Y143855D01*
X356429Y143000D01*
X352040D01*
G01X377787Y148812D02*
X379331Y150356D01*
Y150393D01*
G01X377787Y148812D02*
X376219Y147244D01*
X376181D01*
G01X373032Y153543D02*
X372994D01*
X371457Y155080D01*
G01X376181Y150393D02*
Y150422D01*
X377759Y152000D01*
G01X366733Y144094D02*
Y144083D01*
X365182Y142532D01*
G01X373032Y162992D02*
Y162954D01*
X374582Y161404D01*
G01X376181Y162992D02*
X376144D01*
X374577Y164559D01*
G01X376181Y169291D02*
X377736Y170846D01*
X377750D01*
G01X376181Y156693D02*
X376144D01*
X374570Y158267D01*
G01X366733Y162992D02*
Y162957D01*
X365176Y161400D01*
G01X368336Y189755D02*
X369882Y188209D01*
Y188189D01*
G01X366733D02*
Y188151D01*
X365187Y186605D01*
G01X363583Y185039D02*
X365149Y186605D01*
X365187D01*
G01X366733Y181889D02*
X366540D01*
X364117Y184312D01*
Y184539D01*
X363617Y185039D01*
X363583D01*
G01X368307Y196062D02*
X369881Y194488D01*
X369882D01*
G01X368307Y196062D02*
X366733Y197636D01*
Y197637D01*
G01X368307Y202361D02*
X369881Y200787D01*
X369882D01*
G01X368307Y202361D02*
X366733Y203935D01*
Y203937D01*
G01X369882D02*
X369881D01*
X368307Y205511D01*
G01X369882Y197637D02*
X369881D01*
X368307Y199211D01*
G01X366733Y200787D02*
Y200785D01*
X368307Y199211D01*
G01X373032Y219685D02*
X374607Y218110D01*
G01X376181Y213385D02*
X374606Y211810D01*
G01X373032Y210236D02*
X374606Y211810D01*
G01X380906D02*
X379332Y210236D01*
X379331D01*
G01Y213385D02*
X377756Y211810D01*
G01X376181Y210236D02*
X376182D01*
X377756Y211810D01*
G01X366733Y207086D02*
Y207085D01*
X368307Y205511D01*
G01X366733Y213385D02*
X365158Y211810D01*
G01X373032Y213385D02*
X371457Y211810D01*
G01X369882Y210236D02*
X369883D01*
X371457Y211810D01*
G01X367500Y873250D02*
X368900Y874650D01*
Y882420D01*
G01X388780Y150393D02*
Y150431D01*
X390339Y151990D01*
G01X388780Y153543D02*
X388786D01*
X390339Y151990D01*
G01X395079Y150393D02*
Y150430D01*
X396639Y151990D01*
G01X382481Y150393D02*
Y150392D01*
X380888Y148799D01*
G01X395079Y166141D02*
X396653Y167715D01*
G01X390354D02*
X391929Y169290D01*
Y169291D01*
G01X390354Y167715D02*
X391928Y166141D01*
X391929D01*
G01X388780Y169291D02*
Y169290D01*
X387205Y167715D01*
G01X382481Y169291D02*
Y169254D01*
X380928Y167701D01*
G01X395079Y169291D02*
Y169253D01*
X393528Y167702D01*
G01X382481Y185039D02*
X384055Y186613D01*
G01X395079Y185039D02*
X396654Y186614D01*
G01X395079Y172441D02*
X396653Y174015D01*
G01X395079Y178740D02*
X396653Y180314D01*
G01X390392Y186614D02*
X388817Y185039D01*
X388780D01*
G01X390392Y186614D02*
X391929Y188151D01*
Y188189D01*
G01X382481D02*
Y188192D01*
X384036Y189747D01*
G01X382481Y175590D02*
X382518Y175627D01*
X382537D01*
X384030Y177120D01*
G01X391929Y185039D02*
X391967D01*
X393542Y186614D01*
G01X395079Y188189D02*
Y188151D01*
X393542Y186614D01*
G01X391929Y172441D02*
Y172478D01*
X393490Y174039D01*
G01X395079Y175590D02*
X395041D01*
X393490Y174039D01*
G01X395079Y181889D02*
Y181853D01*
X393541Y180315D01*
G01X391929Y178740D02*
X391969D01*
X393541Y180312D01*
Y180315D01*
G01X395079Y191338D02*
X396653Y192912D01*
G01X382481Y213385D02*
X380906Y211810D01*
G01X385630Y213385D02*
X384055Y211810D01*
G01X382481Y210236D02*
X384055Y211810D01*
G01X401378Y150393D02*
X401381D01*
X402938Y151950D01*
G01X401378Y166141D02*
X402952Y167715D01*
G01X407677Y166141D02*
X409251Y167715D01*
G01X410827Y169291D02*
X409251Y167715D01*
G01X404528Y169291D02*
X402952Y167715D01*
G01X398229Y169291D02*
X396653Y167715D01*
G01X401378Y169291D02*
Y169253D01*
X399827Y167702D01*
G01X398229Y166141D02*
X398266D01*
X399827Y167702D01*
G01X404528Y166141D02*
X404565D01*
X406140Y167716D01*
G01X407677Y169291D02*
Y169253D01*
X406140Y167716D01*
G01X407677Y162992D02*
Y162954D01*
X406127Y161404D01*
G01X410827Y166141D02*
X410864D01*
X412426Y167703D01*
G01X413977Y162992D02*
Y162954D01*
X412427Y161404D01*
G01X413977Y169291D02*
Y169254D01*
X412426Y167703D01*
G01X404528Y188189D02*
X402952Y186613D01*
G01X410827Y188189D02*
X409251Y186613D01*
G01X401378Y178740D02*
X402952Y180314D01*
G01X407677Y172441D02*
X409251Y174015D01*
G01X407677Y185039D02*
X409251Y186613D01*
G01X401378Y185039D02*
X402952Y186613D01*
G01X398229Y188189D02*
X396654Y186614D01*
G01X402977Y174003D02*
X404528Y175554D01*
Y175590D01*
G01X396653Y180314D02*
X398228Y181889D01*
X398229D01*
G01X402952Y180314D02*
X404527Y181889D01*
X404528D01*
G01X402977Y174003D02*
X401415Y172441D01*
X401378D01*
G01X396653Y174015D02*
X398228Y175590D01*
X398229D01*
G01X409288Y180315D02*
X410827Y181854D01*
Y181889D01*
G01X409288Y180315D02*
X407713Y178740D01*
X407677D01*
G01X409251Y174015D02*
X410826Y175590D01*
X410827D01*
G01X398229Y185039D02*
X398266D01*
X399841Y186614D01*
G01X401378Y188189D02*
Y188151D01*
X399841Y186614D01*
G01X398229Y178740D02*
X398265D01*
X399840Y180315D01*
G01X401378Y181889D02*
Y181853D01*
X399840Y180315D01*
G01X401378Y175590D02*
X401341D01*
X399790Y174039D01*
G01X404528Y172441D02*
X404564D01*
X406126Y174003D01*
G01X407677Y175590D02*
Y175554D01*
X406126Y174003D01*
G01X404528Y178740D02*
X404564D01*
X406139Y180315D01*
G01X407677Y181889D02*
Y181853D01*
X406139Y180315D01*
G01X407677Y188189D02*
X406101Y186613D01*
G01X404528Y185039D02*
Y185040D01*
X406101Y186613D01*
G01X410827Y172441D02*
X410864D01*
X412426Y174003D01*
G01X413977Y175590D02*
Y175554D01*
X412426Y174003D01*
G01X413977Y188189D02*
Y188152D01*
X412439Y186614D01*
G01X410827Y185039D02*
X410864D01*
X412439Y186614D01*
G01X413977Y181889D02*
X413975D01*
X412400Y180314D01*
G01X410827Y178740D02*
Y178741D01*
X412400Y180314D01*
G01X398229Y172441D02*
Y172478D01*
X399790Y174039D01*
G01X401378Y191338D02*
X402952Y192912D01*
G01X407677Y191338D02*
X409251Y192912D01*
G01X404528Y191338D02*
X404565D01*
X406128Y192901D01*
G01X398229Y191338D02*
Y191376D01*
X399791Y192938D01*
G01X410827Y191338D02*
X410865D01*
X412428Y192901D01*
G01X413977Y213385D02*
X412402Y211810D01*
G01X401378Y213385D02*
X402953Y211810D01*
G01D02*
X404527Y210236D01*
X404528D01*
G01X412402Y211810D02*
X410828Y210236D01*
X410827D01*
G01X401378D02*
X401377D01*
X399803Y211810D01*
G01X407677Y210236D02*
X407676D01*
X406102Y211810D01*
G01X404528Y213385D02*
Y213384D01*
X406102Y211810D01*
G01X402525Y239975D02*
Y235541D01*
X401778Y234794D01*
Y233753D01*
X401354Y233329D01*
Y230409D01*
X398931Y227985D01*
Y223536D01*
X398229Y222834D01*
G01X402000Y240500D02*
X402525Y239975D01*
G01X415575Y167703D02*
X417126Y169254D01*
Y169291D01*
G01X415575Y167703D02*
X414013Y166141D01*
X413977D01*
G01X426575Y159842D02*
X428149Y161416D01*
G01X418726Y167703D02*
X417164Y166141D01*
G01X420276Y162992D02*
Y163029D01*
X417164Y166141D01*
G01X420276Y169291D02*
Y169253D01*
X418726Y167703D01*
G01X417164Y166141D02*
X417126D01*
G01X413977Y172441D02*
X415551Y174015D01*
G01X417126Y188189D02*
X415551Y186614D01*
G01X417126Y175590D02*
X415551Y174015D01*
G01Y186614D02*
X413977Y185040D01*
Y185039D01*
G01X415587Y180315D02*
X414012Y178740D01*
X413977D01*
G01X415587Y180315D02*
X417126Y181854D01*
Y181889D01*
G01X420276Y175590D02*
Y175553D01*
X418726Y174003D01*
G01X420276Y181889D02*
Y181853D01*
X418726Y180303D01*
G01X417126Y185039D02*
X418701Y186614D01*
G01X420276Y188189D02*
X418701Y186614D01*
G01X417126Y178740D02*
X417163D01*
X418726Y180303D01*
G01X417126Y172441D02*
X417164D01*
X418726Y174003D01*
G01X413977Y191338D02*
X415551Y192912D01*
G01X421876Y192902D02*
X423425Y194451D01*
Y194488D01*
G01X421876Y192902D02*
X420312Y191338D01*
X420276D01*
G01X423425D02*
X424999Y192912D01*
G01X417126Y191338D02*
X417163D01*
X418727Y192902D01*
G01X420276Y194488D02*
Y194451D01*
X418727Y192902D01*
G01X420276Y213385D02*
X418701Y211810D01*
G01D02*
X417127Y210236D01*
X417126D01*
G01X425001Y211810D02*
X426575Y213384D01*
Y213385D01*
G01X425001Y211810D02*
X423427Y210236D01*
X423425D01*
G01X426575D02*
X426576D01*
X428150Y211810D01*
G01X429725Y213385D02*
X428150Y211810D01*
G01X415551D02*
X417126Y213385D01*
G01X413977Y210236D02*
X415551Y211810D01*
G01X423425Y213385D02*
X421850Y211810D01*
G01X420276Y210236D02*
X421850Y211810D01*
G01X436024Y150393D02*
Y150392D01*
X437598Y148818D01*
G01X439173Y147244D02*
X439172D01*
X437598Y148818D01*
G01X436024Y156693D02*
Y156692D01*
X437598Y155118D01*
G01X439173Y153543D02*
X437598Y155118D01*
G01X429725Y159842D02*
X431299Y161416D01*
G01X439173Y166141D02*
X437598Y167716D01*
G01X436024Y169291D02*
Y169290D01*
X437598Y167716D01*
G01X439173Y159842D02*
X437598Y161417D01*
G01X436024Y162992D02*
Y162991D01*
X437598Y161417D01*
G01X439173Y172441D02*
X439172D01*
X437598Y174015D01*
G01X436024Y175590D02*
Y175589D01*
X437598Y174015D01*
G01X439173Y178740D02*
X439172D01*
X437598Y180314D01*
G01X436024Y181889D02*
Y181888D01*
X437598Y180314D01*
G01X439173Y185039D02*
X437598Y186614D01*
G01X439173Y203937D02*
X439172D01*
X437598Y205511D01*
G01X439173Y197637D02*
X437598Y199212D01*
G01X436024Y200787D02*
Y200786D01*
X437598Y199212D01*
G01X439173Y191338D02*
X437598Y192913D01*
G01X436024Y194488D02*
Y194487D01*
X437598Y192913D01*
G01X432874Y213385D02*
X434449Y211810D01*
G01D02*
X436023Y210236D01*
X436024D01*
G01Y213385D02*
Y213384D01*
X437598Y211810D01*
G01X439173Y210236D02*
X439172D01*
X437598Y211810D01*
G01X436024Y207086D02*
Y207085D01*
X437598Y205511D01*
G01X432874Y210236D02*
X429725Y213385D01*
G01X438385Y343897D02*
X438153Y343665D01*
X434680D01*
X434448Y343897D01*
G01X740500Y571750D02*
X739090Y573160D01*
X736400D01*
G01X742530Y575720D02*
X736400D01*
G01X757502Y578248D02*
X765694D01*
G01X760692Y580808D02*
X765694D01*
G01X1002340Y513600D02*
Y519840D01*
X1002500Y520000D01*
G01X994500Y532000D02*
X994660Y531840D01*
Y526400D01*
G01X1016340Y513600D02*
Y519340D01*
X1016500Y519500D01*
G01X1008500Y533400D02*
Y531840D01*
X1008660Y531680D01*
Y526400D01*
G01X1032657Y874725D02*
Y873324D01*
X1032641D01*
X1032600Y873283D01*
Y867657D01*
G01X1030098Y894211D02*
Y897618D01*
G01X1045750Y697000D02*
X1043016D01*
X1041410Y695394D01*
G01X1045750Y693000D02*
X1043716D01*
X1041410Y690694D01*
G01X1045750Y709000D02*
X1041606D01*
X1041410Y708804D01*
G01X1045750Y705000D02*
X1042186D01*
X1041410Y704224D01*
G01X1045750Y701000D02*
X1042576D01*
X1041410Y699834D01*
G01X1066250Y668000D02*
X1065978Y664568D01*
G01X1066250Y673000D02*
X1063100D01*
X1062700Y672600D01*
G01X1077750Y667500D02*
X1076500D01*
X1074500Y665500D01*
G01X1087988Y745374D02*
X1094978D01*
X1095006Y745402D01*
G01X1102000Y864500D02*
X1102666Y865166D01*
X1106725D01*
G01X1118300Y756750D02*
Y759853D01*
X1124460Y766013D01*
Y768140D01*
G01X1124547Y668662D02*
X1123048Y670161D01*
Y670199D01*
X1122985Y670262D01*
G01X1121397Y674961D02*
Y674999D01*
X1122938Y676540D01*
G01X1124547Y674961D02*
X1124517D01*
X1122938Y676540D01*
G01X1121397Y668662D02*
Y668674D01*
X1122985Y670262D01*
G01X1124547Y678111D02*
X1124509D01*
X1122938Y676540D01*
G01X1121397Y678111D02*
X1121401Y678107D01*
Y678077D01*
X1122938Y676540D01*
G01X1121397Y684410D02*
X1120546D01*
X1120000Y683864D01*
X1119265D01*
G01X1133996Y712756D02*
X1135517Y711235D01*
X1135529D01*
X1135546Y711218D01*
X1135570D01*
G01X1130846Y712756D02*
X1132314Y711288D01*
X1132318D01*
X1132417Y711189D01*
G01X1133996Y715906D02*
X1132490Y714400D01*
Y714390D01*
X1132445Y714345D01*
G01X1127696Y719056D02*
X1130846Y715906D01*
G01D02*
X1129290Y714350D01*
X1129260D01*
G01X1133996Y722205D02*
X1133979D01*
X1132398Y720624D01*
G01X1130846Y719056D02*
X1132318Y720528D01*
Y720544D01*
X1132398Y720624D01*
G01X1130846Y722205D02*
Y722176D01*
X1132398Y720624D01*
G01X1133996Y719056D02*
X1132520Y717580D01*
Y717542D01*
X1132459Y717481D01*
G01X1122800Y756750D02*
X1130760Y764710D01*
Y766560D01*
X1130900Y766700D01*
G01X1131095Y772186D02*
Y767995D01*
X1130900Y767800D01*
Y766700D01*
G01X1124796Y772186D02*
Y768476D01*
X1124460Y768140D01*
G01X1134244Y772186D02*
Y769146D01*
X1134245Y769145D01*
G01X1127945Y772186D02*
Y769970D01*
G01X1121646Y772186D02*
Y770432D01*
X1121215Y770001D01*
Y769936D01*
G01X1131095Y797382D02*
Y799965D01*
G01X1124796Y797382D02*
Y800150D01*
G01X1134244Y797382D02*
Y799984D01*
G01X1127945Y797382D02*
Y799935D01*
G01X1121646Y797382D02*
Y799924D01*
G01X1126211Y867725D02*
X1131275D01*
G01X1152893Y662363D02*
X1151337Y660807D01*
G01X1149744Y659213D02*
Y659214D01*
X1151337Y660807D01*
G01X1149744Y674961D02*
X1151793Y677010D01*
X1152090D01*
G01X1152893Y671812D02*
X1151337Y670256D01*
G01X1143444Y675091D02*
Y674961D01*
G01X1146594D02*
X1143574D01*
X1143444Y675091D01*
G01X1141954Y676581D02*
X1143444Y675091D01*
G01X1137145Y681260D02*
Y681298D01*
X1135589Y682854D01*
G01D02*
X1137145Y684410D01*
G01Y697008D02*
Y696971D01*
X1135589Y695415D01*
G01D02*
X1137145Y693859D01*
G01Y690709D02*
X1138493D01*
X1139858Y692074D01*
G01X1137145Y687560D02*
X1139000Y685705D01*
Y685667D01*
G01X1146594Y709607D02*
Y709434D01*
X1144880Y707720D01*
G01X1143444Y709607D02*
Y709156D01*
X1144880Y707720D01*
G01X1137145Y703308D02*
X1135589Y701752D01*
Y701714D01*
G01X1149744Y709607D02*
X1143337Y703200D01*
X1137530D01*
X1137422Y703308D01*
X1137145D01*
G01X1152893Y709607D02*
Y709637D01*
X1151352Y711178D01*
G01X1135589Y701714D02*
X1137145Y700158D01*
G01X1151352Y711178D02*
X1149781Y709607D01*
X1149744D01*
G01X1146843Y772186D02*
Y769783D01*
X1146480Y769420D01*
G01X1149992Y778485D02*
Y779790D01*
X1150310Y780108D01*
Y783840D01*
G01X1140544Y775335D02*
X1142040Y773839D01*
Y773829D01*
X1142095Y773774D01*
G01X1149992Y775335D02*
X1150005D01*
X1151592Y773748D01*
G01X1143693Y775335D02*
X1145240Y776882D01*
Y776920D01*
X1145265Y776945D01*
G01X1143693Y794233D02*
X1143683D01*
X1142110Y792660D01*
G01X1149992Y797382D02*
Y797632D01*
X1150094Y797734D01*
Y799306D01*
X1149400Y800000D01*
G01X1156043Y674961D02*
Y674936D01*
X1154470Y673363D01*
G01X1159192Y674961D02*
X1159194D01*
X1160768Y676535D01*
G01D02*
X1162342Y674961D01*
G01X1152893D02*
Y676078D01*
X1152090Y676881D01*
Y677010D01*
G01X1162342Y674961D02*
X1162553D01*
X1163044Y675452D01*
X1164784D01*
X1165275Y674961D01*
X1165492D01*
G01X1156043Y668662D02*
Y668643D01*
X1154496Y667096D01*
G01X1159192Y709607D02*
Y709482D01*
X1157670Y707960D01*
G01X1156043Y709607D02*
Y709587D01*
X1157670Y707960D01*
G01X1165492Y709607D02*
X1163968Y708083D01*
Y708018D01*
G01X1162342Y709607D02*
X1162379D01*
X1163968Y708018D01*
G01Y708000D02*
Y708018D01*
G01X1156292Y772186D02*
Y770808D01*
X1157400Y769700D01*
X1158100D01*
G01X1162591Y772186D02*
Y770371D01*
X1162450Y770230D01*
Y769190D01*
G01X1159441Y772186D02*
Y770800D01*
X1158341Y769700D01*
X1158100D01*
G01X1165740Y772186D02*
Y771870D01*
X1167320Y770290D01*
G01X1156292Y775335D02*
Y775308D01*
X1157871Y773729D01*
Y773728D01*
G01X1159441Y775335D02*
Y775298D01*
X1157871Y773728D01*
G01X1168890Y772186D02*
Y771860D01*
X1167320Y770290D01*
G01X1159441Y794233D02*
X1160964Y792710D01*
X1161001D01*
X1161051Y792660D01*
G01X1165740Y794233D02*
X1164300Y795673D01*
Y795710D01*
X1164196Y795814D01*
G01X1162591Y797382D02*
X1164054Y795919D01*
X1164091D01*
X1164196Y795814D01*
G01X1165740Y791083D02*
X1167260Y792603D01*
Y792641D01*
X1167277Y792658D01*
G01X1156292Y797382D02*
X1156328D01*
X1157866Y795844D01*
G01X1159441Y797382D02*
X1159404D01*
X1157866Y795844D01*
G01X1156292Y794233D02*
Y794270D01*
X1157866Y795844D01*
G01X1165740Y797382D02*
X1167292Y795830D01*
X1167330D01*
G01X1153142Y797382D02*
X1153162D01*
X1154780Y799000D01*
X1154800D01*
G01X1174940Y697008D02*
X1176496Y698564D01*
G01X1178090Y697008D02*
X1178052D01*
X1176496Y698564D01*
G01X1181240Y697008D02*
X1181228D01*
X1179671Y698565D01*
G01X1171791Y690709D02*
X1171801D01*
X1173389Y689121D01*
G01X1171791Y687560D02*
X1171828D01*
X1173389Y689121D01*
G01X1181240Y706457D02*
X1182796Y708013D01*
G01X1181240Y700158D02*
X1181274D01*
X1182813Y698619D01*
G01X1178090Y700158D02*
X1176496Y698564D01*
G01X1174940Y703308D02*
Y700158D01*
G01D02*
Y700120D01*
X1176496Y698564D01*
G01X1171791Y700158D02*
Y700149D01*
X1173350Y698590D01*
G01X1171791Y703308D02*
Y700158D01*
G01X1187539Y693859D02*
X1187501D01*
X1185945Y695415D01*
G01X1184389Y697008D02*
Y696971D01*
X1185945Y695415D01*
G01X1184389Y693859D02*
X1185945Y695415D01*
G01X1187539Y697008D02*
X1187538D01*
X1185945Y695415D01*
G01X1187539Y700158D02*
X1189342D01*
X1190000Y699500D01*
X360433Y140945D03*
X357284D03*
X360433Y144094D03*
X357284D03*
X360433Y147244D03*
X357284D03*
X360433Y150393D03*
X357284D03*
X360433Y153543D03*
X357284D03*
X360433Y156693D03*
X357284D03*
X360433Y159842D03*
X357284D03*
X360433Y162992D03*
X357284D03*
X360433Y166141D03*
X357284D03*
X360433Y169291D03*
X357284D03*
X360433Y172441D03*
X357284D03*
X360433Y175590D03*
X357284D03*
X360433Y178740D03*
X357284D03*
X360433Y181889D03*
X357284D03*
X360433Y185039D03*
X357284D03*
X360433Y188189D03*
X357284D03*
X360433Y191338D03*
X357284D03*
X360433Y194488D03*
X357284D03*
X360433Y197637D03*
X357284D03*
X360433Y200787D03*
X357284D03*
X360433Y203937D03*
X357284D03*
X360433Y207086D03*
X357284D03*
X360433Y210236D03*
X357284D03*
X360433Y213385D03*
X357284D03*
X379331Y131496D03*
X376181D03*
X373032D03*
X369882D03*
X366733D03*
X379331Y134645D03*
X376181D03*
X373032D03*
X369882D03*
X366733D03*
X379331Y137795D03*
X376181D03*
X373032D03*
X369882D03*
X366733D03*
X379331Y140945D03*
X376181D03*
X373032D03*
X369882D03*
X366733D03*
X363583D03*
X379331Y144094D03*
X376181D03*
X373032D03*
X369882D03*
X366733D03*
X363583D03*
X379331Y147244D03*
X376181D03*
X373032D03*
X369882D03*
X366733D03*
X363583D03*
X379331Y150393D03*
X376181D03*
X373032D03*
X369882D03*
X366733D03*
X363583D03*
X379331Y153543D03*
X376181D03*
X373032D03*
X369882D03*
X366733D03*
X363583D03*
X379331Y156693D03*
X376181D03*
X373032D03*
X369882D03*
X366733D03*
X363583D03*
X379331Y159842D03*
X376181D03*
X373032D03*
X369882D03*
X366733D03*
X363583D03*
X379331Y162992D03*
X376181D03*
X373032D03*
X369882D03*
X366733D03*
X363583D03*
X379331Y166141D03*
X376181D03*
X373032D03*
X369882D03*
X366733D03*
X363583D03*
X379331Y169291D03*
X376181D03*
X373032D03*
X369882D03*
X366733D03*
X363583D03*
X379331Y172441D03*
X376181D03*
X373032D03*
X369882D03*
X366733D03*
X363583D03*
X379331Y175590D03*
X376181D03*
X373032D03*
X369882D03*
X366733D03*
X363583D03*
X379331Y178740D03*
X376181D03*
X373032D03*
X369882D03*
X366733D03*
X363583D03*
X379331Y181889D03*
X376181D03*
X373032D03*
X369882D03*
X366733D03*
X363583D03*
X379331Y185039D03*
X376181D03*
X373032D03*
X369882D03*
X366733D03*
X363583D03*
X379331Y188189D03*
X376181D03*
X373032D03*
X369882D03*
X366733D03*
X363583D03*
X379331Y191338D03*
X376181D03*
X373032D03*
X369882D03*
X366733D03*
X363583D03*
X379331Y194488D03*
X376181D03*
X373032D03*
X369882D03*
X366733D03*
X363583D03*
X379331Y197637D03*
X376181D03*
X373032D03*
X369882D03*
X366733D03*
X363583D03*
X379331Y200787D03*
X376181D03*
X373032D03*
X369882D03*
X366733D03*
X363583D03*
X379331Y203937D03*
X376181D03*
X373032D03*
X369882D03*
X366733D03*
X363583D03*
X379331Y207086D03*
X376181D03*
X373032D03*
X369882D03*
X366733D03*
X363583D03*
X379331Y210236D03*
X376181D03*
X373032D03*
X369882D03*
X366733D03*
X363583D03*
X379331Y213385D03*
X376181D03*
X373032D03*
X369882D03*
X366733D03*
X363583D03*
X379331Y216535D03*
X376181D03*
X373032D03*
X369882D03*
X366733D03*
X379331Y219685D03*
X376181D03*
X373032D03*
X369882D03*
X366733D03*
X379331Y222834D03*
X376181D03*
X373032D03*
X369882D03*
X366733D03*
X395079Y131496D03*
X391929D03*
X388780D03*
X385630D03*
X382481D03*
X395079Y134645D03*
X391929D03*
X388780D03*
X385630D03*
X382481D03*
X395079Y137795D03*
X391929D03*
X388780D03*
X385630D03*
X382481D03*
X395079Y140945D03*
X391929D03*
X388780D03*
X385630D03*
X382481D03*
X395079Y144094D03*
X391929D03*
X388780D03*
X385630D03*
X382481D03*
X395079Y147244D03*
X391929D03*
X388780D03*
X385630D03*
X382481D03*
X395079Y150393D03*
X391929D03*
X388780D03*
X385630D03*
X382481D03*
X395079Y153543D03*
X391929D03*
X388780D03*
X385630D03*
X382481D03*
X395079Y156693D03*
X391929D03*
X388780D03*
X385630D03*
X382481D03*
X395079Y159842D03*
X391929D03*
X388780D03*
X385630D03*
X382481D03*
X395079Y162992D03*
X391929D03*
X388780D03*
X385630D03*
X382481D03*
X395079Y166141D03*
X391929D03*
X388780D03*
X385630D03*
X382481D03*
X395079Y169291D03*
X391929D03*
X388780D03*
X385630D03*
X382481D03*
X395079Y172441D03*
X391929D03*
X388780D03*
X385630D03*
X382481D03*
X395079Y175590D03*
X391929D03*
X388780D03*
X385630D03*
X382481D03*
X395079Y178740D03*
X391929D03*
X388780D03*
X385630D03*
X382481D03*
X395079Y181889D03*
X391929D03*
X388780D03*
X385630D03*
X382481D03*
X395079Y185039D03*
X391929D03*
X388780D03*
X385630D03*
X382481D03*
X395079Y188189D03*
X391929D03*
X388780D03*
X385630D03*
X382481D03*
X395079Y191338D03*
X391929D03*
X388780D03*
X385630D03*
X382481D03*
X395079Y194488D03*
X391929D03*
X388780D03*
X385630D03*
X382481D03*
X395079Y197637D03*
X391929D03*
X388780D03*
X385630D03*
X382481D03*
X395079Y200787D03*
X391929D03*
X388780D03*
X385630D03*
X382481D03*
X395079Y203937D03*
X391929D03*
X388780D03*
X385630D03*
X382481D03*
X395079Y207086D03*
X391929D03*
X388780D03*
X385630D03*
X382481D03*
X395079Y210236D03*
X391929D03*
X388780D03*
X385630D03*
X382481D03*
X395079Y213385D03*
X391929D03*
X388780D03*
X385630D03*
X382481D03*
X395079Y216535D03*
X391929D03*
X388780D03*
X385630D03*
X382481D03*
X395079Y219685D03*
X391929D03*
X388780D03*
X385630D03*
X382481D03*
X395079Y222834D03*
X391929D03*
X388780D03*
X385630D03*
X382481D03*
X410827Y131496D03*
X407677D03*
X404528D03*
X401378D03*
X398229D03*
X410827Y134645D03*
X407677D03*
X404528D03*
X401378D03*
X398229D03*
X410827Y137795D03*
X407677D03*
X404528D03*
X401378D03*
X398229D03*
X410827Y140945D03*
X407677D03*
X404528D03*
X401378D03*
X398229D03*
X410827Y144094D03*
X407677D03*
X404528D03*
X401378D03*
X398229D03*
X410827Y147244D03*
X407677D03*
X404528D03*
X401378D03*
X398229D03*
X410827Y150393D03*
X407677D03*
X404528D03*
X401378D03*
X398229D03*
X410827Y153543D03*
X407677D03*
X404528D03*
X401378D03*
X398229D03*
X410827Y156693D03*
X407677D03*
X404528D03*
X401378D03*
X398229D03*
X410827Y159842D03*
X407677D03*
X404528D03*
X401378D03*
X398229D03*
X410827Y162992D03*
X407677D03*
X404528D03*
X401378D03*
X398229D03*
X410827Y166141D03*
X407677D03*
X404528D03*
X401378D03*
X398229D03*
X410827Y169291D03*
X407677D03*
X404528D03*
X401378D03*
X398229D03*
X410827Y172441D03*
X407677D03*
X404528D03*
X401378D03*
X398229D03*
X410827Y175590D03*
X407677D03*
X404528D03*
X401378D03*
X398229D03*
X410827Y178740D03*
X407677D03*
X404528D03*
X401378D03*
X398229D03*
X410827Y181889D03*
X407677D03*
X404528D03*
X401378D03*
X398229D03*
X410827Y185039D03*
X407677D03*
X404528D03*
X401378D03*
X398229D03*
X410827Y188189D03*
X407677D03*
X404528D03*
X401378D03*
X398229D03*
X410827Y191338D03*
X407677D03*
X404528D03*
X401378D03*
X398229D03*
X410827Y194488D03*
X407677D03*
X404528D03*
X401378D03*
X398229D03*
X410827Y197637D03*
X407677D03*
X404528D03*
X401378D03*
X398229D03*
X410827Y200787D03*
X407677D03*
X404528D03*
X401378D03*
X398229D03*
X410827Y203937D03*
X407677D03*
X404528D03*
X401378D03*
X398229D03*
X410827Y207086D03*
X407677D03*
X404528D03*
X401378D03*
X398229D03*
X410827Y210236D03*
X407677D03*
X404528D03*
X401378D03*
X398229D03*
X410827Y213385D03*
X407677D03*
X404528D03*
X401378D03*
X398229D03*
X410827Y216535D03*
X407677D03*
X404528D03*
X401378D03*
X398229D03*
X410827Y219685D03*
X407677D03*
X404528D03*
X401378D03*
X398229D03*
X410827Y222834D03*
X407677D03*
X404528D03*
X401378D03*
X398229D03*
X426575Y131496D03*
X423425D03*
X420276D03*
X417126D03*
X413977D03*
X426575Y134645D03*
X423425D03*
X420276D03*
X417126D03*
X413977D03*
X426575Y137795D03*
X423425D03*
X420276D03*
X417126D03*
X413977D03*
X426575Y140945D03*
X423425D03*
X420276D03*
X417126D03*
X413977D03*
X426575Y144094D03*
X423425D03*
X420276D03*
X417126D03*
X413977D03*
X426575Y147244D03*
X423425D03*
X420276D03*
X417126D03*
X413977D03*
X426575Y150393D03*
X423425D03*
X420276D03*
X417126D03*
X413977D03*
X426575Y153543D03*
X423425D03*
X420276D03*
X417126D03*
X413977D03*
X426575Y156693D03*
X423425D03*
X420276D03*
X417126D03*
X413977D03*
X426575Y159842D03*
X423425D03*
X420276D03*
X417126D03*
X413977D03*
X426575Y162992D03*
X423425D03*
X420276D03*
X417126D03*
X413977D03*
X426575Y166141D03*
X423425D03*
X420276D03*
X417126D03*
X413977D03*
X426575Y169291D03*
X423425D03*
X420276D03*
X417126D03*
X413977D03*
X426575Y172441D03*
X423425D03*
X420276D03*
X417126D03*
X413977D03*
X426575Y175590D03*
X423425D03*
X420276D03*
X417126D03*
X413977D03*
X426575Y178740D03*
X423425D03*
X420276D03*
X417126D03*
X413977D03*
X426575Y181889D03*
X423425D03*
X420276D03*
X417126D03*
X413977D03*
X426575Y185039D03*
X423425D03*
X420276D03*
X417126D03*
X413977D03*
X426575Y188189D03*
X423425D03*
X420276D03*
X417126D03*
X413977D03*
X426575Y191338D03*
X423425D03*
X420276D03*
X417126D03*
X413977D03*
X426575Y194488D03*
X423425D03*
X420276D03*
X417126D03*
X413977D03*
X426575Y197637D03*
X423425D03*
X420276D03*
X417126D03*
X413977D03*
X426575Y200787D03*
X423425D03*
X420276D03*
X417126D03*
X413977D03*
X426575Y203937D03*
X423425D03*
X420276D03*
X417126D03*
X413977D03*
X426575Y207086D03*
X423425D03*
X420276D03*
X417126D03*
X413977D03*
X426575Y210236D03*
X423425D03*
X420276D03*
X417126D03*
X413977D03*
X426575Y213385D03*
X423425D03*
X420276D03*
X417126D03*
X413977D03*
X426575Y216535D03*
X423425D03*
X420276D03*
X417126D03*
X413977D03*
X426575Y219685D03*
X423425D03*
X420276D03*
X417126D03*
X413977D03*
X426575Y222834D03*
X423425D03*
X420276D03*
X417126D03*
X413977D03*
X439173Y131496D03*
X436024D03*
X432874D03*
X429725D03*
X439173Y134645D03*
X436024D03*
X432874D03*
X429725D03*
X439173Y137795D03*
X436024D03*
X432874D03*
X429725D03*
X442323Y140945D03*
X439173D03*
X436024D03*
X432874D03*
X429725D03*
X442323Y144094D03*
X439173D03*
X436024D03*
X432874D03*
X429725D03*
X442323Y147244D03*
X439173D03*
X436024D03*
X432874D03*
X429725D03*
X442323Y150393D03*
X439173D03*
X436024D03*
X432874D03*
X429725D03*
X442323Y153543D03*
X439173D03*
X436024D03*
X432874D03*
X429725D03*
X442323Y156693D03*
X439173D03*
X436024D03*
X432874D03*
X429725D03*
X442323Y159842D03*
X439173D03*
X436024D03*
X432874D03*
X429725D03*
X442323Y162992D03*
X439173D03*
X436024D03*
X432874D03*
X429725D03*
X442323Y166141D03*
X439173D03*
X436024D03*
X432874D03*
X429725D03*
X442323Y169291D03*
X439173D03*
X436024D03*
X432874D03*
X429725D03*
X442323Y172441D03*
X439173D03*
X436024D03*
X432874D03*
X429725D03*
X442323Y175590D03*
X439173D03*
X436024D03*
X432874D03*
X429725D03*
X442323Y178740D03*
X439173D03*
X436024D03*
X432874D03*
X429725D03*
X442323Y181889D03*
X439173D03*
X436024D03*
X432874D03*
X429725D03*
X442323Y185039D03*
X439173D03*
X436024D03*
X432874D03*
X429725D03*
X442323Y188189D03*
X439173D03*
X436024D03*
X432874D03*
X429725D03*
X442323Y191338D03*
X439173D03*
X436024D03*
X432874D03*
X429725D03*
X442323Y194488D03*
X439173D03*
X436024D03*
X432874D03*
X429725D03*
X442323Y197637D03*
X439173D03*
X436024D03*
X432874D03*
X429725D03*
X442323Y200787D03*
X439173D03*
X436024D03*
X432874D03*
X429725D03*
X442323Y203937D03*
X439173D03*
X436024D03*
X432874D03*
X429725D03*
X442323Y207086D03*
X439173D03*
X436024D03*
X432874D03*
X429725D03*
X442323Y210236D03*
X439173D03*
X436024D03*
X432874D03*
X429725D03*
X442323Y213385D03*
X439173D03*
X436024D03*
X432874D03*
X429725D03*
X439173Y216535D03*
X436024D03*
X432874D03*
X429725D03*
X439173Y219685D03*
X436024D03*
X432874D03*
X429725D03*
X439173Y222834D03*
X436024D03*
X432874D03*
X429725D03*
X448622Y140945D03*
X445473D03*
X448622Y144094D03*
X445473D03*
X448622Y147244D03*
X445473D03*
X448622Y150393D03*
X445473D03*
X448622Y153543D03*
X445473D03*
X448622Y156693D03*
X445473D03*
X448622Y159842D03*
X445473D03*
X448622Y162992D03*
X445473D03*
X448622Y166141D03*
X445473D03*
X448622Y169291D03*
X445473D03*
X448622Y172441D03*
X445473D03*
X448622Y175590D03*
X445473D03*
X448622Y178740D03*
X445473D03*
X448622Y181889D03*
X445473D03*
X448622Y185039D03*
X445473D03*
X448622Y188189D03*
X445473D03*
X448622Y191338D03*
X445473D03*
X448622Y194488D03*
X445473D03*
X448622Y197637D03*
X445473D03*
X448622Y200787D03*
X445473D03*
X448622Y203937D03*
X445473D03*
X448622Y207086D03*
X445473D03*
X448622Y210236D03*
X445473D03*
X448622Y213385D03*
X445473D03*
X1130846Y662363D03*
X1133996D03*
X1130846Y659213D03*
X1133996D03*
X1121397Y678111D03*
X1124547D03*
X1127696D03*
X1130846D03*
X1133996D03*
X1121397Y674961D03*
X1124547D03*
X1127696D03*
X1130846D03*
X1133996D03*
X1121397Y671812D03*
X1124547D03*
X1127696D03*
X1130846D03*
X1133996D03*
X1121397Y668662D03*
X1124547D03*
X1127696D03*
X1130846D03*
X1133996D03*
X1130846Y665512D03*
X1133996D03*
X1121397Y697008D03*
X1124547D03*
X1127696D03*
X1130846D03*
X1133996D03*
X1121397Y693859D03*
X1124547D03*
X1127696D03*
X1130846D03*
X1133996D03*
X1121397Y690709D03*
X1124547D03*
X1127696D03*
X1130846D03*
X1133996D03*
X1121397Y687560D03*
X1124547D03*
X1127696D03*
X1130846D03*
X1133996D03*
X1121397Y684410D03*
X1124547D03*
X1127696D03*
X1130846D03*
X1133996D03*
X1121397Y681260D03*
X1124547D03*
X1127696D03*
X1130846D03*
X1133996D03*
X1121397Y712756D03*
X1124547D03*
X1127696D03*
X1130846D03*
X1133996D03*
X1121397Y709607D03*
X1124547D03*
X1127696D03*
X1130846D03*
X1133996D03*
X1121397Y706457D03*
X1124547D03*
X1127696D03*
X1130846D03*
X1133996D03*
X1121397Y703308D03*
X1124547D03*
X1127696D03*
X1130846D03*
X1133996D03*
X1121397Y700158D03*
X1124547D03*
X1127696D03*
X1130846D03*
X1133996D03*
X1130846Y725355D03*
X1133996D03*
X1130846Y722205D03*
X1133996D03*
X1130846Y719056D03*
X1133996D03*
X1121397Y715906D03*
X1124547D03*
X1127696D03*
X1130846D03*
X1133996D03*
X1121646Y772186D03*
Y775335D03*
Y778485D03*
X1124796Y772186D03*
Y775335D03*
Y778485D03*
X1127945Y772186D03*
Y775335D03*
Y778485D03*
X1131095Y772186D03*
Y775335D03*
Y778485D03*
X1134244Y772186D03*
Y775335D03*
Y778485D03*
X1121646Y791083D03*
Y794233D03*
X1124796Y791083D03*
Y794233D03*
X1127945Y791083D03*
Y794233D03*
X1131095Y791083D03*
Y794233D03*
X1134244Y791083D03*
Y794233D03*
X1121646Y797382D03*
X1124796D03*
X1127945D03*
X1131095D03*
X1134244D03*
X1137145Y662363D03*
X1140295D03*
X1143444D03*
X1146594D03*
X1149744D03*
X1137145Y659213D03*
X1140295D03*
X1143444D03*
X1146594D03*
X1149744D03*
X1143444Y674961D03*
X1146594D03*
X1149744D03*
X1137145Y671812D03*
X1140295D03*
X1143444D03*
X1146594D03*
X1149744D03*
X1137145Y668662D03*
X1140295D03*
X1143444D03*
X1146594D03*
X1149744D03*
X1137145Y665512D03*
X1140295D03*
X1143444D03*
X1146594D03*
X1149744D03*
X1137145Y697008D03*
X1146594D03*
X1149744D03*
X1137145Y693859D03*
X1146594D03*
X1149744D03*
X1137145Y690709D03*
X1146594D03*
X1149744D03*
X1137145Y687560D03*
X1146594D03*
X1149744D03*
X1137145Y684410D03*
X1146594D03*
X1149744D03*
X1137145Y681260D03*
Y712756D03*
X1140295D03*
X1143444D03*
X1146594D03*
X1149744D03*
X1143444Y709607D03*
X1146594D03*
X1149744D03*
X1137145Y703308D03*
Y700158D03*
X1146594D03*
X1149744D03*
X1137145Y725355D03*
X1140295D03*
X1143444D03*
X1146594D03*
X1149744D03*
X1137145Y722205D03*
X1140295D03*
X1143444D03*
X1146594D03*
X1149744D03*
X1137145Y719056D03*
X1140295D03*
X1143444D03*
X1146594D03*
X1149744D03*
X1137145Y715906D03*
X1140295D03*
X1143444D03*
X1146594D03*
X1149744D03*
X1137394Y772186D03*
Y775335D03*
Y778485D03*
X1140544Y772186D03*
Y775335D03*
Y778485D03*
X1143693Y772186D03*
Y775335D03*
Y778485D03*
X1146843Y772186D03*
Y775335D03*
Y778485D03*
X1149992Y772186D03*
Y775335D03*
Y778485D03*
X1137394Y791083D03*
Y794233D03*
X1140544Y791083D03*
Y794233D03*
X1143693Y791083D03*
Y794233D03*
X1146843Y791083D03*
Y794233D03*
X1149992Y791083D03*
Y794233D03*
X1137394Y797382D03*
X1140544D03*
X1143693D03*
X1146843D03*
X1149992D03*
X1152893Y662363D03*
X1156043D03*
X1159192D03*
X1162342D03*
X1165492D03*
X1152893Y659213D03*
X1156043D03*
X1159192D03*
X1162342D03*
X1165492D03*
X1152893Y674961D03*
X1156043D03*
X1159192D03*
X1162342D03*
X1165492D03*
X1152893Y671812D03*
X1156043D03*
X1159192D03*
X1162342D03*
X1165492D03*
X1152893Y668662D03*
X1156043D03*
X1159192D03*
X1162342D03*
X1165492D03*
X1152893Y665512D03*
X1156043D03*
X1159192D03*
X1162342D03*
X1165492D03*
X1152893Y697008D03*
X1156043D03*
X1159192D03*
X1162342D03*
X1152893Y693859D03*
X1156043D03*
X1159192D03*
X1162342D03*
X1152893Y690709D03*
X1156043D03*
X1159192D03*
X1162342D03*
X1152893Y687560D03*
X1156043D03*
X1159192D03*
X1162342D03*
X1152893Y684410D03*
X1156043D03*
X1159192D03*
X1162342D03*
X1152893Y712756D03*
X1156043D03*
X1159192D03*
X1162342D03*
X1165492D03*
X1152893Y709607D03*
X1156043D03*
X1159192D03*
X1162342D03*
X1165492D03*
X1152893Y700158D03*
X1156043D03*
X1159192D03*
X1162342D03*
X1152893Y725355D03*
X1156043D03*
X1159192D03*
X1162342D03*
X1165492D03*
X1152893Y722205D03*
X1156043D03*
X1159192D03*
X1162342D03*
X1165492D03*
X1152893Y719056D03*
X1156043D03*
X1159192D03*
X1162342D03*
X1165492D03*
X1152893Y715906D03*
X1156043D03*
X1159192D03*
X1162342D03*
X1165492D03*
X1153142Y772186D03*
Y775335D03*
Y778485D03*
X1156292Y772186D03*
Y775335D03*
Y778485D03*
X1159441Y772186D03*
Y775335D03*
Y778485D03*
X1162591Y772186D03*
Y775335D03*
Y778485D03*
X1165740Y772186D03*
Y775335D03*
Y778485D03*
X1153142Y791083D03*
Y794233D03*
X1156292Y791083D03*
Y794233D03*
X1159441Y791083D03*
Y794233D03*
X1162591Y791083D03*
Y794233D03*
X1165740Y791083D03*
Y794233D03*
X1153142Y797382D03*
X1156292D03*
X1159441D03*
X1162591D03*
X1165740D03*
X1168641Y662363D03*
X1171791D03*
X1174940D03*
X1178090D03*
X1168641Y659213D03*
X1171791D03*
X1174940D03*
X1178090D03*
X1174940Y678111D03*
X1178090D03*
X1181240D03*
X1174940Y674961D03*
X1178090D03*
X1181240D03*
X1168641Y671812D03*
X1171791D03*
X1174940D03*
X1178090D03*
X1181240D03*
X1168641Y668662D03*
X1171791D03*
X1174940D03*
X1178090D03*
X1181240D03*
X1168641Y665512D03*
X1171791D03*
X1174940D03*
X1178090D03*
X1171791Y697008D03*
X1174940D03*
X1178090D03*
X1181240D03*
X1171791Y693859D03*
X1174940D03*
X1178090D03*
X1181240D03*
X1171791Y690709D03*
X1174940D03*
X1178090D03*
X1181240D03*
X1171791Y687560D03*
X1174940D03*
X1178090D03*
X1181240D03*
X1171791Y684410D03*
X1174940D03*
X1178090D03*
X1181240D03*
X1171791Y681260D03*
X1174940D03*
X1178090D03*
X1181240D03*
X1168641Y712756D03*
X1171791D03*
X1174940D03*
X1178090D03*
X1181240D03*
X1174940Y709607D03*
X1178090D03*
X1181240D03*
X1174940Y706457D03*
X1178090D03*
X1181240D03*
X1171791Y703308D03*
X1174940D03*
X1178090D03*
X1181240D03*
X1171791Y700158D03*
X1174940D03*
X1178090D03*
X1181240D03*
X1168641Y725355D03*
X1171791D03*
X1174940D03*
X1178090D03*
X1168641Y722205D03*
X1171791D03*
X1174940D03*
X1178090D03*
X1168641Y719056D03*
X1171791D03*
X1174940D03*
X1178090D03*
X1168641Y715906D03*
X1171791D03*
X1174940D03*
X1178090D03*
X1181240D03*
X1168890Y772186D03*
Y775335D03*
Y778485D03*
Y791083D03*
Y794233D03*
Y797382D03*
X1184389Y678111D03*
X1187539D03*
X1184389Y674961D03*
X1187539D03*
X1184389Y671812D03*
X1187539D03*
X1184389Y668662D03*
X1187539D03*
X1184389Y697008D03*
X1187539D03*
X1184389Y693859D03*
X1187539D03*
X1184389Y690709D03*
X1187539D03*
X1184389Y687560D03*
X1187539D03*
X1184389Y684410D03*
X1187539D03*
X1184389Y681260D03*
X1187539D03*
X1184389Y712756D03*
X1187539D03*
X1184389Y709607D03*
X1187539D03*
X1184389Y706457D03*
X1187539D03*
X1184389Y703308D03*
X1187539D03*
X1184389Y700158D03*
X1187539D03*
X1184389Y715906D03*
X1187539D03*
G54D99*
X373894Y7992D03*
X386264D03*
X421138D03*
X433508D03*
M02*
